(kicad_pcb (version 20221018) (generator pcbnew)

  (general
    (thickness 1.518)
  )

  (paper "A4")
  (title_block
    (title "Kria K26 Devboard")
    (date "2024-03-26")
    (rev "1.2.5")
    (comment 1 "www.antmicro.com")
    (comment 2 "Antmicro Ltd.")
  )

  (layers
    (0 "F.Cu" mixed)
    (1 "In1.Cu" power)
    (2 "In2.Cu" mixed)
    (3 "In3.Cu" power)
    (4 "In4.Cu" mixed)
    (5 "In5.Cu" power)
    (6 "In6.Cu" mixed)
    (31 "B.Cu" power)
    (32 "B.Adhes" user "B.Adhesive")
    (33 "F.Adhes" user "F.Adhesive")
    (34 "B.Paste" user)
    (35 "F.Paste" user)
    (36 "B.SilkS" user "B.Silkscreen")
    (37 "F.SilkS" user "F.Silkscreen")
    (38 "B.Mask" user)
    (39 "F.Mask" user)
    (40 "Dwgs.User" user "User.Drawings")
    (41 "Cmts.User" user "User.Comments")
    (42 "Eco1.User" user "User.Eco1")
    (43 "Eco2.User" user "User.Eco2")
    (44 "Edge.Cuts" user)
    (45 "Margin" user)
    (46 "B.CrtYd" user "B.Courtyard")
    (47 "F.CrtYd" user "F.Courtyard")
    (48 "B.Fab" user)
    (49 "F.Fab" user)
  )

  (setup
    (stackup
      (layer "F.SilkS" (type "Top Silk Screen") (color "White"))
      (layer "F.Paste" (type "Top Solder Paste"))
      (layer "F.Mask" (type "Top Solder Mask") (color "Black") (thickness 0.01))
      (layer "F.Cu" (type "copper") (thickness 0.035))
      (layer "dielectric 1" (type "prepreg") (thickness 0.12) (material "PR2116") (epsilon_r 4.3) (loss_tangent 0.014))
      (layer "In1.Cu" (type "copper") (thickness 0.018))
      (layer "dielectric 2" (type "core") (thickness 0.2) (material "IS400") (epsilon_r 3.9) (loss_tangent 0.022))
      (layer "In2.Cu" (type "copper") (thickness 0.018))
      (layer "dielectric 3" (type "prepreg") (thickness 0.12) (material "PR2116") (epsilon_r 4.3) (loss_tangent 0.014)
        addsublayer (thickness 0.12) (material "PR2116") (epsilon_r 4.3) (loss_tangent 0.014))
      (layer "In3.Cu" (type "copper") (thickness 0.018))
      (layer "dielectric 4" (type "core") (thickness 0.2) (material "IS400") (epsilon_r 3.9) (loss_tangent 0.022))
      (layer "In4.Cu" (type "copper") (thickness 0.018))
      (layer "dielectric 5" (type "prepreg") (thickness 0.12) (material "PR2116") (epsilon_r 4.3) (loss_tangent 0.014)
        addsublayer (thickness 0.12) (material "PR2116") (epsilon_r 4.3) (loss_tangent 0.014))
      (layer "In5.Cu" (type "copper") (thickness 0.018))
      (layer "dielectric 6" (type "core") (thickness 0.2) (material "IS400") (epsilon_r 3.9) (loss_tangent 0.022))
      (layer "In6.Cu" (type "copper") (thickness 0.018))
      (layer "dielectric 7" (type "prepreg") (thickness 0.12) (material "PR2116") (epsilon_r 4.3) (loss_tangent 0.014))
      (layer "B.Cu" (type "copper") (thickness 0.035))
      (layer "B.Mask" (type "Bottom Solder Mask") (color "Black") (thickness 0.01))
      (layer "B.Paste" (type "Bottom Solder Paste"))
      (layer "B.SilkS" (type "Bottom Silk Screen") (color "White"))
      (copper_finish "ENIG")
      (dielectric_constraints yes)
    )
    (pad_to_mask_clearance 0)
    (pad_to_paste_clearance_ratio -0.1)
    (aux_axis_origin 74 152)
    (pcbplotparams
      (layerselection 0x00010fc_ffffffff)
      (plot_on_all_layers_selection 0x0000000_00000000)
      (disableapertmacros false)
      (usegerberextensions false)
      (usegerberattributes true)
      (usegerberadvancedattributes true)
      (creategerberjobfile true)
      (dashed_line_dash_ratio 12.000000)
      (dashed_line_gap_ratio 3.000000)
      (svgprecision 6)
      (plotframeref false)
      (viasonmask false)
      (mode 1)
      (useauxorigin false)
      (hpglpennumber 1)
      (hpglpenspeed 20)
      (hpglpendiameter 15.000000)
      (dxfpolygonmode true)
      (dxfimperialunits true)
      (dxfusepcbnewfont true)
      (psnegative false)
      (psa4output false)
      (plotreference true)
      (plotvalue true)
      (plotinvisibletext false)
      (sketchpadsonfab false)
      (subtractmaskfromsilk false)
      (outputformat 1)
      (mirror false)
      (drillshape 1)
      (scaleselection 1)
      (outputdirectory "")
    )
  )

  (net 0 "")
  (net 1 "GND")
  (net 2 "/Xilinx K26 SOM/MODE0_C2M")
  (net 3 "/Xilinx K26 SOM/MODE1_C2M")
  (net 4 "/Xilinx K26 SOM/MODE2_C2M")
  (net 5 "/Xilinx K26 SOM/MODE3_C2M")
  (net 6 "/Xilinx K26 SOM/HDA20")
  (net 7 "Net-(D11-Pad1)")
  (net 8 "SOM_5V0")
  (net 9 "/Power Supply/PoE/VDD_POE_IN")
  (net 10 "/Power Supply/PoE/VSS_POE_IN")
  (net 11 "GNDD")
  (net 12 "/Power Supply/PoE/POE_ACTIVE")
  (net 13 "/Power Supply/PoE/POE_12V")
  (net 14 "/Power Supply/DC/DC conventers/DC_MAIN_BUS")
  (net 15 "PS_3V3")
  (net 16 "PS_2V5")
  (net 17 "PS_1V8")
  (net 18 "PS_1V2")
  (net 19 "PS_1V0")
  (net 20 "PL_3V3")
  (net 21 "PL_1V2")
  (net 22 "/Power Supply/DC Input/DC_IN")
  (net 23 "/Power Supply/VCCOEN_PS_M2C")
  (net 24 "/Power Supply/VCCOEN_PL_M2C")
  (net 25 "/Ethernet/MIO64")
  (net 26 "/Ethernet/MIO73")
  (net 27 "/Ethernet/MIO74")
  (net 28 "/Ethernet/MIO75")
  (net 29 "/Ethernet/MIO70")
  (net 30 "/Ethernet/MIO71")
  (net 31 "/Ethernet/MIO72")
  (net 32 "/Ethernet/MIO67")
  (net 33 "/Ethernet/MIO68")
  (net 34 "/Ethernet/MIO69")
  (net 35 "/Ethernet/MIO65")
  (net 36 "/Ethernet/MIO66")
  (net 37 "/USB/MIO61")
  (net 38 "/USB/MIO62")
  (net 39 "/USB/MIO63")
  (net 40 "/USB/MIO58")
  (net 41 "/USB/MIO59")
  (net 42 "/USB/MIO60")
  (net 43 "/USB/MIO55")
  (net 44 "/USB/MIO56")
  (net 45 "/USB/MIO57")
  (net 46 "/USB/MIO52")
  (net 47 "/USB/MIO53")
  (net 48 "/USB/MIO54")
  (net 49 "/Ethernet/MIO76")
  (net 50 "/Ethernet/MIO77")
  (net 51 "/Ethernet/LED2")
  (net 52 "/USB/GTR_DP2_C2M_C_P")
  (net 53 "/USB/GTR_DP2_C2M_C_N")
  (net 54 "/USB/USB2_PHY_N")
  (net 55 "/USB/USB2_PHY_P")
  (net 56 "/USB/GTR_DP2_C2M_P")
  (net 57 "/USB/GTR_DP2_C2M_N")
  (net 58 "/USB/GTR_DP2_M2C_P")
  (net 59 "/USB/GTR_DP2_M2C_N")
  (net 60 "/USB/USB1_TX_N")
  (net 61 "/USB/USB1_TX_P")
  (net 62 "/USB/USB2_TX_N")
  (net 63 "/USB/USB2_TX_P")
  (net 64 "/USB/USB1_VBUS")
  (net 65 "/USB/USB3_TX_N")
  (net 66 "/USB/USB3_TX_P")
  (net 67 "/USB/USB1_N")
  (net 68 "/USB/USB1_P")
  (net 69 "/USB/USB2_N")
  (net 70 "/USB/USB2_P")
  (net 71 "/USB/USB3_N")
  (net 72 "/USB/USB3_P")
  (net 73 "/USB/USB4_RX_N")
  (net 74 "/USB/USB4_RX_P")
  (net 75 "/USB/USB4_TX_N")
  (net 76 "/USB/USB4_TX_P")
  (net 77 "/USB/USB4_N")
  (net 78 "/USB/USB4_P")
  (net 79 "/USB/USB3_RX_N")
  (net 80 "/USB/USB3_RX_P")
  (net 81 "/USB/USB2_RX_N")
  (net 82 "/USB/USB2_RX_P")
  (net 83 "/USB/USB1_RX_N")
  (net 84 "/USB/USB1_RX_P")
  (net 85 "/USB/USB2_VBUS")
  (net 86 "/USB/USB3_VBUS")
  (net 87 "/USB/USB4_VBUS")
  (net 88 "/PCIE M2 key E /GTR_DP3_M2C_P")
  (net 89 "/PCIE M2 key E /GTR_DP3_M2C_C_P")
  (net 90 "/PCIE M2 key E /GTR_DP3_M2C_N")
  (net 91 "/PCIE M2 key E /GTR_DP3_M2C_C_N")
  (net 92 "/Display Port/GTR_DP1_M2C_P")
  (net 93 "/Display Port/GTR_DP1_M2C_C_P")
  (net 94 "/Display Port/GTR_DP1_M2C_N")
  (net 95 "/Display Port/GTR_DP1_M2C_C_N")
  (net 96 "/Display Port/DP_AUX_P")
  (net 97 "/Display Port/DP_AUX_C_P")
  (net 98 "/Display Port/DP_AUX_N")
  (net 99 "/Display Port/DP_AUX_C_N")
  (net 100 "/Display Port/GTR_DP0_M2C_P")
  (net 101 "/Display Port/GTR_DP0_M2C_C_P")
  (net 102 "/Display Port/GTR_DP0_M2C_N")
  (net 103 "/Display Port/GTR_DP0_M2C_C_N")
  (net 104 "/SD 3.0 card/VCCB")
  (net 105 "/Display Port/DP_HPD")
  (net 106 "/SD 3.0 card/MIO45")
  (net 107 "/Clock distribution/GTR_REFCLK3_C2M_P")
  (net 108 "/Clock distribution/GTR_REFCLK3_C2M_N")
  (net 109 "/SD 3.0 card/MIO39")
  (net 110 "/SD 3.0 card/MIO50")
  (net 111 "/Display Port/MIO29")
  (net 112 "/Display Port/MIO30")
  (net 113 "/SD 3.0 card/MIO47")
  (net 114 "/SD 3.0 card/MIO48")
  (net 115 "/SD 3.0 card/MIO49")
  (net 116 "/Display Port/MIO27")
  (net 117 "/Display Port/MIO28")
  (net 118 "/SD 3.0 card/MIO46")
  (net 119 "/PCIE M2 key E /GTR_DP3_C2M_P")
  (net 120 "/PCIE M2 key E /GTR_DP3_C2M_N")
  (net 121 "/Clock distribution/GTR_REFCLK3_N")
  (net 122 "/Clock distribution/GTR_REFCLK3_P")
  (net 123 "/SD 3.0 card/MIO51")
  (net 124 "/Display Port/DP_AUX_OUT")
  (net 125 "/Display Port/DP_OE")
  (net 126 "/Display Port/DP_AUX_IN")
  (net 127 "/Reset logic/MIO43")
  (net 128 "/Reset logic/MIO38")
  (net 129 "/Reset logic/HDA02")
  (net 130 "/Reset logic/MIO44")
  (net 131 "Net-(Q2-G)")
  (net 132 "/Debug and JTAG/USB_1V2")
  (net 133 "/Debug and JTAG/VCC_PD")
  (net 134 "/Debug and JTAG/VREGIN")
  (net 135 "/Debug and JTAG/VCC_USB")
  (net 136 "/Debug and JTAG/PD1_SVBUS")
  (net 137 "/Debug and JTAG/XIN")
  (net 138 "/Debug and JTAG/USB_3V3")
  (net 139 "/Debug and JTAG/XOUT")
  (net 140 "/Debug and JTAG/~{PS_SRST_C2M}")
  (net 141 "/Debug and JTAG/JTAG_TDI_C2M")
  (net 142 "/Debug and JTAG/JTAG_TDO_M2C")
  (net 143 "/Debug and JTAG/JTAG_TCK_C2M")
  (net 144 "/PMOD/HDA11")
  (net 145 "/Debug and JTAG/JTAG_TMS_C2M")
  (net 146 "/PMOD/HDA15")
  (net 147 "/PMOD/HDA16_CC")
  (net 148 "/PMOD/HDA17")
  (net 149 "/Debug and JTAG/MIO36")
  (net 150 "/Debug and JTAG/MIO37")
  (net 151 "/Debug and JTAG/~{PS_POR}")
  (net 152 "/PMOD/HDA18")
  (net 153 "/I2C /MIO24_I2C_SCK")
  (net 154 "Net-(U23-VDD_3V3)")
  (net 155 "/PMOD/HDA12")
  (net 156 "/PMOD/HDA13")
  (net 157 "/PMOD/HDA14")
  (net 158 "/Debug and JTAG/FTDI_EEPROM_WC")
  (net 159 "/Debug and JTAG/~{FTDI_LS_OE}")
  (net 160 "/Debug and JTAG/~{LS_OE}")
  (net 161 "/Reset logic/PS_RST")
  (net 162 "/I2C /I2C_SCK_3V3")
  (net 163 "/I2C /I2C_SDA_3V3")
  (net 164 "/Debug and JTAG/~{FTDI_PWREN}")
  (net 165 "/Debug and JTAG/FTDI_UARTB_RXD")
  (net 166 "/Debug and JTAG/FTDI_UARTB_TXD")
  (net 167 "/Debug and JTAG/~{FTDI_PS_SRST}")
  (net 168 "/Debug and JTAG/~{FTDI_PS_POR}")
  (net 169 "/Debug and JTAG/JTAG_VCCO_ON")
  (net 170 "/Debug and JTAG/FTDI_TMS")
  (net 171 "/Debug and JTAG/FTDI_TDO")
  (net 172 "/Debug and JTAG/FTDI_TDI")
  (net 173 "/Debug and JTAG/FTDI_TCK")
  (net 174 "/Reset logic/PL_RST")
  (net 175 "/Reset logic/~{USB_HUB_RESET}")
  (net 176 "/Ethernet/~{ETH_RESET}")
  (net 177 "/Reset logic/~{SD_CARD_RESET}")
  (net 178 "/Reset logic/~{USB_PHY_RESET}")
  (net 179 "/Clock distribution/GTR_REFCLK1_C2M_P")
  (net 180 "/Clock distribution/GTR_REFCLK1_C2M_N")
  (net 181 "/Clock distribution/GTR_REFCLK0_C2M_P")
  (net 182 "/Clock distribution/GTR_REFCLK0_C2M_N")
  (net 183 "/Clock distribution/GTR_REFCLK2_C2M_P")
  (net 184 "/Clock distribution/GTR_REFCLK2_C2M_N")
  (net 185 "/Clock distribution/PS_CLK_EN")
  (net 186 "/Debug and JTAG/~{EEPROM_WC}")
  (net 187 "/Debug and JTAG/PD_3V3")
  (net 188 "/Debug and JTAG/USBC_P")
  (net 189 "/Debug and JTAG/USBC_N")
  (net 190 "Net-(D18-Pad1)")
  (net 191 "Net-(D19-Pad1)")
  (net 192 "Net-(D20-Pad1)")
  (net 193 "/Camera interface/CCI1_I2C_SCL_3V3")
  (net 194 "/Camera interface/CCI1_I2C_SDA_3V3")
  (net 195 "/Camera interface/CCI0_I2C_SCL_3V3")
  (net 196 "/Camera interface/CCI0_I2C_SDA_3V3")
  (net 197 "/Camera interface/CAM1_VSYNC")
  (net 198 "/Camera interface/CAM0_RST")
  (net 199 "/Camera interface/CAM0_VSYNC")
  (net 200 "/Camera interface/HPA05_CC_P")
  (net 201 "/Camera interface/HPA05_CC_N")
  (net 202 "/Camera interface/HPA06_P")
  (net 203 "/Camera interface/HPA06_N")
  (net 204 "/Camera interface/HPA07_P")
  (net 205 "/Camera interface/HPA07_N")
  (net 206 "/Camera interface/HPA08_P")
  (net 207 "/Camera interface/HPA08_N")
  (net 208 "/Camera interface/HPA09_P")
  (net 209 "/Camera interface/HPA09_N")
  (net 210 "/Camera interface/HPA00_CC_P")
  (net 211 "/Camera interface/HPA00_CC_N")
  (net 212 "/Camera interface/HPA01_P")
  (net 213 "/Camera interface/HPA01_N")
  (net 214 "/Camera interface/HPA02_P")
  (net 215 "/Camera interface/HPA02_N")
  (net 216 "/Camera interface/HPA03_P")
  (net 217 "/Camera interface/HPA03_N")
  (net 218 "/Camera interface/HPA04_P")
  (net 219 "/Camera interface/HPA04_N")
  (net 220 "/Debug and JTAG/CONN_GND")
  (net 221 "/PCIE M2 key E /~{M2_PERST}")
  (net 222 "/Debug and JTAG/USBB_P")
  (net 223 "/Debug and JTAG/USBB_N")
  (net 224 "/Reset logic/MIO41")
  (net 225 "/Camera interface/HDA01")
  (net 226 "/Clock distribution/~{M2_CLKREQ}")
  (net 227 "/PCIE M2 key E /~{M2_PEWAKE}")
  (net 228 "/Power Supply/Supply ORing/PD_VBUS")
  (net 229 "/Debug and JTAG/PD_EN")
  (net 230 "/Debug and JTAG/EEDATA")
  (net 231 "/Debug and JTAG/EECLK")
  (net 232 "/Debug and JTAG/EECS")
  (net 233 "/Debug and JTAG/USB_P")
  (net 234 "/Debug and JTAG/USB_N")
  (net 235 "/Ethernet/POE_VC2")
  (net 236 "/Ethernet/POE_VC1")
  (net 237 "/Ethernet/POE_VC4")
  (net 238 "/Ethernet/POE_VC3")
  (net 239 "Net-(D14-Pad1)")
  (net 240 "Net-(D15-Pad1)")
  (net 241 "Net-(D16-Pad1)")
  (net 242 "Net-(D17-Pad1)")
  (net 243 "Net-(Q6-D)")
  (net 244 "Net-(FB1-Pad2)")
  (net 245 "Net-(FB2-Pad2)")
  (net 246 "Net-(U32-CT)")
  (net 247 "Net-(U31-CT)")
  (net 248 "Net-(U47-PVCC)")
  (net 249 "Net-(U48-PVCC)")
  (net 250 "Net-(U47-SS)")
  (net 251 "Net-(U48-SS)")
  (net 252 "Net-(U47-BOOT)")
  (net 253 "Net-(U48-BOOT)")
  (net 254 "Net-(U47-FB)")
  (net 255 "Net-(U48-FB)")
  (net 256 "/Power Supply/DC/DC conventers/SW_PS_1V0")
  (net 257 "Net-(U49-BST)")
  (net 258 "Net-(U50-BST)")
  (net 259 "/SD 3.0 card/SD_DAT1")
  (net 260 "/SD 3.0 card/SD_DAT0")
  (net 261 "/SD 3.0 card/SD_CLK")
  (net 262 "/SD 3.0 card/SD_CMD")
  (net 263 "/SD 3.0 card/SD_DAT3")
  (net 264 "/SD 3.0 card/SD_DAT2")
  (net 265 "/Debug and JTAG/USBC_VBUS")
  (net 266 "/Debug and JTAG/USBB_VBUS")
  (net 267 "/Ethernet/TD_A_P")
  (net 268 "/Ethernet/TD_A_N")
  (net 269 "/Ethernet/TD_B_P")
  (net 270 "/Ethernet/TD_B_N")
  (net 271 "/Ethernet/TD_C_P")
  (net 272 "/Ethernet/TD_C_N")
  (net 273 "/Ethernet/TD_D_P")
  (net 274 "/Ethernet/TD_D_N")
  (net 275 "/USB/VBUS")
  (net 276 "Net-(U51-BST)")
  (net 277 "/USB/USB2_REFCLK")
  (net 278 "/USB/USB1_TX_C_N")
  (net 279 "/USB/USB1_TX_C_P")
  (net 280 "/USB/USB2_TX_C_N")
  (net 281 "/USB/USB2_TX_C_P")
  (net 282 "/USB/USB3_TX_C_N")
  (net 283 "/USB/USB3_TX_C_P")
  (net 284 "/USB/USB4_TX_C_N")
  (net 285 "/USB/USB4_TX_C_P")
  (net 286 "/USB/USB1_TVS_N")
  (net 287 "/USB/USB1_TVS_P")
  (net 288 "/USB/USB2_TVS_N")
  (net 289 "/USB/USB2_TVS_P")
  (net 290 "/USB/USB3_TVS_N")
  (net 291 "/USB/USB3_TVS_P")
  (net 292 "/USB/USB4_TVS_N")
  (net 293 "/USB/USB4_TVS_P")
  (net 294 "/USB/CLK_IN")
  (net 295 "/Ethernet/X_I")
  (net 296 "/Clock distribution/CLK_100M_P")
  (net 297 "/Clock distribution/CLK_100M_N")
  (net 298 "/Power Supply/USB-C socket/USBC_TVS_N")
  (net 299 "/Power Supply/USB-C socket/USBC_TVS_P")
  (net 300 "/Power Supply/USB-C socket/USBC_TVS_CC2")
  (net 301 "/Power Supply/USB-C socket/USBC_TVS_CC1")
  (net 302 "/USB/USB_PRT_CTL1")
  (net 303 "/USB/USB_PRT_CTL2")
  (net 304 "/USB/USB_PRT_CTL3")
  (net 305 "/USB/USB_PRT_CTL4")
  (net 306 "USB_5V")
  (net 307 "/Debug and JTAG/USBC_CC1")
  (net 308 "/Debug and JTAG/USBC_CC2")
  (net 309 "/Power Supply/DC/DC conventers/SW_PS_3V3")
  (net 310 "/Power Supply/DC/DC conventers/SW_PS_2V5")
  (net 311 "/Power Supply/DC/DC conventers/SW_PS_1V8")
  (net 312 "/Power Supply/DC/DC conventers/SW_PS_1V2")
  (net 313 "/Debug and JTAG/USB_VBUS")
  (net 314 "Net-(U52-BST)")
  (net 315 "/Power Supply/DC/DC conventers/SW_PL_3V3")
  (net 316 "/Power Supply/DC/DC conventers/SW_PL_1V2")
  (net 317 "/SD 3.0 card/SD_VDD")
  (net 318 "SH_DOWN")
  (net 319 "SH_UP")
  (net 320 "/USB/GTR_DP2_M2C_C_P")
  (net 321 "/USB/GTR_DP2_M2C_C_N")
  (net 322 "PL_1V8")
  (net 323 "Net-(U53-BST)")
  (net 324 "/I2C /Vref2")
  (net 325 "Net-(U54-BST)")
  (net 326 "Net-(U55-BST)")
  (net 327 "Net-(D4-PadK)")
  (net 328 "Net-(U58-VDD)")
  (net 329 "Net-(D12-Pad1)")
  (net 330 "Net-(D13-Pad1)")
  (net 331 "Net-(U58-GND)")
  (net 332 "Net-(J5-P4)")
  (net 333 "Net-(J5-P5)")
  (net 334 "Net-(J1-DP_PWR)")
  (net 335 "Net-(U32-MR_N)")
  (net 336 "Net-(U31-MR_N)")
  (net 337 "Net-(Q18-C)")
  (net 338 "Net-(Q13-C)")
  (net 339 "Net-(Q14-C)")
  (net 340 "Net-(Q15-C)")
  (net 341 "Net-(IC1-DEN)")
  (net 342 "Net-(IC1-CLS)")
  (net 343 "unconnected-(IC1-T2P-Pad7)")
  (net 344 "unconnected-(J1-TXD2+-Pad7)")
  (net 345 "unconnected-(J1-TXD2--Pad9)")
  (net 346 "unconnected-(J1-TXD3+-Pad10)")
  (net 347 "unconnected-(J1-TXD3--Pad12)")
  (net 348 "Net-(J1-CFG1)")
  (net 349 "Net-(J1-CFG2)")
  (net 350 "Net-(J5-LED_GRN+)")
  (net 351 "Net-(J5-LED_GRN-)")
  (net 352 "Net-(J5-LED_YEL+)")
  (net 353 "Net-(J5-LED_YEL-)")
  (net 354 "Net-(J8-CC_{1})")
  (net 355 "Net-(J8-D_{A}+)")
  (net 356 "Net-(J8-D_{A}-)")
  (net 357 "unconnected-(J8-SBU_{1}-PadA8)")
  (net 358 "Net-(J8-CC_{2})")
  (net 359 "unconnected-(J8-SBU_{2}-PadB8)")
  (net 360 "/PCIE M2 key E /M2_USB_N")
  (net 361 "/PCIE M2 key E /M2_USB_P")
  (net 362 "/Display Port/DP_AUX_C_TVS_P")
  (net 363 "/Display Port/DP_AUX_C_TVS_N")
  (net 364 "/Ethernet/LED0")
  (net 365 "/Power Supply/DC/DC conventers/SW_USB_5V")
  (net 366 "/Power Supply/DC/DC conventers/SW_SOM_5V")
  (net 367 "unconnected-(J10-SBU_{1}-PadA8)")
  (net 368 "unconnected-(J10-SBU_{2}-PadB8)")
  (net 369 "unconnected-(J12-~{LED_1}-Pad6)")
  (net 370 "unconnected-(J12-PCM_CLK-Pad8)")
  (net 371 "unconnected-(J12-SDIO_CLK-Pad9)")
  (net 372 "unconnected-(J12-PCM_SYNC-Pad10)")
  (net 373 "unconnected-(J12-SDIO_CMD-Pad11)")
  (net 374 "unconnected-(J12-PCM_OUT-Pad12)")
  (net 375 "unconnected-(J12-SDIO_D0-Pad13)")
  (net 376 "unconnected-(J12-PCM_IN-Pad14)")
  (net 377 "unconnected-(J12-SDIO_D1-Pad15)")
  (net 378 "unconnected-(J12-~{LED_2}-Pad16)")
  (net 379 "unconnected-(J12-SDIO_D2-Pad17)")
  (net 380 "Net-(R3-Pad2)")
  (net 381 "unconnected-(J12-SDIO_D3-Pad19)")
  (net 382 "unconnected-(J12-~{UART_WAKE}-Pad20)")
  (net 383 "unconnected-(J12-SDIO_~{WAKE}-Pad21)")
  (net 384 "unconnected-(J12-UART_TXD-Pad22)")
  (net 385 "unconnected-(J12-SDIO_~{RESET}-Pad23)")
  (net 386 "unconnected-(J12-UART_RXD-Pad32)")
  (net 387 "unconnected-(J12-UART_RTS-Pad34)")
  (net 388 "unconnected-(J12-UART_CTS-Pad36)")
  (net 389 "unconnected-(J12-VENDOR_1-Pad38)")
  (net 390 "unconnected-(J12-VENDOR_2-Pad40)")
  (net 391 "unconnected-(J12-VENDOR_3-Pad42)")
  (net 392 "unconnected-(J12-COEX3-Pad44)")
  (net 393 "unconnected-(J12-COEX_TXD-Pad46)")
  (net 394 "unconnected-(J12-COEX_RXD-Pad48)")
  (net 395 "unconnected-(J12-SUSCLK-Pad50)")
  (net 396 "Net-(J12-~{CLKREQ0})")
  (net 397 "unconnected-(J12-W_DISABLE2-Pad54)")
  (net 398 "unconnected-(J12-W_DISABLE1-Pad56)")
  (net 399 "unconnected-(J12-I2C_DATA-Pad58)")
  (net 400 "unconnected-(J12-PET1+-Pad59)")
  (net 401 "unconnected-(J12-I2C_CLK-Pad60)")
  (net 402 "unconnected-(J12-PET1--Pad61)")
  (net 403 "unconnected-(J12-~{ALERT}-Pad62)")
  (net 404 "unconnected-(J12-RFU-Pad64)")
  (net 405 "unconnected-(J12-PER1+-Pad65)")
  (net 406 "unconnected-(J12-UIM_SWP-Pad66)")
  (net 407 "unconnected-(J12-PER1--Pad67)")
  (net 408 "unconnected-(J12-UIM_POWER_SNK-Pad68)")
  (net 409 "/Xilinx K26 SOM/MIO31_SHUTDOWN")
  (net 410 "/Camera interface/HDA00_CC")
  (net 411 "unconnected-(J12-UIM_POWER_SRC-Pad70)")
  (net 412 "unconnected-(J12-REFCLK1+-Pad71)")
  (net 413 "unconnected-(J12-REFCLK1--Pad73)")
  (net 414 "unconnected-(PS1-TRIM-Pad5)")
  (net 415 "Net-(Q1-D)")
  (net 416 "unconnected-(J3-Pad13)")
  (net 417 "unconnected-(J3-Pad14)")
  (net 418 "unconnected-(J3-Pad16)")
  (net 419 "unconnected-(J3-Pad17)")
  (net 420 "unconnected-(J3-Pad31)")
  (net 421 "unconnected-(J3-Pad35)")
  (net 422 "unconnected-(J3-Pad36)")
  (net 423 "unconnected-(J3-Pad37)")
  (net 424 "unconnected-(J3-Pad38)")
  (net 425 "unconnected-(J3-Pad43)")
  (net 426 "unconnected-(J3-Pad44)")
  (net 427 "unconnected-(J3-Pad45)")
  (net 428 "unconnected-(J3-Pad46)")
  (net 429 "Net-(Q3-C)")
  (net 430 "Net-(Q6-G)")
  (net 431 "Net-(Q19-C)")
  (net 432 "/I2C /MIO25_I2C_SDA")
  (net 433 "Net-(Q16-G)")
  (net 434 "unconnected-(J9-Pad12)")
  (net 435 "Net-(U5-CMD_{A})")
  (net 436 "Net-(U5-CLK_{A})")
  (net 437 "unconnected-(J11-Pad2)")
  (net 438 "/Xilinx K26 SOM/VCC_BATT")
  (net 439 "/Xilinx K26 SOM/HPA06_CLK0_P")
  (net 440 "/Xilinx K26 SOM/HPA06_CLK0_N")
  (net 441 "/Xilinx K26 SOM/HPA12_P")
  (net 442 "/Xilinx K26 SOM/HPA12_N")
  (net 443 "/Xilinx K26 SOM/HPA13_P")
  (net 444 "/Xilinx K26 SOM/HPA13_N")
  (net 445 "/Xilinx K26 SOM/HDA10")
  (net 446 "unconnected-(J_SOM240_1-PadA31)")
  (net 447 "unconnected-(J_SOM240_1-PadA32)")
  (net 448 "/Xilinx K26 SOM/MIO42")
  (net 449 "/Xilinx K26 SOM/GTR_DP0_C2M_P")
  (net 450 "/Xilinx K26 SOM/GTR_DP0_C2M_N")
  (net 451 "/Xilinx K26 SOM/HPA11_P")
  (net 452 "/Xilinx K26 SOM/HPA11_N")
  (net 453 "/Xilinx K26 SOM/HDA03")
  (net 454 "/Xilinx K26 SOM/HDA05")
  (net 455 "/Xilinx K26 SOM/PS_ERROR_OUT_M2C")
  (net 456 "/Xilinx K26 SOM/PS_ERROR_STATUS_M2C")
  (net 457 "/Xilinx K26 SOM/PWROFF_C2M_L")
  (net 458 "/Xilinx K26 SOM/MIO35_WD_OUT")
  (net 459 "/Xilinx K26 SOM/MIO40")
  (net 460 "unconnected-(J_SOM240_1-PadB38)")
  (net 461 "/Xilinx K26 SOM/HPA10_CC_P")
  (net 462 "/Xilinx K26 SOM/HPA10_CC_N")
  (net 463 "/Xilinx K26 SOM/HDA06")
  (net 464 "/Xilinx K26 SOM/HDA07")
  (net 465 "/Xilinx K26 SOM/HDA08_CC")
  (net 466 "/Xilinx K26 SOM/HDA19")
  (net 467 "/Xilinx K26 SOM/MIO12_FWUEN_C2M_L")
  (net 468 "unconnected-(J_SOM240_1-PadC45)")
  (net 469 "/Xilinx K26 SOM/GTR_DP1_C2M_P")
  (net 470 "/Xilinx K26 SOM/GTR_DP1_C2M_N")
  (net 471 "/Xilinx K26 SOM/HPA14_P")
  (net 472 "/Xilinx K26 SOM/HPA14_N")
  (net 473 "/Xilinx K26 SOM/PWRGD_FPD_M2C")
  (net 474 "/Xilinx K26 SOM/PWRGD_LPD_M2C")
  (net 475 "/Xilinx K26 SOM/PWR_GD_PL_M2C")
  (net 476 "/Xilinx K26 SOM/MIO26")
  (net 477 "unconnected-(J_SOM240_1-PadD46)")
  (net 478 "/Xilinx K26 SOM/GTH_DP3_M2C_P")
  (net 479 "/Xilinx K26 SOM/GTH_DP3_M2C_N")
  (net 480 "/Xilinx K26 SOM/GTH_REFCLK1_C2M_P")
  (net 481 "/Xilinx K26 SOM/GTH_REFCLK1_C2M_N")
  (net 482 "/Xilinx K26 SOM/HPB15_CC_P")
  (net 483 "/Xilinx K26 SOM/HPB_15_CC_N")
  (net 484 "/Xilinx K26 SOM/HPB08_P")
  (net 485 "/Xilinx K26 SOM/HPB08_N")
  (net 486 "/Xilinx K26 SOM/HPB12_P")
  (net 487 "/Xilinx K26 SOM/HPB12_N")
  (net 488 "/Xilinx K26 SOM/HPB06_P")
  (net 489 "/Xilinx K26 SOM/HPB06_N")
  (net 490 "/Xilinx K26 SOM/HPB16_P")
  (net 491 "/Xilinx K26 SOM/HPB16_N")
  (net 492 "/Xilinx K26 SOM/HPB19_P")
  (net 493 "/Xilinx K26 SOM/HPB19_N")
  (net 494 "/Xilinx K26 SOM/HPC08_P")
  (net 495 "/Xilinx K26 SOM/HPC08_N")
  (net 496 "/Xilinx K26 SOM/HPC19_P")
  (net 497 "/Xilinx K26 SOM/HPC19_N")
  (net 498 "/Xilinx K26 SOM/HPC14_P")
  (net 499 "/Xilinx K26 SOM/HPC14_N")
  (net 500 "/Xilinx K26 SOM/HPC15_CC_P")
  (net 501 "/Xilinx K26 SOM/HPC15_CC_N")
  (net 502 "/Xilinx K26 SOM/HPC03_P")
  (net 503 "/Xilinx K26 SOM/HPC03_N")
  (net 504 "/Xilinx K26 SOM/VCCO_HPB_1")
  (net 505 "/Xilinx K26 SOM/HDB18")
  (net 506 "/Xilinx K26 SOM/HDB19")
  (net 507 "/Xilinx K26 SOM/HDB20")
  (net 508 "/Xilinx K26 SOM/HDB21")
  (net 509 "/Xilinx K26 SOM/HDB22")
  (net 510 "/Xilinx K26 SOM/HDB23")
  (net 511 "/Xilinx K26 SOM/HDC18")
  (net 512 "/Xilinx K26 SOM/HDC19")
  (net 513 "/Xilinx K26 SOM/HDC20")
  (net 514 "/Xilinx K26 SOM/HDC21")
  (net 515 "/Xilinx K26 SOM/HDC22")
  (net 516 "/Xilinx K26 SOM/HDC23")
  (net 517 "/Xilinx K26 SOM/GTH_DP2_C2M_P")
  (net 518 "/Xilinx K26 SOM/GTH_DP2_C2M_N")
  (net 519 "/Xilinx K26 SOM/GTH_DP2_M2C_P")
  (net 520 "/Xilinx K26 SOM/GTH_DP2_M2C_N")
  (net 521 "/Xilinx K26 SOM/GTH_DP0_C2M_P")
  (net 522 "/Xilinx K26 SOM/GTH_DP0_C2M_N")
  (net 523 "/Xilinx K26 SOM/HPB10_CC_P")
  (net 524 "/Xilinx K26 SOM/HPB10_CC_N")
  (net 525 "/Xilinx K26 SOM/HPB07_P")
  (net 526 "/Xilinx K26 SOM/HPB07_N")
  (net 527 "/Xilinx K26 SOM/HPB05_CC_P")
  (net 528 "/Xilinx K26 SOM/HPB05_CC_N")
  (net 529 "/Xilinx K26 SOM/HPB11_P")
  (net 530 "/Xilinx K26 SOM/HPB11_N")
  (net 531 "/Xilinx K26 SOM/HPB03_P")
  (net 532 "/Xilinx K26 SOM/HPB03_N")
  (net 533 "/Xilinx K26 SOM/HPC06_P")
  (net 534 "/Xilinx K26 SOM/HPC06_N")
  (net 535 "/Xilinx K26 SOM/HPC13_P")
  (net 536 "/Xilinx K26 SOM/HPC13_N")
  (net 537 "/Xilinx K26 SOM/HPC16_P")
  (net 538 "/Xilinx K26 SOM/HPC16_N")
  (net 539 "/Xilinx K26 SOM/HPC07_P")
  (net 540 "/Xilinx K26 SOM/HPC07_N")
  (net 541 "/Xilinx K26 SOM/HPC18_P")
  (net 542 "/Xilinx K26 SOM/HPC18_N")
  (net 543 "/Xilinx K26 SOM/VCCO_HPB_2")
  (net 544 "/Xilinx K26 SOM/HDB12")
  (net 545 "/Xilinx K26 SOM/HDB13")
  (net 546 "/Xilinx K26 SOM/HDB14")
  (net 547 "/Xilinx K26 SOM/HDB15")
  (net 548 "/Xilinx K26 SOM/HDB16_CC")
  (net 549 "/Xilinx K26 SOM/HDB17")
  (net 550 "/Xilinx K26 SOM/HDC12")
  (net 551 "/Xilinx K26 SOM/HDC13")
  (net 552 "/Xilinx K26 SOM/HDC14")
  (net 553 "/Xilinx K26 SOM/HDC15")
  (net 554 "/Xilinx K26 SOM/HDC16_CC")
  (net 555 "/Xilinx K26 SOM/HDC17")
  (net 556 "/Xilinx K26 SOM/VCCO_HDB_1")
  (net 557 "/Xilinx K26 SOM/VCCO_HDB_2")
  (net 558 "/Xilinx K26 SOM/GTH_REFCLK0_C2M_P")
  (net 559 "/Xilinx K26 SOM/GTH_REFCLK0_C2M_N")
  (net 560 "/Xilinx K26 SOM/GTH_DP1_M2C_P")
  (net 561 "/Xilinx K26 SOM/GTH_DP1_M2C_N")
  (net 562 "/Xilinx K26 SOM/HPB09_P")
  (net 563 "/Xilinx K26 SOM/HPB09_N")
  (net 564 "/Xilinx K26 SOM/HPB14_P")
  (net 565 "/Xilinx K26 SOM/HPB14_N")
  (net 566 "/Xilinx K26 SOM/HPB02_P")
  (net 567 "/Xilinx K26 SOM/HPB02_N")
  (net 568 "/Xilinx K26 SOM/HPB13_P")
  (net 569 "/Xilinx K26 SOM/HPB13_N")
  (net 570 "/Xilinx K26 SOM/HPB_18_P")
  (net 571 "/Xilinx K26 SOM/HPB_18_N")
  (net 572 "/Xilinx K26 SOM/HPC17_P")
  (net 573 "/Xilinx K26 SOM/HPC17_N")
  (net 574 "/Xilinx K26 SOM/HPC10_CC_P")
  (net 575 "/Xilinx K26 SOM/HPC10_CC_N")
  (net 576 "/Xilinx K26 SOM/HPC11_P")
  (net 577 "/Xilinx K26 SOM/HPC11_N")
  (net 578 "/Xilinx K26 SOM/HPC12_P")
  (net 579 "/Xilinx K26 SOM/HPC12_N")
  (net 580 "/Xilinx K26 SOM/HPC05_CC_P")
  (net 581 "/Xilinx K26 SOM/HPC05_CC_N")
  (net 582 "/Xilinx K26 SOM/HPC_CLK0_P")
  (net 583 "/Xilinx K26 SOM/HPC_CLK0_N")
  (net 584 "/Xilinx K26 SOM/VCCO_HPC_1")
  (net 585 "/Xilinx K26 SOM/HDB06")
  (net 586 "/Xilinx K26 SOM/HDB07")
  (net 587 "/Xilinx K26 SOM/HDB08_CC")
  (net 588 "/Xilinx K26 SOM/HDB09")
  (net 589 "/Xilinx K26 SOM/HDB10")
  (net 590 "/Xilinx K26 SOM/HDB11")
  (net 591 "/Xilinx K26 SOM/HDC06")
  (net 592 "/Xilinx K26 SOM/HDC07")
  (net 593 "/Xilinx K26 SOM/HDC08_CC")
  (net 594 "/Xilinx K26 SOM/HDC09")
  (net 595 "/Xilinx K26 SOM/HDC10")
  (net 596 "/Xilinx K26 SOM/HDC11")
  (net 597 "/Xilinx K26 SOM/GTH_DP1_C2M_P")
  (net 598 "/Xilinx K26 SOM/GTH_DP1_C2M_N")
  (net 599 "/Xilinx K26 SOM/GTH_DP3_C2M_P")
  (net 600 "/Xilinx K26 SOM/GTH_DP3_C2M_N")
  (net 601 "/Xilinx K26 SOM/GTH_DP0_M2C_P")
  (net 602 "/Xilinx K26 SOM/GTH_DP0_M2C_N")
  (net 603 "/Xilinx K26 SOM/HPB01_P")
  (net 604 "/Xilinx K26 SOM/HPB01_N")
  (net 605 "/Xilinx K26 SOM/HPB00_CC_P")
  (net 606 "/Xilinx K26 SOM/HPB00_CC_N")
  (net 607 "/Xilinx K26 SOM/HPB_CLK0_P")
  (net 608 "/Xilinx K26 SOM/HPB_CLK0_N")
  (net 609 "/Xilinx K26 SOM/HPB04_P")
  (net 610 "/Xilinx K26 SOM/HPB04_N")
  (net 611 "/Xilinx K26 SOM/HPB17_P")
  (net 612 "/Xilinx K26 SOM/HPB17_N")
  (net 613 "/Xilinx K26 SOM/HPC09_P")
  (net 614 "/Xilinx K26 SOM/HPC09_N")
  (net 615 "/Xilinx K26 SOM/HPC01_P")
  (net 616 "/Xilinx K26 SOM/HPC01_N")
  (net 617 "/Xilinx K26 SOM/HPC00_CC_P")
  (net 618 "/Xilinx K26 SOM/HPC00_CC_N")
  (net 619 "/Xilinx K26 SOM/HPC02_P")
  (net 620 "/Xilinx K26 SOM/HPC02_N")
  (net 621 "/Xilinx K26 SOM/HPC04_P")
  (net 622 "/Xilinx K26 SOM/HPC04_N")
  (net 623 "/Xilinx K26 SOM/VCCO_HPC_2")
  (net 624 "/Xilinx K26 SOM/HDB00_CC")
  (net 625 "/Xilinx K26 SOM/HDB01")
  (net 626 "/Xilinx K26 SOM/HDB02")
  (net 627 "/Xilinx K26 SOM/HDB03")
  (net 628 "/Xilinx K26 SOM/HDB04")
  (net 629 "/Xilinx K26 SOM/HDB05")
  (net 630 "/Xilinx K26 SOM/HDC00_CC")
  (net 631 "/Xilinx K26 SOM/HDC01")
  (net 632 "/Xilinx K26 SOM/HDC02")
  (net 633 "/Xilinx K26 SOM/HDC03")
  (net 634 "/Xilinx K26 SOM/HDC04")
  (net 635 "/Xilinx K26 SOM/HDC05")
  (net 636 "/Xilinx K26 SOM/VCCO_HDC_1")
  (net 637 "/Xilinx K26 SOM/VCCO_HDC_2")
  (net 638 "Net-(R15-R4.2)")
  (net 639 "Net-(R15-R3.2)")
  (net 640 "Net-(R15-R2.2)")
  (net 641 "Net-(R15-R1.2)")
  (net 642 "Net-(U7-I_{REF})")
  (net 643 "Net-(U17-SPI_CLK{slash}PF21)")
  (net 644 "Net-(U17-SPI_CE_N{slash}CFG_NON_REM{slash}PF20)")
  (net 645 "Net-(U17-SPI_D0{slash}CFG_BC_EN{slash}PF22)")
  (net 646 "Net-(U17-SPI_D1{slash}PF23)")
  (net 647 "Net-(U17-SPI_D2{slash}PF24)")
  (net 648 "Net-(U17-SPI_D3{slash}PF25)")
  (net 649 "Net-(U17-TEST1)")
  (net 650 "Net-(U17-TEST2)")
  (net 651 "Net-(U17-TEST3)")
  (net 652 "Net-(U17-CFG_STRAP1)")
  (net 653 "Net-(U17-CFG_STRAP2)")
  (net 654 "Net-(U17-CFG_STRAP3)")
  (net 655 "Net-(U17-RBIAS)")
  (net 656 "Net-(U17-PF3)")
  (net 657 "Net-(U17-PF4)")
  (net 658 "Net-(U17-PF5)")
  (net 659 "Net-(U17-PF6)")
  (net 660 "Net-(U17-PF7)")
  (net 661 "Net-(U17-PF8)")
  (net 662 "Net-(U17-PF9)")
  (net 663 "Net-(U17-PF30)")
  (net 664 "Net-(U17-PF31)")
  (net 665 "Net-(U17-DP1_CC1)")
  (net 666 "Net-(U17-PF26)")
  (net 667 "Net-(U17-PF27)")
  (net 668 "Net-(U23-RBIAS)")
  (net 669 "Net-(U23-VBUS)")
  (net 670 "Net-(U30-INT_PWDN)")
  (net 671 "Net-(U30-RBIAS)")
  (net 672 "Net-(U30-JTAG_TDI)")
  (net 673 "Net-(U30-JTAG_CLK)")
  (net 674 "Net-(U30-JTAG_TMS)")
  (net 675 "Net-(U33-1A1)")
  (net 676 "Net-(U34-A_{1})")
  (net 677 "Net-(U33-1A2)")
  (net 678 "Net-(U33-2A1)")
  (net 679 "Net-(U33-2A2)")
  (net 680 "Net-(U40-REF)")
  (net 681 "Net-(U40-~{RESET})")
  (net 682 "Net-(U39-DO)")
  (net 683 "Net-(U44-B_{1})")
  (net 684 "Net-(U44-B_{2})")
  (net 685 "Net-(U47-EN)")
  (net 686 "Net-(U48-EN)")
  (net 687 "Net-(U50-EN)")
  (net 688 "Net-(U49-FB)")
  (net 689 "Net-(U50-FB)")
  (net 690 "Net-(U51-FB)")
  (net 691 "Net-(U52-FB)")
  (net 692 "Net-(U53-FB)")
  (net 693 "Net-(U54-FB)")
  (net 694 "Net-(U55-FB)")
  (net 695 "Net-(U6-ST)")
  (net 696 "Net-(U17-DP1_CC2)")
  (net 697 "Net-(U17-DP1_VBUS_MON)")
  (net 698 "Net-(U8-IN)")
  (net 699 "Net-(U40-CDBUS0)")
  (net 700 "Net-(U40-CDBUS1)")
  (net 701 "unconnected-(U2-NC-Pad3)")
  (net 702 "unconnected-(U2-NC-Pad5)")
  (net 703 "unconnected-(U2-NC-Pad6)")
  (net 704 "unconnected-(U2-NC-Pad13)")
  (net 705 "unconnected-(U5-CLK_{FB}-Pad6)")
  (net 706 "unconnected-(U8-NC-Pad3)")
  (net 707 "unconnected-(U8-NC-Pad5)")
  (net 708 "unconnected-(U8-NC-Pad6)")
  (net 709 "unconnected-(U9-NC-Pad2)")
  (net 710 "unconnected-(U17-USB3DN_TXDP1B-Pad16)")
  (net 711 "unconnected-(U17-USB3DN_TXDM1B-Pad17)")
  (net 712 "unconnected-(U17-USB3DN_RXDP1B-Pad19)")
  (net 713 "unconnected-(U17-USB3DN_RXDM1B-Pad20)")
  (net 714 "unconnected-(U17-PF10-Pad51)")
  (net 715 "unconnected-(U17-PF11-Pad52)")
  (net 716 "unconnected-(U17-PF12-Pad54)")
  (net 717 "unconnected-(U17-PF16-Pad59)")
  (net 718 "unconnected-(U17-PF18-Pad61)")
  (net 719 "unconnected-(U17-PF19-Pad66)")
  (net 720 "unconnected-(U17-PF29-Pad74)")
  (net 721 "unconnected-(U17-PF28-Pad77)")
  (net 722 "unconnected-(U17-ATEST-Pad96)")
  (net 723 "unconnected-(U17-XTALO-Pad97)")
  (net 724 "unconnected-(U30-VDDA1P8-Pad13)")
  (net 725 "unconnected-(U30-X_O-Pad14)")
  (net 726 "unconnected-(U30-CLK_OUT-Pad18)")
  (net 727 "unconnected-(U30-JTAG_TDO-Pad21)")
  (net 728 "unconnected-(U30-GPIO_0-Pad39)")
  (net 729 "unconnected-(U30-GPIO_1-Pad40)")
  (net 730 "unconnected-(U30-LED_1-Pad46)")
  (net 731 "unconnected-(U30-VDDA1P8-Pad48)")
  (net 732 "unconnected-(U34-A_{2}-Pad9)")
  (net 733 "unconnected-(U36G-DAP-Pad15)")
  (net 734 "unconnected-(U38-NC-Pad2)")
  (net 735 "unconnected-(U38-PG-Pad5)")
  (net 736 "unconnected-(U39-ORG-Pad6)")
  (net 737 "unconnected-(U39-NC-Pad7)")
  (net 738 "unconnected-(U40-GPIO3-Pad5)")
  (net 739 "unconnected-(U40-BDBUS2-Pad19)")
  (net 740 "unconnected-(U40-BDBUS3-Pad20)")
  (net 741 "unconnected-(U40-BDBUS4-Pad21)")
  (net 742 "unconnected-(U40-BDBUS5-Pad22)")
  (net 743 "unconnected-(U40-BDBUS6-Pad23)")
  (net 744 "unconnected-(U40-BDBUS7-Pad24)")
  (net 745 "unconnected-(U40-F_{SOURCE}-Pad32)")
  (net 746 "unconnected-(U40-V_{PP}-Pad33)")
  (net 747 "unconnected-(U40-CDBUS2-Pad36)")
  (net 748 "unconnected-(U40-CDBUS3-Pad37)")
  (net 749 "unconnected-(U40-CDBUS4-Pad38)")
  (net 750 "unconnected-(U40-CDBUS5-Pad40)")
  (net 751 "unconnected-(U40-CDBUS6-Pad41)")
  (net 752 "unconnected-(U40-CDBUS7-Pad42)")
  (net 753 "unconnected-(U40-~{SUSPEND}-Pad43)")
  (net 754 "unconnected-(U40-DDBUS0-Pad45)")
  (net 755 "unconnected-(U40-DDBUS2-Pad47)")
  (net 756 "unconnected-(U59-Pad5)")
  (net 757 "unconnected-(U60-Pad5)")
  (net 758 "unconnected-(U40-DDBUS3-Pad48)")
  (net 759 "unconnected-(U40-DDBUS4-Pad49)")
  (net 760 "unconnected-(U40-DDBUS5-Pad50)")
  (net 761 "unconnected-(U40-DDBUS6-Pad52)")
  (net 762 "unconnected-(U40-DDBUS7-Pad53)")
  (net 763 "unconnected-(U37-Pad5)")
  (net 764 "unconnected-(U40-GPIO1-Pad55)")
  (net 765 "/Power Supply/DC/DC conventers/PS_3V3_OUT")
  (net 766 "/Power Supply/DC/DC conventers/PS_2V5_OUT")
  (net 767 "/Power Supply/DC/DC conventers/PS_1V8_OUT")
  (net 768 "/Power Supply/DC/DC conventers/PS_1V2_OUT")
  (net 769 "/Power Supply/DC/DC conventers/PS_1V0_OUT")
  (net 770 "/Power Supply/DC/DC conventers/PL_3V3_OUT")
  (net 771 "/Power Supply/DC/DC conventers/PL_1V2_OUT")
  (net 772 "/Power Supply/DC/DC conventers/USB_5V_OUT")
  (net 773 "/Power Supply/DC/DC conventers/SOM_5V_OUT")
  (net 774 "/Power Supply/DC/DC conventers/SOM_5V_FB")
  (net 775 "unconnected-(U40-GPIO0-Pad56)")
  (net 776 "unconnected-(U42-2B2-Pad12)")
  (net 777 "unconnected-(U43-1A2-Pad7)")
  (net 778 "unconnected-(U43-2A2-Pad9)")
  (net 779 "unconnected-(U47-NC-Pad4)")
  (net 780 "unconnected-(U47-NC-Pad7)")
  (net 781 "unconnected-(U47-PG-Pad8)")
  (net 782 "unconnected-(U48-NC-Pad4)")
  (net 783 "unconnected-(U48-NC-Pad7)")
  (net 784 "unconnected-(U48-PG-Pad8)")
  (net 785 "unconnected-(U56-GATE-Pad5)")
  (net 786 "unconnected-(U56-NC-Pad6)")
  (net 787 "unconnected-(U56-NC-Pad10)")
  (net 788 "unconnected-(U57-GATE-Pad5)")
  (net 789 "unconnected-(U57-NC-Pad6)")
  (net 790 "unconnected-(U57-NC-Pad10)")
  (net 791 "unconnected-(U58-GATE-Pad5)")
  (net 792 "unconnected-(U58-NC-Pad6)")
  (net 793 "unconnected-(U58-NC-Pad10)")
  (net 794 "unconnected-(U61-NC-Pad2)")
  (net 795 "unconnected-(U61-PG-Pad5)")
  (net 796 "unconnected-(Y1-NC-Pad2)")
  (net 797 "unconnected-(Y3-NC-Pad2)")
  (net 798 "unconnected-(Y4-EN-Pad1)")
  (net 799 "unconnected-(J7-PadMP)")
  (net 800 "unconnected-(U36-Pad12)")
  (net 801 "unconnected-(U36-Pad13)")
  (net 802 "unconnected-(Y5-EN-Pad1)")
  (net 803 "unconnected-(Y6-EN-Pad1)")
  (net 804 "Net-(J1-RTN)")

  (footprint "kria-k26-devboard-footprints:SOD-964" (layer "F.Cu")
    (at 167 141.9 90)
    (property "Author" "Antmicro")
    (property "License" "Apache-2.0")
    (property "MPN" "PTVS5V0Z1USKPYL")
    (property "Manufacturer" "Nexperia")
    (property "Sheetfile" "pmod.kicad_sch")
    (property "Sheetname" "PMOD")
    (property "ki_description" "Transient voltage suppressor in DSN1608-2 for mobile applications")
    (property "ki_keywords" "Transient voltage suppressor in DSN1608-2 for mobile applications")
    (attr smd)
    (fp_text reference "D2" (at -1.332967 4.472678 90) (layer "F.SilkS")
        (effects (font (size 0.7 0.7) (thickness 0.15)) (justify left bottom))
    )
    (fp_text value "PTVS5V0Z1USKP" (at 0 1.399 90) (layer "F.Fab") hide
        (effects (font (size 0.7 0.7) (thickness 0.15)) (justify left bottom))
    )
    (fp_text user "License: Apache-2.0" (at -1 5.799 90) (layer "F.Fab") hide
        (effects (font (size 0.7 0.7) (thickness 0.15)) (justify left bottom))
    )
    (fp_text user "${REFERENCE}" (at -1 3.399 90) (layer "F.Fab") hide
        (effects (font (size 0.7 0.7) (thickness 0.15)) (justify left bottom))
    )
    (fp_text user "Author: Antmicro" (at -1 4.599 90) (layer "F.Fab") hide
        (effects (font (size 0.7 0.7) (thickness 0.15)) (justify left bottom))
    )
    (fp_line (start -0.85 -0.451) (end -0.85 0.45)
      (stroke (width 0.15) (type solid)) (layer "F.SilkS"))
    (fp_line (start -0.85 -0.451) (end 0.149 -0.451)
      (stroke (width 0.15) (type solid)) (layer "F.SilkS"))
    (fp_line (start 0.149 0.45) (end -0.85 0.45)
      (stroke (width 0.15) (type solid)) (layer "F.SilkS"))
    (fp_line (start -1 -0.6) (end 0.99 -0.6)
      (stroke (width 0.05) (type solid)) (layer "F.CrtYd"))
    (fp_line (start -1 0.59) (end -1 -0.6)
      (stroke (width 0.05) (type solid)) (layer "F.CrtYd"))
    (fp_line (start 0.99 -0.6) (end 0.99 0.59)
      (stroke (width 0.05) (type solid)) (layer "F.CrtYd"))
    (fp_line (start 0.99 0.59) (end -1 0.59)
      (stroke (width 0.05) (type solid)) (layer "F.CrtYd"))
    (fp_line (start -0.651 -0.425) (end 0.65 -0.425)
      (stroke (width 0.15) (type solid)) (layer "F.Fab"))
    (fp_line (start -0.651 0.424) (end -0.651 -0.425)
      (stroke (width 0.15) (type solid)) (layer "F.Fab"))
    (fp_line (start -0.651 0.424) (end 0.65 0.424)
      (stroke (width 0.15) (type solid)) (layer "F.Fab"))
    (fp_line (start -0.451 -0.401) (end -0.451 0.4)
      (stroke (width 0.15) (type solid)) (layer "F.Fab"))
    (fp_line (start 0.65 -0.425) (end 0.65 0.424)
      (stroke (width 0.15) (type solid)) (layer "F.Fab"))
    (pad "A" smd roundrect (at 0.599 0 90) (size 0.3 0.7) (layers "F.Cu" "F.Paste" "F.Mask") (roundrect_rratio 0.25)
      (net 1 "GND") (pinfunction "A") (pintype "passive"))
    (pad "K" smd roundrect (at -0.285 0 90) (size 0.93 0.7) (layers "F.Cu" "F.Paste" "F.Mask") (roundrect_rratio 0.107)
      (net 20 "PL_3V3") (pinfunction "K") (pintype "passive"))
  )

  (footprint "kria-k26-devboard-footprints:C_0402_1005Metric" (layer "F.Cu")
    (at 133.015 136.5)
    (descr "Capacitor SMD 0402")
    (tags "capacitor SMD 0402")
    (property "Author" "Antmicro")
    (property "Dielectric" "X5R")
    (property "License" "Apache-2.0")
    (property "MPN" "GRM155R61H104KE14D")
    (property "Manufacturer" "Murata")
    (property "Sheetfile" "sd-3-card.kicad_sch")
    (property "Sheetname" "SD 3.0 card")
    (property "Val" "100n")
    (property "Voltage" "50V")
    (property "ki_description" " ")
    (attr smd)
    (fp_text reference "C14" (at -1.225 -1.57) (layer "F.SilkS")
        (effects (font (size 0.7 0.7) (thickness 0.15)) (justify left bottom))
    )
    (fp_text value "C_100n_0402" (at 0 1.4) (layer "F.Fab") hide
        (effects (font (size 0.7 0.7) (thickness 0.15)) (justify left bottom))
    )
    (fp_text user "${REFERENCE}" (at -0.932 3.168) (layer "F.Fab") hide
        (effects (font (size 0.7 0.7) (thickness 0.15)) (justify left bottom))
    )
    (fp_text user "License: Apache-2.0" (at -0.932 5.17) (layer "F.Fab") hide
        (effects (font (size 0.7 0.7) (thickness 0.15)) (justify left bottom))
    )
    (fp_text user "Author: Antmicro" (at -0.932 4.17) (layer "F.Fab") hide
        (effects (font (size 0.7 0.7) (thickness 0.15)) (justify left bottom))
    )
    (fp_rect (start -0.9659 -0.481258) (end 0.9649 0.458742)
      (stroke (width 0.05) (type solid)) (fill none) (layer "F.CrtYd"))
    (fp_line (start -0.499 -0.25) (end 0.499 -0.25)
      (stroke (width 0.15) (type solid)) (layer "F.Fab"))
    (fp_line (start -0.499 0.248) (end -0.499 -0.25)
      (stroke (width 0.15) (type solid)) (layer "F.Fab"))
    (fp_line (start 0.499 -0.25) (end 0.499 0.248)
      (stroke (width 0.15) (type solid)) (layer "F.Fab"))
    (fp_line (start 0.499 0.248) (end -0.499 0.248)
      (stroke (width 0.15) (type solid)) (layer "F.Fab"))
    (pad "1" smd roundrect (at -0.484 0) (size 0.59 0.64) (layers "F.Cu" "F.Paste" "F.Mask") (roundrect_rratio 0.25)
      (net 17 "PS_1V8") (pintype "passive"))
    (pad "2" smd roundrect (at 0.484 0) (size 0.59 0.64) (layers "F.Cu" "F.Paste" "F.Mask") (roundrect_rratio 0.25)
      (net 1 "GND") (pintype "passive"))
  )

  (footprint "kria-k26-devboard-footprints:C_0402_1005Metric" (layer "F.Cu")
    (at 133.005 137.5)
    (descr "Capacitor SMD 0402")
    (tags "capacitor SMD 0402")
    (property "Author" "Antmicro")
    (property "Dielectric" "X5R")
    (property "License" "Apache-2.0")
    (property "MPN" "GRM155R61H104KE14D")
    (property "Manufacturer" "Murata")
    (property "Sheetfile" "sd-3-card.kicad_sch")
    (property "Sheetname" "SD 3.0 card")
    (property "Val" "100n")
    (property "Voltage" "50V")
    (property "ki_description" " ")
    (attr smd)
    (fp_text reference "C16" (at -1.225 -1.57) (layer "F.SilkS")
        (effects (font (size 0.7 0.7) (thickness 0.15)) (justify left bottom))
    )
    (fp_text value "C_100n_0402" (at 0 1.4) (layer "F.Fab") hide
        (effects (font (size 0.7 0.7) (thickness 0.15)) (justify left bottom))
    )
    (fp_text user "License: Apache-2.0" (at -0.932 5.17) (layer "F.Fab") hide
        (effects (font (size 0.7 0.7) (thickness 0.15)) (justify left bottom))
    )
    (fp_text user "${REFERENCE}" (at -0.932 3.168) (layer "F.Fab") hide
        (effects (font (size 0.7 0.7) (thickness 0.15)) (justify left bottom))
    )
    (fp_text user "Author: Antmicro" (at -0.932 4.17) (layer "F.Fab") hide
        (effects (font (size 0.7 0.7) (thickness 0.15)) (justify left bottom))
    )
    (fp_rect (start -0.94 -0.47) (end 0.94 0.47)
      (stroke (width 0.05) (type solid)) (fill none) (layer "F.CrtYd"))
    (fp_rect (start -0.499 -0.249) (end 0.499 0.249)
      (stroke (width 0.15) (type solid)) (fill none) (layer "F.Fab"))
    (pad "1" smd roundrect (at -0.484 0) (size 0.59 0.64) (layers "F.Cu" "F.Paste" "F.Mask") (roundrect_rratio 0.25)
      (net 104 "/SD 3.0 card/VCCB") (pintype "passive"))
    (pad "2" smd roundrect (at 0.484 0) (size 0.59 0.64) (layers "F.Cu" "F.Paste" "F.Mask") (roundrect_rratio 0.25)
      (net 1 "GND") (pintype "passive"))
  )

  (footprint "kria-k26-devboard-footprints:C_0402_1005Metric" (layer "F.Cu")
    (at 110.91 95.98 -90)
    (descr "Capacitor SMD 0402")
    (tags "capacitor SMD 0402")
    (property "Author" "Antmicro")
    (property "Dielectric" "X5R")
    (property "License" "Apache-2.0")
    (property "MPN" "GRM155R61H104KE14D")
    (property "Manufacturer" "Murata")
    (property "Sheetfile" "clock.kicad_sch")
    (property "Sheetname" "Clock distribution")
    (property "Val" "100n")
    (property "Voltage" "50V")
    (property "ki_description" " ")
    (attr smd)
    (fp_text reference "C22" (at -0.83 -0.35 -90) (layer "F.SilkS")
        (effects (font (size 0.7 0.7) (thickness 0.15)) (justify left bottom))
    )
    (fp_text value "C_100n_0402" (at 0 1.4 -90) (layer "F.Fab") hide
        (effects (font (size 0.7 0.7) (thickness 0.15)) (justify left bottom))
    )
    (fp_text user "Author: Antmicro" (at -0.932 4.17 -90) (layer "F.Fab") hide
        (effects (font (size 0.7 0.7) (thickness 0.15)) (justify left bottom))
    )
    (fp_text user "License: Apache-2.0" (at -0.932 5.17 -90) (layer "F.Fab") hide
        (effects (font (size 0.7 0.7) (thickness 0.15)) (justify left bottom))
    )
    (fp_text user "${REFERENCE}" (at -0.932 3.168 -90) (layer "F.Fab") hide
        (effects (font (size 0.7 0.7) (thickness 0.15)) (justify left bottom))
    )
    (fp_rect (start -0.94 -0.47) (end 0.94 0.47)
      (stroke (width 0.05) (type solid)) (fill none) (layer "F.CrtYd"))
    (fp_rect (start -0.499 -0.249) (end 0.499 0.249)
      (stroke (width 0.15) (type solid)) (fill none) (layer "F.Fab"))
    (pad "1" smd roundrect (at -0.484 0 270) (size 0.59 0.64) (layers "F.Cu" "F.Paste" "F.Mask") (roundrect_rratio 0.25)
      (net 15 "PS_3V3") (pintype "passive"))
    (pad "2" smd roundrect (at 0.484 0 270) (size 0.59 0.64) (layers "F.Cu" "F.Paste" "F.Mask") (roundrect_rratio 0.25)
      (net 1 "GND") (pintype "passive"))
  )

  (footprint "kria-k26-devboard-footprints:C_0402_1005Metric" (layer "F.Cu")
    (at 112.12 96.98 90)
    (descr "Capacitor SMD 0402")
    (tags "capacitor SMD 0402")
    (property "Author" "Antmicro")
    (property "Dielectric" "X5R")
    (property "License" "Apache-2.0")
    (property "MPN" "GRM155R61H104KE14D")
    (property "Manufacturer" "Murata")
    (property "Sheetfile" "clock.kicad_sch")
    (property "Sheetname" "Clock distribution")
    (property "Val" "100n")
    (property "Voltage" "50V")
    (property "ki_description" " ")
    (attr smd)
    (fp_text reference "C25" (at 0.93 0.36 90) (layer "F.SilkS")
        (effects (font (size 0.7 0.7) (thickness 0.15)) (justify left bottom))
    )
    (fp_text value "C_100n_0402" (at 0 1.4 90) (layer "F.Fab") hide
        (effects (font (size 0.7 0.7) (thickness 0.15)) (justify left bottom))
    )
    (fp_text user "License: Apache-2.0" (at -0.932 5.17 90) (layer "F.Fab") hide
        (effects (font (size 0.7 0.7) (thickness 0.15)) (justify left bottom))
    )
    (fp_text user "Author: Antmicro" (at -0.932 4.17 90) (layer "F.Fab") hide
        (effects (font (size 0.7 0.7) (thickness 0.15)) (justify left bottom))
    )
    (fp_text user "${REFERENCE}" (at -0.932 3.168 90) (layer "F.Fab") hide
        (effects (font (size 0.7 0.7) (thickness 0.15)) (justify left bottom))
    )
    (fp_rect (start -0.94 -0.47) (end 0.94 0.47)
      (stroke (width 0.05) (type solid)) (fill none) (layer "F.CrtYd"))
    (fp_rect (start -0.499 -0.249) (end 0.499 0.249)
      (stroke (width 0.15) (type solid)) (fill none) (layer "F.Fab"))
    (pad "1" smd roundrect (at -0.484 0 90) (size 0.59 0.64) (layers "F.Cu" "F.Paste" "F.Mask") (roundrect_rratio 0.25)
      (net 15 "PS_3V3") (pintype "passive"))
    (pad "2" smd roundrect (at 0.484 0 90) (size 0.59 0.64) (layers "F.Cu" "F.Paste" "F.Mask") (roundrect_rratio 0.25)
      (net 1 "GND") (pintype "passive"))
  )

  (footprint "kria-k26-devboard-footprints:C_0402_1005Metric" (layer "F.Cu")
    (at 190.7 66.1 -90)
    (descr "Capacitor SMD 0402")
    (tags "capacitor SMD 0402")
    (property "Author" "Antmicro")
    (property "Dielectric" "X5R")
    (property "License" "Apache-2.0")
    (property "MPN" "GRM155R61H104KE14D")
    (property "Manufacturer" "Murata")
    (property "Sheetfile" "supply-oring.kicad_sch")
    (property "Sheetname" "Supply ORing")
    (property "Val" "100n")
    (property "Voltage" "50V")
    (property "ki_description" " ")
    (attr smd)
    (fp_text reference "C227" (at 1.37 -1.15 -90) (layer "F.SilkS")
        (effects (font (size 0.7 0.7) (thickness 0.15)) (justify left bottom))
    )
    (fp_text value "C_100n_0402" (at 0 1.4 -90) (layer "F.Fab") hide
        (effects (font (size 0.7 0.7) (thickness 0.15)) (justify left bottom))
    )
    (fp_text user "License: Apache-2.0" (at -0.932 5.17 -90) (layer "F.Fab") hide
        (effects (font (size 0.7 0.7) (thickness 0.15)) (justify left bottom))
    )
    (fp_text user "Author: Antmicro" (at -0.932 4.17 -90) (layer "F.Fab") hide
        (effects (font (size 0.7 0.7) (thickness 0.15)) (justify left bottom))
    )
    (fp_text user "${REFERENCE}" (at -0.932 3.168 -90) (layer "F.Fab") hide
        (effects (font (size 0.7 0.7) (thickness 0.15)) (justify left bottom))
    )
    (fp_rect (start -0.94 -0.47) (end 0.94 0.47)
      (stroke (width 0.05) (type solid)) (fill none) (layer "F.CrtYd"))
    (fp_rect (start -0.499 -0.249) (end 0.499 0.249)
      (stroke (width 0.15) (type solid)) (fill none) (layer "F.Fab"))
    (pad "1" smd roundrect (at -0.484 0 270) (size 0.59 0.64) (layers "F.Cu" "F.Paste" "F.Mask") (roundrect_rratio 0.25)
      (net 328 "Net-(U58-VDD)") (pintype "passive"))
    (pad "2" smd roundrect (at 0.484 0 270) (size 0.59 0.64) (layers "F.Cu" "F.Paste" "F.Mask") (roundrect_rratio 0.25)
      (net 331 "Net-(U58-GND)") (pintype "passive"))
  )

  (footprint "kria-k26-devboard-footprints:C_0402_1005Metric" (layer "F.Cu")
    (at 135.145 136.4 90)
    (descr "Capacitor SMD 0402")
    (tags "capacitor SMD 0402")
    (property "Author" "Antmicro")
    (property "Dielectric" "X5R")
    (property "License" "Apache-2.0")
    (property "MPN" "GRM155R61H104KE14D")
    (property "Manufacturer" "Murata")
    (property "Sheetfile" "sd-3-card.kicad_sch")
    (property "Sheetname" "SD 3.0 card")
    (property "Val" "100n")
    (property "Voltage" "50V")
    (property "ki_description" " ")
    (attr smd)
    (fp_text reference "C12" (at 0.86 0.345 90) (layer "F.SilkS")
        (effects (font (size 0.7 0.7) (thickness 0.15)) (justify left bottom))
    )
    (fp_text value "C_100n_0402" (at 0 1.4 90) (layer "F.Fab") hide
        (effects (font (size 0.7 0.7) (thickness 0.15)) (justify left bottom))
    )
    (fp_text user "${REFERENCE}" (at -0.932 3.168 90) (layer "F.Fab") hide
        (effects (font (size 0.7 0.7) (thickness 0.15)) (justify left bottom))
    )
    (fp_text user "License: Apache-2.0" (at -0.932 5.17 90) (layer "F.Fab") hide
        (effects (font (size 0.7 0.7) (thickness 0.15)) (justify left bottom))
    )
    (fp_text user "Author: Antmicro" (at -0.932 4.17 90) (layer "F.Fab") hide
        (effects (font (size 0.7 0.7) (thickness 0.15)) (justify left bottom))
    )
    (fp_rect (start -0.94 -0.47) (end 0.94 0.47)
      (stroke (width 0.05) (type solid)) (fill none) (layer "F.CrtYd"))
    (fp_rect (start -0.499 -0.249) (end 0.499 0.249)
      (stroke (width 0.15) (type solid)) (fill none) (layer "F.Fab"))
    (pad "1" smd roundrect (at -0.484 0 90) (size 0.59 0.64) (layers "F.Cu" "F.Paste" "F.Mask") (roundrect_rratio 0.25)
      (net 15 "PS_3V3") (pintype "passive"))
    (pad "2" smd roundrect (at 0.484 0 90) (size 0.59 0.64) (layers "F.Cu" "F.Paste" "F.Mask") (roundrect_rratio 0.25)
      (net 1 "GND") (pintype "passive"))
  )

  (footprint "kria-k26-devboard-footprints:C_0402_1005Metric" (layer "F.Cu")
    (at 137.7 138)
    (descr "Capacitor SMD 0402")
    (tags "capacitor SMD 0402")
    (property "Author" "Antmicro")
    (property "Dielectric" "X5R")
    (property "License" "Apache-2.0")
    (property "MPN" "GRM155R61H104KE14D")
    (property "Manufacturer" "Murata")
    (property "Sheetfile" "sd-3-card.kicad_sch")
    (property "Sheetname" "SD 3.0 card")
    (property "Val" "100n")
    (property "Voltage" "50V")
    (property "ki_description" " ")
    (attr smd)
    (fp_text reference "C15" (at -0.74 1.16) (layer "F.SilkS")
        (effects (font (size 0.7 0.7) (thickness 0.15)) (justify left bottom))
    )
    (fp_text value "C_100n_0402" (at 0 1.4) (layer "F.Fab") hide
        (effects (font (size 0.7 0.7) (thickness 0.15)) (justify left bottom))
    )
    (fp_text user "Author: Antmicro" (at -0.932 4.17) (layer "F.Fab") hide
        (effects (font (size 0.7 0.7) (thickness 0.15)) (justify left bottom))
    )
    (fp_text user "${REFERENCE}" (at -0.932 3.168) (layer "F.Fab") hide
        (effects (font (size 0.7 0.7) (thickness 0.15)) (justify left bottom))
    )
    (fp_text user "License: Apache-2.0" (at -0.932 5.17) (layer "F.Fab") hide
        (effects (font (size 0.7 0.7) (thickness 0.15)) (justify left bottom))
    )
    (fp_rect (start -0.94 -0.47) (end 0.94 0.47)
      (stroke (width 0.05) (type solid)) (fill none) (layer "F.CrtYd"))
    (fp_rect (start -0.499 -0.249) (end 0.499 0.249)
      (stroke (width 0.15) (type solid)) (fill none) (layer "F.Fab"))
    (pad "1" smd roundrect (at -0.484 0) (size 0.59 0.64) (layers "F.Cu" "F.Paste" "F.Mask") (roundrect_rratio 0.25)
      (net 104 "/SD 3.0 card/VCCB") (pintype "passive"))
    (pad "2" smd roundrect (at 0.484 0) (size 0.59 0.64) (layers "F.Cu" "F.Paste" "F.Mask") (roundrect_rratio 0.25)
      (net 1 "GND") (pintype "passive"))
  )

  (footprint "kria-k26-devboard-footprints:C_0402_1005Metric" (layer "F.Cu")
    (at 143.215 108.3 180)
    (descr "Capacitor SMD 0402")
    (tags "capacitor SMD 0402")
    (property "Author" "Antmicro")
    (property "Dielectric" "X5R")
    (property "License" "Apache-2.0")
    (property "MPN" "GRM155R61H104KE14D")
    (property "Manufacturer" "Murata")
    (property "Sheetfile" "debug.kicad_sch")
    (property "Sheetname" "Debug and JTAG")
    (property "Val" "100n")
    (property "Voltage" "50V")
    (property "ki_description" " ")
    (attr smd)
    (fp_text reference "C160" (at 1.745 1.48 180) (layer "F.SilkS")
        (effects (font (size 0.7 0.7) (thickness 0.15)) (justify left bottom))
    )
    (fp_text value "C_100n_0402" (at 0 1.4 180) (layer "F.Fab") hide
        (effects (font (size 0.7 0.7) (thickness 0.15)) (justify left bottom))
    )
    (fp_text user "License: Apache-2.0" (at -0.932 5.17 180) (layer "F.Fab") hide
        (effects (font (size 0.7 0.7) (thickness 0.15)) (justify left bottom))
    )
    (fp_text user "${REFERENCE}" (at -0.932 3.168 180) (layer "F.Fab") hide
        (effects (font (size 0.7 0.7) (thickness 0.15)) (justify left bottom))
    )
    (fp_text user "Author: Antmicro" (at -0.932 4.17 180) (layer "F.Fab") hide
        (effects (font (size 0.7 0.7) (thickness 0.15)) (justify left bottom))
    )
    (fp_rect (start -0.94 -0.47) (end 0.94 0.47)
      (stroke (width 0.05) (type solid)) (fill none) (layer "F.CrtYd"))
    (fp_rect (start -0.499 -0.249) (end 0.499 0.249)
      (stroke (width 0.15) (type solid)) (fill none) (layer "F.Fab"))
    (pad "1" smd roundrect (at -0.484 0 180) (size 0.59 0.64) (layers "F.Cu" "F.Paste" "F.Mask") (roundrect_rratio 0.25)
      (net 136 "/Debug and JTAG/PD1_SVBUS") (pintype "passive"))
    (pad "2" smd roundrect (at 0.484 0 180) (size 0.59 0.64) (layers "F.Cu" "F.Paste" "F.Mask") (roundrect_rratio 0.25)
      (net 1 "GND") (pintype "passive"))
  )

  (footprint "kria-k26-devboard-footprints:C_0402_1005Metric" (layer "F.Cu")
    (at 165.907322 141.878033 90)
    (descr "Capacitor SMD 0402")
    (tags "capacitor SMD 0402")
    (property "Author" "Antmicro")
    (property "Dielectric" "")
    (property "License" "Apache-2.0")
    (property "MPN" "C1005X6S1A105K050BC")
    (property "Manufacturer" "TDK")
    (property "Sheetfile" "pmod.kicad_sch")
    (property "Sheetname" "PMOD")
    (property "Val" "1u")
    (property "Voltage" "")
    (property "ki_description" " ")
    (attr smd)
    (fp_text reference "C36" (at -1.331967 4.522678 90) (layer "F.SilkS")
        (effects (font (size 0.7 0.7) (thickness 0.15)) (justify left bottom))
    )
    (fp_text value "C_1u_0402" (at 0 1.4 90) (layer "F.Fab") hide
        (effects (font (size 0.7 0.7) (thickness 0.15)) (justify left bottom))
    )
    (fp_text user "License: Apache-2.0" (at -0.932 5.17 90) (layer "F.Fab") hide
        (effects (font (size 0.7 0.7) (thickness 0.15)) (justify left bottom))
    )
    (fp_text user "${REFERENCE}" (at -0.932 3.168 90) (layer "F.Fab") hide
        (effects (font (size 0.7 0.7) (thickness 0.15)) (justify left bottom))
    )
    (fp_text user "Author: Antmicro" (at -0.932 4.17 90) (layer "F.Fab") hide
        (effects (font (size 0.7 0.7) (thickness 0.15)) (justify left bottom))
    )
    (fp_rect (start -0.94 -0.47) (end 0.94 0.47)
      (stroke (width 0.05) (type solid)) (fill none) (layer "F.CrtYd"))
    (fp_rect (start -0.499 -0.249) (end 0.499 0.249)
      (stroke (width 0.15) (type solid)) (fill none) (layer "F.Fab"))
    (pad "1" smd roundrect (at -0.484 0 90) (size 0.59 0.64) (layers "F.Cu" "F.Paste" "F.Mask") (roundrect_rratio 0.25)
      (net 20 "PL_3V3") (pintype "passive"))
    (pad "2" smd roundrect (at 0.484 0 90) (size 0.59 0.64) (layers "F.Cu" "F.Paste" "F.Mask") (roundrect_rratio 0.25)
      (net 1 "GND") (pintype "passive"))
  )

  (footprint "kria-k26-devboard-footprints:C_0402_1005Metric" (layer "F.Cu")
    (at 163.9 141.878033 90)
    (descr "Capacitor SMD 0402")
    (tags "capacitor SMD 0402")
    (property "Author" "Antmicro")
    (property "Dielectric" "X5R")
    (property "License" "Apache-2.0")
    (property "MPN" "GRM155R61H104KE14D")
    (property "Manufacturer" "Murata")
    (property "Sheetfile" "pmod.kicad_sch")
    (property "Sheetname" "PMOD")
    (property "Val" "100n")
    (property "Voltage" "50V")
    (property "ki_description" " ")
    (attr smd)
    (fp_text reference "C37" (at -1.331967 4.522678 90) (layer "F.SilkS")
        (effects (font (size 0.7 0.7) (thickness 0.15)) (justify left bottom))
    )
    (fp_text value "C_100n_0402" (at 0 1.4 90) (layer "F.Fab") hide
        (effects (font (size 0.7 0.7) (thickness 0.15)) (justify left bottom))
    )
    (fp_text user "License: Apache-2.0" (at -0.932 5.17 90) (layer "F.Fab") hide
        (effects (font (size 0.7 0.7) (thickness 0.15)) (justify left bottom))
    )
    (fp_text user "Author: Antmicro" (at -0.932 4.17 90) (layer "F.Fab") hide
        (effects (font (size 0.7 0.7) (thickness 0.15)) (justify left bottom))
    )
    (fp_text user "${REFERENCE}" (at -0.932 3.168 90) (layer "F.Fab") hide
        (effects (font (size 0.7 0.7) (thickness 0.15)) (justify left bottom))
    )
    (fp_rect (start -0.94 -0.47) (end 0.94 0.47)
      (stroke (width 0.05) (type solid)) (fill none) (layer "F.CrtYd"))
    (fp_rect (start -0.499 -0.249) (end 0.499 0.249)
      (stroke (width 0.15) (type solid)) (fill none) (layer "F.Fab"))
    (pad "1" smd roundrect (at -0.484 0 90) (size 0.59 0.64) (layers "F.Cu" "F.Paste" "F.Mask") (roundrect_rratio 0.25)
      (net 20 "PL_3V3") (pintype "passive"))
    (pad "2" smd roundrect (at 0.484 0 90) (size 0.59 0.64) (layers "F.Cu" "F.Paste" "F.Mask") (roundrect_rratio 0.25)
      (net 1 "GND") (pintype "passive"))
  )

  (footprint "kria-k26-devboard-footprints:C_0402_1005Metric" (layer "F.Cu")
    (at 164.9 141.878033 90)
    (descr "Capacitor SMD 0402")
    (tags "capacitor SMD 0402")
    (property "Author" "Antmicro")
    (property "Dielectric" "X5R")
    (property "License" "Apache-2.0")
    (property "MPN" "GRM155R61H104KE14D")
    (property "Manufacturer" "Murata")
    (property "Sheetfile" "pmod.kicad_sch")
    (property "Sheetname" "PMOD")
    (property "Val" "100n")
    (property "Voltage" "50V")
    (property "ki_description" " ")
    (attr smd)
    (fp_text reference "C38" (at -1.331967 4.522678 90) (layer "F.SilkS")
        (effects (font (size 0.7 0.7) (thickness 0.15)) (justify left bottom))
    )
    (fp_text value "C_100n_0402" (at 0 1.4 90) (layer "F.Fab") hide
        (effects (font (size 0.7 0.7) (thickness 0.15)) (justify left bottom))
    )
    (fp_text user "Author: Antmicro" (at -0.932 4.17 90) (layer "F.Fab") hide
        (effects (font (size 0.7 0.7) (thickness 0.15)) (justify left bottom))
    )
    (fp_text user "${REFERENCE}" (at -0.932 3.168 90) (layer "F.Fab") hide
        (effects (font (size 0.7 0.7) (thickness 0.15)) (justify left bottom))
    )
    (fp_text user "License: Apache-2.0" (at -0.932 5.17 90) (layer "F.Fab") hide
        (effects (font (size 0.7 0.7) (thickness 0.15)) (justify left bottom))
    )
    (fp_rect (start -0.94 -0.47) (end 0.94 0.47)
      (stroke (width 0.05) (type solid)) (fill none) (layer "F.CrtYd"))
    (fp_rect (start -0.499 -0.249) (end 0.499 0.249)
      (stroke (width 0.15) (type solid)) (fill none) (layer "F.Fab"))
    (pad "1" smd roundrect (at -0.484 0 90) (size 0.59 0.64) (layers "F.Cu" "F.Paste" "F.Mask") (roundrect_rratio 0.25)
      (net 20 "PL_3V3") (pintype "passive"))
    (pad "2" smd roundrect (at 0.484 0 90) (size 0.59 0.64) (layers "F.Cu" "F.Paste" "F.Mask") (roundrect_rratio 0.25)
      (net 1 "GND") (pintype "passive"))
  )

  (footprint "kria-k26-devboard-footprints:DisplayPort_Receptacle_Molex_472720001" (layer "F.Cu")
    (at 90.26 59.26 180)
    (property "Author" "Antmicro")
    (property "License" "Apache-2.0")
    (property "MPN" "472720001")
    (property "Manufacturer" "Molex")
    (property "Sheetfile" "dp.kicad_sch")
    (property "Sheetname" "Display Port")
    (property "ki_description" "DisplayPort Receptacle Connector 20 Position Surface Mount, Right Angle; Through Hole")
    (property "ki_keywords" "DISPLAYPORT, CONNECTOR, SMT, THT, HORIZONTAL")
    (attr smd)
    (fp_text reference "J1" (at -14 -0.2 180) (layer "F.SilkS")
        (effects (font (size 0.7 0.7) (thickness 0.15)) (justify left bottom))
    )
    (fp_text value "DisplayPort_Molex_472720001" (at -14.4 16.2 180) (layer "F.Fab") hide
        (effects (font (size 0.7 0.7) (thickness 0.15)) (justify left bottom))
    )
    (fp_text user "${REFERENCE}" (at -14.4 17.601 180) (layer "F.Fab") hide
        (effects (font (size 0.7 0.7) (thickness 0.15)) (justify left bottom))
    )
    (fp_text user "License: Apache-2.0" (at -14.4 20.399 180) (layer "F.Fab") hide
        (effects (font (size 0.7 0.7) (thickness 0.15)) (justify left bottom))
    )
    (fp_text user "Author: Antmicro" (at -14.4 19 180) (layer "F.Fab") hide
        (effects (font (size 0.7 0.7) (thickness 0.15)) (justify left bottom))
    )
    (fp_line (start -8.449 -6.181) (end -8.449 -5.481)
      (stroke (width 0.15) (type solid)) (layer "F.SilkS"))
    (fp_line (start -8.449 -2.05) (end -8.449 1.498)
      (stroke (width 0.15) (type solid)) (layer "F.SilkS"))
    (fp_line (start -8.449 4.53) (end -8.449 6.93)
      (stroke (width 0.15) (type solid)) (layer "F.SilkS"))
    (fp_line (start -4.449 -6.181) (end -8.449 -6.181)
      (stroke (width 0.15) (type solid)) (layer "F.SilkS"))
    (fp_line (start 5.802 -7.37) (end 5.802 -6.181)
      (stroke (width 0.15) (type solid)) (layer "F.SilkS"))
    (fp_line (start 8.45 -6.181) (end 5.802 -6.181)
      (stroke (width 0.15) (type solid)) (layer "F.SilkS"))
    (fp_line (start 8.45 -6.181) (end 8.45 -5.481)
      (stroke (width 0.15) (type solid)) (layer "F.SilkS"))
    (fp_line (start 8.45 -2.05) (end 8.45 1.498)
      (stroke (width 0.15) (type solid)) (layer "F.SilkS"))
    (fp_line (start 8.45 4.53) (end 8.45 6.93)
      (stroke (width 0.15) (type solid)) (layer "F.SilkS"))
    (fp_line (start -9.1 7.6) (end -9.1 8.4)
      (stroke (width 0.05) (type solid)) (layer "F.CrtYd"))
    (fp_line (start -9.1 8.4) (end 9.1 8.4)
      (stroke (width 0.05) (type solid)) (layer "F.CrtYd"))
    (fp_line (start -8.65 -6.37) (end -8.65 7.6)
      (stroke (width 0.05) (type solid)) (layer "F.CrtYd"))
    (fp_line (start -8.65 7.6) (end -9.1 7.6)
      (stroke (width 0.05) (type solid)) (layer "F.CrtYd"))
    (fp_line (start -4.35 -7.77) (end -4.35 -6.37)
      (stroke (width 0.05) (type solid)) (layer "F.CrtYd"))
    (fp_line (start -4.35 -6.37) (end -8.65 -6.37)
      (stroke (width 0.05) (type solid)) (layer "F.CrtYd"))
    (fp_line (start 5.85 -7.77) (end -4.35 -7.77)
      (stroke (width 0.05) (type solid)) (layer "F.CrtYd"))
    (fp_line (start 5.85 -6.37) (end 5.85 -7.77)
      (stroke (width 0.05) (type solid)) (layer "F.CrtYd"))
    (fp_line (start 8.65 -6.37) (end 5.85 -6.37)
      (stroke (width 0.05) (type solid)) (layer "F.CrtYd"))
    (fp_line (start 8.65 7.6) (end 8.65 -6.37)
      (stroke (width 0.05) (type solid)) (layer "F.CrtYd"))
    (fp_line (start 9.1 7.6) (end 8.65 7.6)
      (stroke (width 0.05) (type solid)) (layer "F.CrtYd"))
    (fp_line (start 9.1 8.4) (end 9.1 7.6)
      (stroke (width 0.05) (type solid)) (layer "F.CrtYd"))
    (fp_line (start -8.449 -6.181) (end 8.45 -6.181)
      (stroke (width 0.15) (type solid)) (layer "F.Fab"))
    (fp_line (start -8.449 8.209) (end -8.449 -6.181)
      (stroke (width 0.15) (type solid)) (layer "F.Fab"))
    (fp_line (start 8.45 -6.181) (end 8.45 8.209)
      (stroke (width 0.15) (type solid)) (layer "F.Fab"))
    (fp_line (start 8.45 8.209) (end -8.449 8.209)
      (stroke (width 0.15) (type solid)) (layer "F.Fab"))
    (pad "" np_thru_hole circle (at 0.002 3.909 180) (size 1.4 1.4) (drill 1.4) (layers "*.Cu" "*.Mask"))
    (pad "1" smd rect (at 5.502 -6.37 180) (size 0.28 2.4) (layers "F.Cu" "F.Paste" "F.Mask")
      (net 93 "/Display Port/GTR_DP1_M2C_C_P") (pinfunction "TXD0+") (pintype "bidirectional"))
    (pad "2" smd rect (at 5.002 -6.37 180) (size 0.28 2.4) (layers "F.Cu" "F.Paste" "F.Mask")
      (net 1 "GND") (pinfunction "GND") (pintype "passive"))
    (pad "3" smd rect (at 4.502 -6.37 180) (size 0.28 2.4) (layers "F.Cu" "F.Paste" "F.Mask")
      (net 95 "/Display Port/GTR_DP1_M2C_C_N") (pinfunction "TXD0-") (pintype "bidirectional"))
    (pad "4" smd rect (at 4.002 -6.37 180) (size 0.28 2.4) (layers "F.Cu" "F.Paste" "F.Mask")
      (net 101 "/Display Port/GTR_DP0_M2C_C_P") (pinfunction "TXD1+") (pintype "bidirectional"))
    (pad "5" smd rect (at 3.502 -6.37 180) (size 0.28 2.4) (layers "F.Cu" "F.Paste" "F.Mask")
      (net 1 "GND") (pinfunction "GND") (pintype "passive"))
    (pad "6" smd rect (at 3.002 -6.37 180) (size 0.28 2.4) (layers "F.Cu" "F.Paste" "F.Mask")
      (net 103 "/Display Port/GTR_DP0_M2C_C_N") (pinfunction "TXD1-") (pintype "bidirectional"))
    (pad "7" smd rect (at 2.502 -6.37 180) (size 0.28 2.4) (layers "F.Cu" "F.Paste" "F.Mask")
      (net 344 "unconnected-(J1-TXD2+-Pad7)") (pinfunction "TXD2+") (pintype "bidirectional+no_connect"))
    (pad "8" smd rect (at 2.002 -6.37 180) (size 0.28 2.4) (layers "F.Cu" "F.Paste" "F.Mask")
      (net 1 "GND") (pinfunction "GND") (pintype "passive"))
    (pad "9" smd rect (at 1.502 -6.37 180) (size 0.28 2.4) (layers "F.Cu" "F.Paste" "F.Mask")
      (net 345 "unconnected-(J1-TXD2--Pad9)") (pinfunction "TXD2-") (pintype "bidirectional+no_connect"))
    (pad "10" smd rect (at 1.002 -6.37 180) (size 0.28 2.4) (layers "F.Cu" "F.Paste" "F.Mask")
      (net 346 "unconnected-(J1-TXD3+-Pad10)") (pinfunction "TXD3+") (pintype "bidirectional+no_connect"))
    (pad "11" smd rect (at 0.502 -6.37 180) (size 0.28 2.4) (layers "F.Cu" "F.Paste" "F.Mask")
      (net 1 "GND") (pinfunction "GND") (pintype "power_in"))
    (pad "12" smd rect (at 0.002 -6.37 180) (size 0.28 2.4) (layers "F.Cu" "F.Paste" "F.Mask")
      (net 347 "unconnected-(J1-TXD3--Pad12)") (pinfunction "TXD3-") (pintype "bidirectional+no_connect"))
    (pad "13" smd rect (at -0.498 -6.37 180) (size 0.28 2.4) (layers "F.Cu" "F.Paste" "F.Mask")
      (net 348 "Net-(J1-CFG1)") (pinfunction "CFG1") (pintype "passive"))
    (pad "14" smd rect (at -0.998 -6.37 180) (size 0.28 2.4) (layers "F.Cu" "F.Paste" "F.Mask")
      (net 349 "Net-(J1-CFG2)") (pinfunction "CFG2") (pintype "passive"))
    (pad "15" smd rect (at -1.498 -6.37 180) (size 0.28 2.4) (layers "F.Cu" "F.Paste" "F.Mask")
      (net 362 "/Display Port/DP_AUX_C_TVS_P") (pinfunction "AUX+") (pintype "bidirectional"))
    (pad "16" smd rect (at -1.998 -6.37 180) (size 0.28 2.4) (layers "F.Cu" "F.Paste" "F.Mask")
      (net 1 "GND") (pinfunction "GND") (pintype "passive"))
    (pad "17" smd rect (at -2.498 -6.37 180) (size 0.28 2.4) (layers "F.Cu" "F.Paste" "F.Mask")
      (net 363 "/Display Port/DP_AUX_C_TVS_N") (pinfunction "AUX-") (pintype "bidirectional"))
    (pad "18" smd rect (at -2.998 -6.37 180) (size 0.28 2.4) (layers "F.Cu" "F.Paste" "F.Mask")
      (net 105 "/Display Port/DP_HPD") (pinfunction "HPD") (pintype "passive"))
    (pad "19" smd rect (at -3.498 -6.37 180) (size 0.28 2.4) (layers "F.Cu" "F.Paste" "F.Mask")
      (net 804 "Net-(J1-RTN)") (pinfunction "RTN") (pintype "power_in"))
    (pad "20" smd rect (at -3.998 -6.37 180) (size 0.28 2.4) (layers "F.Cu" "F.Paste" "F.Mask")
      (net 334 "Net-(J1-DP_PWR)") (pinfunction "DP_PWR") (pintype "power_in"))
    (pad "SH" thru_hole oval (at -8.248 -3.771 180) (size 1.4 2.8) (drill oval 0.6 2.2) (layers "*.Cu" "*.Mask")
      (net 319 "SH_UP") (pinfunction "SH") (pintype "passive"))
    (pad "SH" thru_hole oval (at -8.248 3.01 180) (size 1.2 2.4) (drill oval 0.6 1.7) (layers "*.Cu" "*.Mask")
      (net 319 "SH_UP") (pinfunction "SH") (pintype "passive"))
    (pad "SH" thru_hole oval (at 8.251 -3.771 180) (size 1.4 2.8) (drill oval 0.6 2.2) (layers "*.Cu" "*.Mask")
      (net 319 "SH_UP") (pinfunction "SH") (pintype "passive"))
    (pad "SH" thru_hole oval (at 8.251 3.01 180) (size 1.2 2.4) (drill oval 0.6 1.7) (layers "*.Cu" "*.Mask")
      (net 319 "SH_UP") (pinfunction "SH") (pintype "passive"))
  )

  (footprint "kria-k26-devboard-footprints:PinSocket_2x6_P2.54mm_Drill1.04mm_Horizontal" (layer "F.Cu")
    (at 178.078 146.799 180)
    (property "Author" "Antmicro")
    (property "License" "Apache-2.0")
    (property "MPN" "SSW-106-02-G-D-RA")
    (property "Manufacturer" "Samtec")
    (property "Sheetfile" "pmod.kicad_sch")
    (property "Sheetname" "PMOD")
    (property "ki_description" "PCB Receptacle, Board-to-Board, 2.54 mm, 2 Rows, 12 Contacts, Through Hole Mount Right Angle, SSW")
    (property "ki_keywords" "CONNECTOR, SOCKET, THT, HORIZONTAL")
    (attr through_hole)
    (fp_text reference "J4" (at 0 -11.25 180) (layer "F.SilkS")
        (effects (font (size 0.7 0.7) (thickness 0.15)) (justify left bottom))
    )
    (fp_text value "PinSocket_2x6_P2.54mm_Drill1.04mm_Horizontal" (at 0 4.75 180) (layer "F.Fab") hide
        (effects (font (size 0.7 0.7) (thickness 0.15)) (justify left bottom))
    )
    (fp_text user "Author: Antmicro" (at -2.275 8.298 180) (layer "F.Fab") hide
        (effects (font (size 0.7 0.7) (thickness 0.15)) (justify left bottom))
    )
    (fp_text user "${REFERENCE}" (at -2.275 7.099 180) (layer "F.Fab") hide
        (effects (font (size 0.7 0.7) (thickness 0.15)) (justify left bottom))
    )
    (fp_text user "License: Apache-2.0" (at -2.275 9.499 180) (layer "F.Fab") hide
        (effects (font (size 0.7 0.7) (thickness 0.15)) (justify left bottom))
    )
    (fp_line (start -1.526 -1.524) (end -1.526 -10.035)
      (stroke (width 0.15) (type solid)) (layer "F.SilkS"))
    (fp_line (start 14.223 -10.035) (end -1.526 -10.035)
      (stroke (width 0.15) (type solid)) (layer "F.SilkS"))
    (fp_line (start 14.223 -10.035) (end 14.223 -1.524)
      (stroke (width 0.15) (type solid)) (layer "F.SilkS"))
    (fp_line (start 14.223 -1.524) (end -1.526 -1.524)
      (stroke (width 0.15) (type solid)) (layer "F.SilkS"))
    (fp_circle (center -2.2 0) (end -2.15 0)
      (stroke (width 0.15) (type solid)) (fill solid) (layer "F.SilkS"))
    (fp_rect (start -2.524 -11.01) (end 15.223 3.766)
      (stroke (width 0.05) (type solid)) (fill none) (layer "F.CrtYd"))
    (fp_line (start -1.526 -10.035) (end 14.223 -10.035)
      (stroke (width 0.15) (type solid)) (layer "F.Fab"))
    (fp_line (start -1.526 -10.035) (end 14.223 -10.035)
      (stroke (width 0.15) (type solid)) (layer "F.Fab"))
    (fp_line (start -1.526 -1.524) (end -1.526 -10.035)
      (stroke (width 0.15) (type solid)) (layer "F.Fab"))
    (fp_line (start -1.526 -1.524) (end -1.526 -10.035)
      (stroke (width 0.15) (type solid)) (layer "F.Fab"))
    (fp_line (start 14.223 -10.035) (end 14.223 -1.524)
      (stroke (width 0.15) (type solid)) (layer "F.Fab"))
    (fp_line (start 14.223 -10.035) (end 14.223 -1.524)
      (stroke (width 0.15) (type solid)) (layer "F.Fab"))
    (fp_line (start 14.223 -1.524) (end -1.526 -1.524)
      (stroke (width 0.15) (type solid)) (layer "F.Fab"))
    (pad "1" thru_hole rect (at 0 0 180) (size 1.84 1.84) (drill 1.04) (layers "*.Cu" "*.Mask")
      (net 144 "/PMOD/HDA11") (pintype "passive"))
    (pad "2" thru_hole circle (at 0 2.539 180) (size 1.84 1.84) (drill 1.04) (layers "*.Cu" "*.Mask")
      (net 146 "/PMOD/HDA15") (pintype "passive"))
    (pad "3" thru_hole circle (at 2.539 0 180) (size 1.84 1.84) (drill 1.04) (layers "*.Cu" "*.Mask")
      (net 155 "/PMOD/HDA12") (pintype "passive"))
    (pad "4" thru_hole circle (at 2.539 2.539 180) (size 1.8 1.8) (drill 1.04) (layers "*.Cu" "*.Mask")
      (net 147 "/PMOD/HDA16_CC") (pintype "passive"))
    (pad "5" thru_hole circle (at 5.078 0 180) (size 1.84 1.84) (drill 1.04) (layers "*.Cu" "*.Mask")
      (net 156 "/PMOD/HDA13") (pintype "passive"))
    (pad "6" thru_hole circle (at 5.078 2.539 180) (size 1.84 1.84) (drill 1.04) (layers "*.Cu" "*.Mask")
      (net 148 "/PMOD/HDA17") (pintype "passive"))
    (pad "7" thru_hole circle (at 7.618 0 180) (size 1.84 1.84) (drill 1.04) (layers "*.Cu" "*.Mask")
      (net 157 "/PMOD/HDA14") (pintype "passive"))
    (pad "8" thru_hole circle (at 7.618 2.539 180) (size 1.84 1.84) (drill 1.04) (layers "*.Cu" "*.Mask")
      (net 152 "/PMOD/HDA18") (pintype "passive"))
    (pad "9" thru_hole circle (at 10.159 0 180) (size 1.84 1.84) (drill 1.04) (layers "*.Cu" "*.Mask")
      (net 1 "GND") (pintype "passive"))
    (pad "10" thru_hole circle (at 10.159 2.539 180) (size 1.84 1.84) (drill 1.04) (layers "*.Cu" "*.Mask")
      (net 1 "GND") (pintype "passive"))
    (pad "11" thru_hole circle (at 12.698 0 180) (size 1.84 1.84) (drill 1.04) (layers "*.Cu" "*.Mask")
      (net 20 "PL_3V3") (pintype "passive"))
    (pad "12" thru_hole circle (at 12.698 2.539 180) (size 1.84 1.84) (drill 1.04) (layers "*.Cu" "*.Mask")
      (net 20 "PL_3V3") (pintype "passive"))
  )

  (footprint "kria-k26-devboard-footprints:Conn_JST_SH_1x8_BM08B-SRSS-TB-LF-SN" (layer "F.Cu")
    (at 111.785 149.698 180)
    (descr "Connector SMD pitch 1mm")
    (tags "connector SMD pitch 1mm")
    (property "Author" "Antmicro")
    (property "License" "Apache-2.0")
    (property "MPN" "BM08B-SRSS-TB(LF)(SN)")
    (property "Manufacturer" "JST Automotive Connectors")
    (property "Sheetfile" "reset.kicad_sch")
    (property "Sheetname" "Reset logic")
    (property "ki_description" "Pin Header, Wire-to-Board, 1 mm, 1 Rows, 8 Contacts, Surface Mount, SR")
    (property "ki_keywords" "VERTICAL, SMT, WIRE-BOARD, CONNECTOR")
    (attr smd)
    (fp_text reference "J7" (at -6.525 0.388) (layer "F.SilkS")
        (effects (font (size 0.7 0.7) (thickness 0.15)) (justify right bottom))
    )
    (fp_text value "JST_SH_1x8_BM08B-SRSS-TB-LF-SN" (at 0 2.7) (layer "F.Fab") hide
        (effects (font (size 0.7 0.7) (thickness 0.15)) (justify right bottom))
    )
    (fp_text user "License: Apache-2.0" (at -5.49 6.949) (layer "F.Fab") hide
        (effects (font (size 0.7 0.7) (thickness 0.15)) (justify right bottom))
    )
    (fp_text user "Author: Antmicro" (at -5.49 5.949) (layer "F.Fab") hide
        (effects (font (size 0.7 0.7) (thickness 0.15)) (justify right bottom))
    )
    (fp_text user "${REFERENCE}" (at -5.49 4.949) (layer "F.Fab") hide
        (effects (font (size 0.7 0.7) (thickness 0.15)) (justify right bottom))
    )
    (fp_line (start -5 0.973) (end -5 0)
      (stroke (width 0.15) (type solid)) (layer "F.SilkS"))
    (fp_line (start -4.242 0.973) (end -5 0.973)
      (stroke (width 0.15) (type solid)) (layer "F.SilkS"))
    (fp_line (start 3.88 -1.926) (end -3.88 -1.926)
      (stroke (width 0.15) (type solid)) (layer "F.SilkS"))
    (fp_line (start 4.242 0.973) (end 5 0.973)
      (stroke (width 0.15) (type solid)) (layer "F.SilkS"))
    (fp_line (start 5 0.973) (end 5 0)
      (stroke (width 0.15) (type solid)) (layer "F.SilkS"))
    (fp_circle (center -3.5 2.573) (end -3.45 2.573)
      (stroke (width 0.15) (type solid)) (fill solid) (layer "F.SilkS"))
    (fp_line (start -5.49 -2.337) (end 5.5 -2.337)
      (stroke (width 0.05) (type solid)) (layer "F.CrtYd"))
    (fp_line (start -5.49 -0.037) (end -5.49 -2.337)
      (stroke (width 0.05) (type solid)) (layer "F.CrtYd"))
    (fp_line (start -5.28 -0.037) (end -5.49 -0.037)
      (stroke (width 0.05) (type solid)) (layer "F.CrtYd"))
    (fp_line (start -5.28 1.263) (end -5.28 -0.037)
      (stroke (width 0.05) (type solid)) (layer "F.CrtYd"))
    (fp_line (start -4.04 1.263) (end -5.28 1.263)
      (stroke (width 0.05) (type solid)) (layer "F.CrtYd"))
    (fp_line (start -4.04 2.173) (end -4.04 1.263)
      (stroke (width 0.05) (type solid)) (layer "F.CrtYd"))
    (fp_line (start 4.05 1.263) (end 4.05 2.173)
      (stroke (width 0.05) (type solid)) (layer "F.CrtYd"))
    (fp_line (start 4.05 2.173) (end -4.04 2.173)
      (stroke (width 0.05) (type solid)) (layer "F.CrtYd"))
    (fp_line (start 5.25 -0.037) (end 5.25 1.263)
      (stroke (width 0.05) (type solid)) (layer "F.CrtYd"))
    (fp_line (start 5.25 1.263) (end 4.05 1.263)
      (stroke (width 0.05) (type solid)) (layer "F.CrtYd"))
    (fp_line (start 5.5 -2.337) (end 5.5 -0.037)
      (stroke (width 0.05) (type solid)) (layer "F.CrtYd"))
    (fp_line (start 5.5 -0.037) (end 5.25 -0.037)
      (stroke (width 0.05) (type solid)) (layer "F.CrtYd"))
    (fp_line (start -5 0.573) (end -4.6 0.973)
      (stroke (width 0.15) (type solid)) (layer "F.Fab"))
    (fp_rect (start -5 -1.927) (end 5 0.973)
      (stroke (width 0.15) (type solid)) (fill none) (layer "F.Fab"))
    (pad "1" smd rect (at -3.5 1.298) (size 0.6 1.55) (layers "F.Cu" "F.Paste" "F.Mask")
      (net 1 "GND") (pinfunction "Pin_1") (pintype "passive"))
    (pad "2" smd rect (at -2.5 1.298) (size 0.6 1.55) (layers "F.Cu" "F.Paste" "F.Mask")
      (net 221 "/PCIE M2 key E /~{M2_PERST}") (pinfunction "Pin_2") (pintype "passive"))
    (pad "3" smd rect (at -1.5 1.298) (size 0.6 1.55) (layers "F.Cu" "F.Paste" "F.Mask")
      (net 198 "/Camera interface/CAM0_RST") (pinfunction "Pin_3") (pintype "passive"))
    (pad "4" smd rect (at -0.5 1.298) (size 0.6 1.55) (layers "F.Cu" "F.Paste" "F.Mask")
      (net 176 "/Ethernet/~{ETH_RESET}") (pinfunction "Pin_4") (pintype "passive"))
    (pad "5" smd rect (at 0.5 1.298) (size 0.6 1.55) (layers "F.Cu" "F.Paste" "F.Mask")
      (net 175 "/Reset logic/~{USB_HUB_RESET}") (pinfunction "Pin_5") (pintype "passive"))
    (pad "6" smd rect (at 1.5 1.298) (size 0.6 1.55) (layers "F.Cu" "F.Paste" "F.Mask")
      (net 178 "/Reset logic/~{USB_PHY_RESET}") (pinfunction "Pin_6") (pintype "passive"))
    (pad "7" smd rect (at 2.5 1.298) (size 0.6 1.55) (layers "F.Cu" "F.Paste" "F.Mask")
      (net 177 "/Reset logic/~{SD_CARD_RESET}") (pinfunction "Pin_7") (pintype "passive"))
    (pad "8" smd rect (at 3.5 1.298) (size 0.6 1.55) (layers "F.Cu" "F.Paste" "F.Mask")
      (net 151 "/Debug and JTAG/~{PS_POR}") (pinfunction "Pin_8") (pintype "passive"))
    (pad "MP" smd rect (at -4.798 -1.225) (size 1.2 1.8) (layers "F.Cu" "F.Paste" "F.Mask")
      (net 799 "unconnected-(J7-PadMP)") (pinfunction "MP") (pintype "passive+no_connect"))
    (pad "MP" smd rect (at 4.801 -1.225) (size 1.2 1.8) (layers "F.Cu" "F.Paste" "F.Mask")
      (net 799 "unconnected-(J7-PadMP)") (pinfunction "MP") (pintype "passive+no_connect"))
  )

  (footprint "kria-k26-devboard-footprints:oshw-logo" (layer "F.Cu")
    (at 78.175 68.6)
    (descr "OSHW Logo")
    (tags "OSHW Logo")
    (property "Author" "Antmicro")
    (property "License" "Apache-2.0")
    (property "MPN" "")
    (property "Manufacturer" "")
    (property "Sheetfile" "kria-k26-devboard.kicad_sch")
    (property "Sheetname" "")
    (attr exclude_from_pos_files)
    (fp_text reference "N2" (at 0 -4.4) (layer "F.SilkS") hide
        (effects (font (size 0.7 0.7) (thickness 0.15)) (justify left bottom))
    )
    (fp_text value "oshw_logo" (at 0 -3.4) (layer "F.Fab") hide
        (effects (font (size 0.7 0.7) (thickness 0.15)) (justify left bottom))
    )
    (fp_text user "Author: Antmicro" (at -3.081 6.404) (layer "F.Fab") hide
        (effects (font (size 0.7 0.7) (thickness 0.15)) (justify left bottom))
    )
    (fp_text user "License: Apache-2.0" (at -3.081 7.604) (layer "F.Fab") hide
        (effects (font (size 0.7 0.7) (thickness 0.15)) (justify left bottom))
    )
    (fp_text user "${REFERENCE}" (at -3.081 5.204) (layer "F.Fab") hide
        (effects (font (size 0.7 0.7) (thickness 0.15)) (justify left bottom))
    )
    (fp_poly
      (pts
        (xy -0.843 2.558)
        (xy -0.815 2.564)
        (xy -0.794 2.572)
        (xy -0.773 2.581)
        (xy -0.759 2.589)
        (xy -0.738 2.603)
        (xy -0.783 2.658)
        (xy -0.8 2.677)
        (xy -0.814 2.694)
        (xy -0.825 2.706)
        (xy -0.831 2.712)
        (xy -0.832 2.712)
        (xy -0.837 2.71)
        (xy -0.847 2.703)
        (xy -0.849 2.702)
        (xy -0.874 2.69)
        (xy -0.904 2.684)
        (xy -0.935 2.685)
        (xy -0.942 2.686)
        (xy -0.975 2.698)
        (xy -1.001 2.717)
        (xy -1.02 2.741)
        (xy -1.034 2.766)
        (xy -1.039 3.197)
        (xy -1.164 3.2)
        (xy -1.164 2.565)
        (xy -1.037 2.565)
        (xy -1.037 2.626)
        (xy -1.009 2.604)
        (xy -0.972 2.579)
        (xy -0.931 2.563)
        (xy -0.887 2.556)
        (xy -0.843 2.558)
      )

      (stroke (width 0.01) (type solid)) (fill solid) (layer "F.Cu"))
    (fp_poly
      (pts
        (xy 1.889 1.554)
        (xy 1.907 1.559)
        (xy 1.927 1.566)
        (xy 1.948 1.574)
        (xy 1.966 1.583)
        (xy 1.979 1.592)
        (xy 1.984 1.597)
        (xy 1.982 1.604)
        (xy 1.974 1.616)
        (xy 1.962 1.633)
        (xy 1.946 1.652)
        (xy 1.945 1.654)
        (xy 1.929 1.673)
        (xy 1.915 1.689)
        (xy 1.906 1.7)
        (xy 1.901 1.706)
        (xy 1.896 1.705)
        (xy 1.885 1.7)
        (xy 1.873 1.695)
        (xy 1.84 1.683)
        (xy 1.808 1.68)
        (xy 1.776 1.685)
        (xy 1.747 1.698)
        (xy 1.723 1.717)
        (xy 1.704 1.742)
        (xy 1.696 1.763)
        (xy 1.695 1.772)
        (xy 1.694 1.79)
        (xy 1.693 1.817)
        (xy 1.692 1.85)
        (xy 1.692 1.89)
        (xy 1.691 1.934)
        (xy 1.691 1.983)
        (xy 1.691 2.194)
        (xy 1.559 2.194)
        (xy 1.559 1.559)
        (xy 1.691 1.559)
        (xy 1.691 1.626)
        (xy 1.71 1.607)
        (xy 1.739 1.585)
        (xy 1.775 1.568)
        (xy 1.814 1.556)
        (xy 1.855 1.552)
        (xy 1.889 1.554)
      )

      (stroke (width 0.01) (type solid)) (fill solid) (layer "F.Cu"))
    (fp_poly
      (pts
        (xy -0.837 1.56)
        (xy -0.797 1.576)
        (xy -0.761 1.6)
        (xy -0.73 1.63)
        (xy -0.706 1.667)
        (xy -0.69 1.709)
        (xy -0.687 1.721)
        (xy -0.685 1.734)
        (xy -0.684 1.757)
        (xy -0.683 1.79)
        (xy -0.682 1.833)
        (xy -0.681 1.884)
        (xy -0.681 1.945)
        (xy -0.681 1.971)
        (xy -0.681 2.194)
        (xy -0.808 2.194)
        (xy -0.809 1.984)
        (xy -0.811 1.774)
        (xy -0.826 1.744)
        (xy -0.845 1.716)
        (xy -0.868 1.697)
        (xy -0.897 1.686)
        (xy -0.925 1.682)
        (xy -0.947 1.682)
        (xy -0.967 1.684)
        (xy -0.979 1.686)
        (xy -1.001 1.698)
        (xy -1.023 1.716)
        (xy -1.041 1.738)
        (xy -1.049 1.752)
        (xy -1.052 1.758)
        (xy -1.054 1.765)
        (xy -1.056 1.773)
        (xy -1.057 1.783)
        (xy -1.058 1.797)
        (xy -1.059 1.815)
        (xy -1.06 1.839)
        (xy -1.06 1.869)
        (xy -1.061 1.907)
        (xy -1.061 1.953)
        (xy -1.061 1.985)
        (xy -1.063 2.194)
        (xy -1.189 2.194)
        (xy -1.189 1.559)
        (xy -1.062 1.559)
        (xy -1.062 1.625)
        (xy -1.033 1.602)
        (xy -1.001 1.579)
        (xy -0.969 1.564)
        (xy -0.934 1.555)
        (xy -0.927 1.554)
        (xy -0.881 1.553)
        (xy -0.837 1.56)
      )

      (stroke (width 0.01) (type solid)) (fill solid) (layer "F.Cu"))
    (fp_poly
      (pts
        (xy 1.042 1.769)
        (xy 1.043 1.979)
        (xy 1.059 2.009)
        (xy 1.077 2.036)
        (xy 1.1 2.056)
        (xy 1.129 2.067)
        (xy 1.159 2.071)
        (xy 1.193 2.07)
        (xy 1.221 2.063)
        (xy 1.245 2.047)
        (xy 1.258 2.034)
        (xy 1.266 2.025)
        (xy 1.273 2.016)
        (xy 1.278 2.008)
        (xy 1.282 1.997)
        (xy 1.286 1.985)
        (xy 1.288 1.969)
        (xy 1.29 1.948)
        (xy 1.291 1.922)
        (xy 1.292 1.89)
        (xy 1.293 1.85)
        (xy 1.293 1.801)
        (xy 1.294 1.766)
        (xy 1.295 1.559)
        (xy 1.422 1.559)
        (xy 1.422 2.194)
        (xy 1.295 2.194)
        (xy 1.295 2.161)
        (xy 1.295 2.144)
        (xy 1.293 2.132)
        (xy 1.292 2.128)
        (xy 1.287 2.131)
        (xy 1.278 2.14)
        (xy 1.271 2.147)
        (xy 1.256 2.159)
        (xy 1.236 2.171)
        (xy 1.219 2.181)
        (xy 1.202 2.188)
        (xy 1.186 2.193)
        (xy 1.17 2.196)
        (xy 1.148 2.197)
        (xy 1.135 2.198)
        (xy 1.107 2.198)
        (xy 1.087 2.197)
        (xy 1.07 2.194)
        (xy 1.059 2.19)
        (xy 1.036 2.181)
        (xy 1.019 2.172)
        (xy 1.003 2.161)
        (xy 0.985 2.146)
        (xy 0.981 2.141)
        (xy 0.952 2.107)
        (xy 0.931 2.068)
        (xy 0.92 2.033)
        (xy 0.918 2.019)
        (xy 0.917 1.996)
        (xy 0.916 1.963)
        (xy 0.915 1.92)
        (xy 0.914 1.869)
        (xy 0.914 1.808)
        (xy 0.914 1.782)
        (xy 0.914 1.559)
        (xy 1.04 1.559)
        (xy 1.042 1.769)
      )

      (stroke (width 0.01) (type solid)) (fill solid) (layer "F.Cu"))
    (fp_poly
      (pts
        (xy 1.753 2.563)
        (xy 1.768 2.568)
        (xy 1.787 2.577)
        (xy 1.804 2.586)
        (xy 1.818 2.595)
        (xy 1.826 2.602)
        (xy 1.827 2.606)
        (xy 1.824 2.611)
        (xy 1.815 2.621)
        (xy 1.803 2.636)
        (xy 1.789 2.654)
        (xy 1.775 2.671)
        (xy 1.761 2.688)
        (xy 1.749 2.701)
        (xy 1.742 2.71)
        (xy 1.739 2.712)
        (xy 1.735 2.71)
        (xy 1.724 2.704)
        (xy 1.713 2.698)
        (xy 1.697 2.69)
        (xy 1.682 2.686)
        (xy 1.664 2.685)
        (xy 1.653 2.685)
        (xy 1.618 2.688)
        (xy 1.59 2.699)
        (xy 1.566 2.718)
        (xy 1.561 2.723)
        (xy 1.554 2.732)
        (xy 1.548 2.74)
        (xy 1.544 2.748)
        (xy 1.54 2.758)
        (xy 1.537 2.769)
        (xy 1.534 2.785)
        (xy 1.533 2.804)
        (xy 1.532 2.829)
        (xy 1.531 2.861)
        (xy 1.53 2.899)
        (xy 1.53 2.947)
        (xy 1.53 2.988)
        (xy 1.528 3.2)
        (xy 1.468 3.2)
        (xy 1.444 3.2)
        (xy 1.425 3.199)
        (xy 1.411 3.198)
        (xy 1.405 3.197)
        (xy 1.404 3.191)
        (xy 1.404 3.176)
        (xy 1.403 3.153)
        (xy 1.403 3.122)
        (xy 1.402 3.085)
        (xy 1.402 3.042)
        (xy 1.402 2.993)
        (xy 1.402 2.941)
        (xy 1.402 2.886)
        (xy 1.402 2.565)
        (xy 1.529 2.565)
        (xy 1.529 2.595)
        (xy 1.529 2.611)
        (xy 1.53 2.623)
        (xy 1.532 2.626)
        (xy 1.537 2.623)
        (xy 1.547 2.615)
        (xy 1.554 2.608)
        (xy 1.588 2.584)
        (xy 1.627 2.567)
        (xy 1.669 2.558)
        (xy 1.712 2.556)
        (xy 1.753 2.563)
      )

      (stroke (width 0.01) (type solid)) (fill solid) (layer "F.Cu"))
    (fp_poly
      (pts
        (xy 2.316 1.557)
        (xy 2.365 1.57)
        (xy 2.41 1.593)
        (xy 2.453 1.625)
        (xy 2.46 1.631)
        (xy 2.491 1.661)
        (xy 2.466 1.684)
        (xy 2.448 1.699)
        (xy 2.43 1.715)
        (xy 2.419 1.725)
        (xy 2.397 1.743)
        (xy 2.376 1.724)
        (xy 2.345 1.701)
        (xy 2.312 1.687)
        (xy 2.274 1.681)
        (xy 2.265 1.681)
        (xy 2.226 1.684)
        (xy 2.195 1.693)
        (xy 2.167 1.708)
        (xy 2.159 1.715)
        (xy 2.136 1.741)
        (xy 2.118 1.776)
        (xy 2.107 1.817)
        (xy 2.103 1.866)
        (xy 2.103 1.876)
        (xy 2.106 1.926)
        (xy 2.116 1.97)
        (xy 2.132 2.006)
        (xy 2.155 2.034)
        (xy 2.184 2.055)
        (xy 2.219 2.067)
        (xy 2.259 2.072)
        (xy 2.274 2.071)
        (xy 2.309 2.066)
        (xy 2.339 2.056)
        (xy 2.366 2.038)
        (xy 2.377 2.028)
        (xy 2.386 2.02)
        (xy 2.393 2.016)
        (xy 2.4 2.015)
        (xy 2.409 2.018)
        (xy 2.42 2.027)
        (xy 2.436 2.041)
        (xy 2.456 2.059)
        (xy 2.491 2.092)
        (xy 2.476 2.108)
        (xy 2.449 2.132)
        (xy 2.416 2.155)
        (xy 2.38 2.174)
        (xy 2.35 2.186)
        (xy 2.327 2.193)
        (xy 2.306 2.197)
        (xy 2.283 2.199)
        (xy 2.259 2.199)
        (xy 2.233 2.198)
        (xy 2.209 2.196)
        (xy 2.189 2.193)
        (xy 2.182 2.191)
        (xy 2.133 2.173)
        (xy 2.089 2.146)
        (xy 2.053 2.112)
        (xy 2.023 2.071)
        (xy 2.012 2.051)
        (xy 2 2.023)
        (xy 1.991 1.999)
        (xy 1.984 1.975)
        (xy 1.981 1.948)
        (xy 1.979 1.917)
        (xy 1.978 1.879)
        (xy 1.978 1.877)
        (xy 1.979 1.838)
        (xy 1.98 1.806)
        (xy 1.984 1.78)
        (xy 1.99 1.756)
        (xy 1.999 1.731)
        (xy 2.011 1.704)
        (xy 2.012 1.701)
        (xy 2.039 1.657)
        (xy 2.072 1.62)
        (xy 2.111 1.591)
        (xy 2.156 1.57)
        (xy 2.207 1.557)
        (xy 2.263 1.552)
        (xy 2.316 1.557)
      )

      (stroke (width 0.01) (type solid)) (fill solid) (layer "F.Cu"))
    (fp_poly
      (pts
        (xy -1.494 1.56)
        (xy -1.447 1.576)
        (xy -1.405 1.6)
        (xy -1.368 1.633)
        (xy -1.341 1.668)
        (xy -1.326 1.692)
        (xy -1.316 1.716)
        (xy -1.308 1.743)
        (xy -1.302 1.774)
        (xy -1.299 1.811)
        (xy -1.297 1.845)
        (xy -1.294 1.925)
        (xy -1.692 1.925)
        (xy -1.692 1.942)
        (xy -1.687 1.977)
        (xy -1.673 2.011)
        (xy -1.65 2.039)
        (xy -1.626 2.059)
        (xy -1.601 2.071)
        (xy -1.572 2.078)
        (xy -1.537 2.079)
        (xy -1.497 2.074)
        (xy -1.458 2.06)
        (xy -1.422 2.036)
        (xy -1.421 2.036)
        (xy -1.402 2.021)
        (xy -1.359 2.057)
        (xy -1.342 2.072)
        (xy -1.327 2.085)
        (xy -1.317 2.094)
        (xy -1.314 2.098)
        (xy -1.316 2.103)
        (xy -1.324 2.113)
        (xy -1.338 2.126)
        (xy -1.354 2.139)
        (xy -1.372 2.152)
        (xy -1.389 2.163)
        (xy -1.399 2.168)
        (xy -1.421 2.178)
        (xy -1.445 2.187)
        (xy -1.461 2.191)
        (xy -1.488 2.196)
        (xy -1.522 2.199)
        (xy -1.557 2.199)
        (xy -1.591 2.196)
        (xy -1.62 2.192)
        (xy -1.629 2.19)
        (xy -1.677 2.171)
        (xy -1.718 2.146)
        (xy -1.752 2.114)
        (xy -1.779 2.074)
        (xy -1.8 2.026)
        (xy -1.802 2.02)
        (xy -1.81 1.989)
        (xy -1.815 1.951)
        (xy -1.818 1.908)
        (xy -1.819 1.865)
        (xy -1.818 1.823)
        (xy -1.816 1.804)
        (xy -1.692 1.804)
        (xy -1.692 1.818)
        (xy -1.428 1.818)
        (xy -1.428 1.801)
        (xy -1.432 1.775)
        (xy -1.442 1.748)
        (xy -1.457 1.722)
        (xy -1.469 1.707)
        (xy -1.495 1.688)
        (xy -1.526 1.676)
        (xy -1.56 1.672)
        (xy -1.593 1.676)
        (xy -1.619 1.685)
        (xy -1.646 1.704)
        (xy -1.668 1.73)
        (xy -1.683 1.76)
        (xy -1.691 1.792)
        (xy -1.692 1.804)
        (xy -1.816 1.804)
        (xy -1.814 1.786)
        (xy -1.812 1.777)
        (xy -1.797 1.724)
        (xy -1.775 1.676)
        (xy -1.747 1.636)
        (xy -1.713 1.603)
        (xy -1.673 1.578)
        (xy -1.629 1.561)
        (xy -1.597 1.554)
        (xy -1.544 1.552)
        (xy -1.494 1.56)
      )

      (stroke (width 0.01) (type solid)) (fill solid) (layer "F.Cu"))
    (fp_poly
      (pts
        (xy 2.835 1.557)
        (xy 2.883 1.57)
        (xy 2.926 1.592)
        (xy 2.964 1.621)
        (xy 2.996 1.657)
        (xy 3.021 1.699)
        (xy 3.038 1.747)
        (xy 3.04 1.757)
        (xy 3.043 1.776)
        (xy 3.045 1.802)
        (xy 3.047 1.832)
        (xy 3.047 1.858)
        (xy 3.047 1.925)
        (xy 2.65 1.925)
        (xy 2.653 1.951)
        (xy 2.663 1.991)
        (xy 2.68 2.024)
        (xy 2.703 2.049)
        (xy 2.733 2.067)
        (xy 2.77 2.077)
        (xy 2.801 2.079)
        (xy 2.845 2.075)
        (xy 2.883 2.063)
        (xy 2.916 2.042)
        (xy 2.92 2.039)
        (xy 2.929 2.031)
        (xy 2.935 2.026)
        (xy 2.941 2.025)
        (xy 2.949 2.027)
        (xy 2.959 2.034)
        (xy 2.974 2.047)
        (xy 2.994 2.064)
        (xy 3.01 2.078)
        (xy 3.023 2.088)
        (xy 3.03 2.095)
        (xy 3.032 2.096)
        (xy 3.03 2.1)
        (xy 3.022 2.11)
        (xy 3.01 2.122)
        (xy 3.009 2.123)
        (xy 2.98 2.147)
        (xy 2.945 2.169)
        (xy 2.906 2.185)
        (xy 2.887 2.191)
        (xy 2.861 2.196)
        (xy 2.828 2.198)
        (xy 2.793 2.198)
        (xy 2.759 2.197)
        (xy 2.729 2.193)
        (xy 2.721 2.191)
        (xy 2.675 2.175)
        (xy 2.634 2.15)
        (xy 2.599 2.118)
        (xy 2.569 2.077)
        (xy 2.547 2.029)
        (xy 2.536 1.996)
        (xy 2.532 1.973)
        (xy 2.529 1.942)
        (xy 2.527 1.906)
        (xy 2.527 1.869)
        (xy 2.528 1.832)
        (xy 2.529 1.818)
        (xy 2.65 1.818)
        (xy 2.922 1.818)
        (xy 2.918 1.799)
        (xy 2.908 1.758)
        (xy 2.891 1.725)
        (xy 2.869 1.7)
        (xy 2.84 1.683)
        (xy 2.826 1.678)
        (xy 2.788 1.672)
        (xy 2.753 1.675)
        (xy 2.722 1.687)
        (xy 2.695 1.706)
        (xy 2.674 1.734)
        (xy 2.659 1.768)
        (xy 2.654 1.794)
        (xy 2.65 1.818)
        (xy 2.529 1.818)
        (xy 2.53 1.798)
        (xy 2.534 1.769)
        (xy 2.536 1.76)
        (xy 2.554 1.707)
        (xy 2.578 1.662)
        (xy 2.609 1.624)
        (xy 2.645 1.593)
        (xy 2.687 1.571)
        (xy 2.734 1.557)
        (xy 2.783 1.553)
        (xy 2.835 1.557)
      )

      (stroke (width 0.01) (type solid)) (fill solid) (layer "F.Cu"))
    (fp_poly
      (pts
        (xy -2.733 1.557)
        (xy -2.685 1.57)
        (xy -2.642 1.592)
        (xy -2.604 1.622)
        (xy -2.581 1.649)
        (xy -2.562 1.676)
        (xy -2.548 1.706)
        (xy -2.537 1.739)
        (xy -2.53 1.777)
        (xy -2.527 1.821)
        (xy -2.526 1.873)
        (xy -2.527 1.907)
        (xy -2.529 1.956)
        (xy -2.534 1.997)
        (xy -2.542 2.031)
        (xy -2.553 2.06)
        (xy -2.567 2.086)
        (xy -2.587 2.111)
        (xy -2.603 2.129)
        (xy -2.637 2.158)
        (xy -2.673 2.178)
        (xy -2.714 2.192)
        (xy -2.76 2.198)
        (xy -2.789 2.199)
        (xy -2.813 2.198)
        (xy -2.835 2.196)
        (xy -2.852 2.194)
        (xy -2.857 2.194)
        (xy -2.898 2.179)
        (xy -2.937 2.155)
        (xy -2.97 2.126)
        (xy -2.993 2.101)
        (xy -3.011 2.077)
        (xy -3.024 2.051)
        (xy -3.034 2.022)
        (xy -3.041 1.988)
        (xy -3.045 1.947)
        (xy -3.047 1.91)
        (xy -3.047 1.882)
        (xy -2.919 1.882)
        (xy -2.919 1.968)
        (xy -2.903 2.001)
        (xy -2.885 2.031)
        (xy -2.863 2.051)
        (xy -2.837 2.064)
        (xy -2.804 2.07)
        (xy -2.779 2.07)
        (xy -2.755 2.069)
        (xy -2.737 2.065)
        (xy -2.722 2.058)
        (xy -2.717 2.055)
        (xy -2.697 2.041)
        (xy -2.681 2.025)
        (xy -2.67 2.004)
        (xy -2.662 1.978)
        (xy -2.657 1.945)
        (xy -2.654 1.903)
        (xy -2.654 1.899)
        (xy -2.653 1.848)
        (xy -2.656 1.806)
        (xy -2.662 1.772)
        (xy -2.673 1.744)
        (xy -2.687 1.722)
        (xy -2.707 1.705)
        (xy -2.723 1.695)
        (xy -2.755 1.684)
        (xy -2.788 1.68)
        (xy -2.821 1.684)
        (xy -2.851 1.695)
        (xy -2.877 1.713)
        (xy -2.892 1.729)
        (xy -2.901 1.745)
        (xy -2.908 1.76)
        (xy -2.913 1.778)
        (xy -2.916 1.8)
        (xy -2.918 1.828)
        (xy -2.919 1.864)
        (xy -2.919 1.882)
        (xy -3.047 1.882)
        (xy -3.048 1.844)
        (xy -3.043 1.786)
        (xy -3.034 1.736)
        (xy -3.021 1.695)
        (xy -3.004 1.664)
        (xy -2.972 1.624)
        (xy -2.935 1.594)
        (xy -2.893 1.571)
        (xy -2.846 1.558)
        (xy -2.794 1.553)
        (xy -2.787 1.553)
        (xy -2.733 1.557)
      )

      (stroke (width 0.01) (type solid)) (fill solid) (layer "F.Cu"))
    (fp_poly
      (pts
        (xy 2.148 2.561)
        (xy 2.193 2.574)
        (xy 2.235 2.595)
        (xy 2.273 2.623)
        (xy 2.304 2.657)
        (xy 2.326 2.691)
        (xy 2.338 2.718)
        (xy 2.346 2.745)
        (xy 2.352 2.774)
        (xy 2.355 2.808)
        (xy 2.357 2.85)
        (xy 2.357 2.858)
        (xy 2.357 2.931)
        (xy 1.96 2.931)
        (xy 1.963 2.955)
        (xy 1.973 2.993)
        (xy 1.991 3.026)
        (xy 2.015 3.053)
        (xy 2.039 3.069)
        (xy 2.057 3.076)
        (xy 2.08 3.08)
        (xy 2.103 3.082)
        (xy 2.144 3.081)
        (xy 2.18 3.071)
        (xy 2.214 3.054)
        (xy 2.227 3.045)
        (xy 2.24 3.035)
        (xy 2.25 3.029)
        (xy 2.253 3.027)
        (xy 2.258 3.03)
        (xy 2.269 3.039)
        (xy 2.284 3.05)
        (xy 2.3 3.064)
        (xy 2.315 3.078)
        (xy 2.329 3.09)
        (xy 2.338 3.099)
        (xy 2.341 3.103)
        (xy 2.337 3.11)
        (xy 2.327 3.121)
        (xy 2.312 3.134)
        (xy 2.294 3.148)
        (xy 2.276 3.161)
        (xy 2.259 3.171)
        (xy 2.252 3.175)
        (xy 2.204 3.192)
        (xy 2.152 3.202)
        (xy 2.098 3.204)
        (xy 2.046 3.198)
        (xy 2.032 3.195)
        (xy 1.984 3.178)
        (xy 1.943 3.154)
        (xy 1.909 3.123)
        (xy 1.881 3.084)
        (xy 1.859 3.037)
        (xy 1.847 3.003)
        (xy 1.841 2.972)
        (xy 1.838 2.934)
        (xy 1.836 2.893)
        (xy 1.837 2.851)
        (xy 1.839 2.824)
        (xy 1.96 2.824)
        (xy 2.23 2.824)
        (xy 2.23 2.813)
        (xy 2.225 2.783)
        (xy 2.214 2.753)
        (xy 2.196 2.725)
        (xy 2.175 2.702)
        (xy 2.151 2.686)
        (xy 2.128 2.68)
        (xy 2.101 2.677)
        (xy 2.072 2.678)
        (xy 2.051 2.683)
        (xy 2.023 2.696)
        (xy 2 2.717)
        (xy 1.981 2.746)
        (xy 1.968 2.779)
        (xy 1.963 2.8)
        (xy 1.96 2.824)
        (xy 1.839 2.824)
        (xy 1.839 2.811)
        (xy 1.844 2.776)
        (xy 1.848 2.76)
        (xy 1.866 2.708)
        (xy 1.889 2.663)
        (xy 1.919 2.627)
        (xy 1.954 2.598)
        (xy 1.996 2.575)
        (xy 2.007 2.571)
        (xy 2.054 2.559)
        (xy 2.101 2.556)
        (xy 2.148 2.561)
      )

      (stroke (width 0.01) (type solid)) (fill solid) (layer "F.Cu"))
    (fp_poly
      (pts
        (xy -0.229 3.2)
        (xy -0.354 3.197)
        (xy -0.355 3.165)
        (xy -0.357 3.133)
        (xy -0.374 3.148)
        (xy -0.411 3.175)
        (xy -0.453 3.193)
        (xy -0.497 3.203)
        (xy -0.542 3.204)
        (xy -0.585 3.195)
        (xy -0.586 3.195)
        (xy -0.621 3.181)
        (xy -0.651 3.16)
        (xy -0.673 3.141)
        (xy -0.689 3.123)
        (xy -0.702 3.106)
        (xy -0.712 3.086)
        (xy -0.72 3.064)
        (xy -0.726 3.038)
        (xy -0.73 3.007)
        (xy -0.732 2.968)
        (xy -0.733 2.922)
        (xy -0.733 2.88)
        (xy -0.602 2.88)
        (xy -0.602 2.915)
        (xy -0.602 2.942)
        (xy -0.601 2.962)
        (xy -0.6 2.977)
        (xy -0.598 2.988)
        (xy -0.596 2.998)
        (xy -0.592 3.007)
        (xy -0.591 3.01)
        (xy -0.574 3.039)
        (xy -0.552 3.059)
        (xy -0.525 3.071)
        (xy -0.492 3.076)
        (xy -0.472 3.076)
        (xy -0.442 3.072)
        (xy -0.418 3.063)
        (xy -0.398 3.048)
        (xy -0.382 3.029)
        (xy -0.371 3.004)
        (xy -0.363 2.972)
        (xy -0.358 2.933)
        (xy -0.356 2.885)
        (xy -0.356 2.88)
        (xy -0.358 2.828)
        (xy -0.363 2.785)
        (xy -0.373 2.75)
        (xy -0.387 2.724)
        (xy -0.406 2.704)
        (xy -0.43 2.692)
        (xy -0.46 2.686)
        (xy -0.483 2.685)
        (xy -0.517 2.687)
        (xy -0.544 2.696)
        (xy -0.565 2.711)
        (xy -0.583 2.734)
        (xy -0.591 2.751)
        (xy -0.595 2.76)
        (xy -0.598 2.769)
        (xy -0.6 2.779)
        (xy -0.601 2.793)
        (xy -0.602 2.811)
        (xy -0.602 2.836)
        (xy -0.602 2.869)
        (xy -0.602 2.88)
        (xy -0.733 2.88)
        (xy -0.733 2.827)
        (xy -0.732 2.783)
        (xy -0.729 2.746)
        (xy -0.725 2.716)
        (xy -0.719 2.691)
        (xy -0.71 2.67)
        (xy -0.699 2.651)
        (xy -0.685 2.633)
        (xy -0.668 2.616)
        (xy -0.668 2.615)
        (xy -0.632 2.587)
        (xy -0.592 2.567)
        (xy -0.55 2.557)
        (xy -0.506 2.556)
        (xy -0.463 2.564)
        (xy -0.421 2.582)
        (xy -0.411 2.587)
        (xy -0.394 2.598)
        (xy -0.377 2.61)
        (xy -0.373 2.614)
        (xy -0.356 2.627)
        (xy -0.356 2.306)
        (xy -0.229 2.306)
        (xy -0.229 3.2)
      )

      (stroke (width 0.01) (type solid)) (fill solid) (layer "F.Cu"))
    (fp_poly
      (pts
        (xy 0.605 1.558)
        (xy 0.651 1.574)
        (xy 0.694 1.598)
        (xy 0.728 1.627)
        (xy 0.75 1.652)
        (xy 0.768 1.678)
        (xy 0.781 1.707)
        (xy 0.791 1.739)
        (xy 0.797 1.777)
        (xy 0.801 1.822)
        (xy 0.802 1.876)
        (xy 0.802 1.877)
        (xy 0.801 1.929)
        (xy 0.798 1.973)
        (xy 0.792 2.009)
        (xy 0.784 2.04)
        (xy 0.774 2.062)
        (xy 0.748 2.103)
        (xy 0.715 2.139)
        (xy 0.675 2.167)
        (xy 0.632 2.187)
        (xy 0.626 2.189)
        (xy 0.599 2.195)
        (xy 0.567 2.198)
        (xy 0.532 2.199)
        (xy 0.499 2.197)
        (xy 0.471 2.193)
        (xy 0.466 2.192)
        (xy 0.428 2.177)
        (xy 0.391 2.155)
        (xy 0.359 2.129)
        (xy 0.354 2.123)
        (xy 0.332 2.098)
        (xy 0.316 2.073)
        (xy 0.303 2.047)
        (xy 0.294 2.017)
        (xy 0.287 1.983)
        (xy 0.284 1.943)
        (xy 0.282 1.894)
        (xy 0.282 1.877)
        (xy 0.409 1.877)
        (xy 0.41 1.918)
        (xy 0.412 1.95)
        (xy 0.416 1.976)
        (xy 0.423 1.997)
        (xy 0.432 2.015)
        (xy 0.445 2.03)
        (xy 0.451 2.037)
        (xy 0.471 2.054)
        (xy 0.491 2.064)
        (xy 0.514 2.07)
        (xy 0.543 2.072)
        (xy 0.569 2.07)
        (xy 0.59 2.065)
        (xy 0.601 2.06)
        (xy 0.625 2.047)
        (xy 0.642 2.031)
        (xy 0.656 2.009)
        (xy 0.661 1.998)
        (xy 0.665 1.989)
        (xy 0.668 1.98)
        (xy 0.67 1.969)
        (xy 0.671 1.954)
        (xy 0.672 1.935)
        (xy 0.673 1.909)
        (xy 0.673 1.877)
        (xy 0.673 1.842)
        (xy 0.672 1.817)
        (xy 0.671 1.798)
        (xy 0.67 1.784)
        (xy 0.668 1.773)
        (xy 0.665 1.764)
        (xy 0.661 1.755)
        (xy 0.647 1.73)
        (xy 0.632 1.712)
        (xy 0.612 1.698)
        (xy 0.601 1.693)
        (xy 0.569 1.683)
        (xy 0.535 1.681)
        (xy 0.501 1.686)
        (xy 0.471 1.7)
        (xy 0.447 1.719)
        (xy 0.434 1.736)
        (xy 0.424 1.753)
        (xy 0.417 1.774)
        (xy 0.412 1.8)
        (xy 0.41 1.833)
        (xy 0.409 1.873)
        (xy 0.409 1.877)
        (xy 0.282 1.877)
        (xy 0.283 1.824)
        (xy 0.286 1.78)
        (xy 0.292 1.742)
        (xy 0.301 1.711)
        (xy 0.313 1.683)
        (xy 0.33 1.657)
        (xy 0.35 1.633)
        (xy 0.351 1.632)
        (xy 0.385 1.601)
        (xy 0.42 1.578)
        (xy 0.46 1.563)
        (xy 0.505 1.554)
        (xy 0.555 1.551)
        (xy 0.605 1.558)
      )

      (stroke (width 0.01) (type solid)) (fill solid) (layer "F.Cu"))
    (fp_poly
      (pts
        (xy 0.004 1.556)
        (xy 0.054 1.566)
        (xy 0.102 1.582)
        (xy 0.146 1.605)
        (xy 0.154 1.61)
        (xy 0.193 1.636)
        (xy 0.178 1.655)
        (xy 0.166 1.668)
        (xy 0.152 1.686)
        (xy 0.138 1.7)
        (xy 0.114 1.727)
        (xy 0.07 1.705)
        (xy 0.032 1.688)
        (xy -0.007 1.677)
        (xy -0.044 1.672)
        (xy -0.079 1.672)
        (xy -0.11 1.678)
        (xy -0.136 1.69)
        (xy -0.154 1.707)
        (xy -0.162 1.724)
        (xy -0.164 1.745)
        (xy -0.164 1.761)
        (xy -0.159 1.772)
        (xy -0.15 1.782)
        (xy -0.149 1.783)
        (xy -0.139 1.791)
        (xy -0.128 1.797)
        (xy -0.114 1.802)
        (xy -0.095 1.805)
        (xy -0.07 1.808)
        (xy -0.037 1.811)
        (xy -0.02 1.813)
        (xy 0.027 1.817)
        (xy 0.065 1.823)
        (xy 0.096 1.832)
        (xy 0.122 1.842)
        (xy 0.14 1.854)
        (xy 0.166 1.879)
        (xy 0.186 1.91)
        (xy 0.2 1.947)
        (xy 0.206 1.987)
        (xy 0.206 2.018)
        (xy 0.198 2.06)
        (xy 0.181 2.097)
        (xy 0.155 2.129)
        (xy 0.122 2.156)
        (xy 0.08 2.177)
        (xy 0.042 2.189)
        (xy 0.005 2.196)
        (xy -0.038 2.199)
        (xy -0.083 2.198)
        (xy -0.125 2.194)
        (xy -0.153 2.189)
        (xy -0.177 2.181)
        (xy -0.204 2.171)
        (xy -0.229 2.16)
        (xy -0.232 2.159)
        (xy -0.251 2.148)
        (xy -0.272 2.136)
        (xy -0.292 2.122)
        (xy -0.309 2.109)
        (xy -0.323 2.098)
        (xy -0.33 2.09)
        (xy -0.331 2.088)
        (xy -0.327 2.084)
        (xy -0.318 2.073)
        (xy -0.304 2.059)
        (xy -0.288 2.043)
        (xy -0.246 2)
        (xy -0.221 2.021)
        (xy -0.184 2.047)
        (xy -0.145 2.065)
        (xy -0.102 2.075)
        (xy -0.053 2.079)
        (xy -0.049 2.079)
        (xy -0.023 2.079)
        (xy -0.004 2.078)
        (xy 0.011 2.074)
        (xy 0.025 2.069)
        (xy 0.029 2.068)
        (xy 0.054 2.052)
        (xy 0.071 2.033)
        (xy 0.079 2.01)
        (xy 0.078 1.986)
        (xy 0.074 1.975)
        (xy 0.068 1.964)
        (xy 0.06 1.956)
        (xy 0.048 1.949)
        (xy 0.031 1.944)
        (xy 0.007 1.939)
        (xy -0.024 1.935)
        (xy -0.052 1.932)
        (xy -0.089 1.929)
        (xy -0.119 1.925)
        (xy -0.142 1.921)
        (xy -0.16 1.917)
        (xy -0.176 1.912)
        (xy -0.192 1.906)
        (xy -0.201 1.901)
        (xy -0.235 1.879)
        (xy -0.262 1.85)
        (xy -0.28 1.816)
        (xy -0.29 1.776)
        (xy -0.292 1.75)
        (xy -0.291 1.727)
        (xy -0.289 1.705)
        (xy -0.286 1.689)
        (xy -0.286 1.688)
        (xy -0.273 1.659)
        (xy -0.253 1.63)
        (xy -0.229 1.604)
        (xy -0.221 1.599)
        (xy -0.185 1.577)
        (xy -0.143 1.562)
        (xy -0.096 1.554)
        (xy -0.047 1.552)
        (xy 0.004 1.556)
      )

      (stroke (width 0.01) (type solid)) (fill solid) (layer "F.Cu"))
    (fp_poly
      (pts
        (xy 1.038 2.556)
        (xy 1.091 2.563)
        (xy 1.137 2.576)
        (xy 1.177 2.595)
        (xy 1.209 2.62)
        (xy 1.234 2.65)
        (xy 1.242 2.665)
        (xy 1.247 2.677)
        (xy 1.251 2.691)
        (xy 1.255 2.708)
        (xy 1.258 2.727)
        (xy 1.26 2.751)
        (xy 1.262 2.78)
        (xy 1.263 2.815)
        (xy 1.263 2.858)
        (xy 1.264 2.908)
        (xy 1.263 2.967)
        (xy 1.263 2.989)
        (xy 1.262 3.197)
        (xy 1.135 3.197)
        (xy 1.133 3.171)
        (xy 1.132 3.144)
        (xy 1.119 3.159)
        (xy 1.096 3.179)
        (xy 1.065 3.193)
        (xy 1.026 3.202)
        (xy 0.98 3.204)
        (xy 0.976 3.204)
        (xy 0.955 3.204)
        (xy 0.937 3.203)
        (xy 0.925 3.202)
        (xy 0.924 3.201)
        (xy 0.879 3.189)
        (xy 0.839 3.17)
        (xy 0.806 3.144)
        (xy 0.781 3.113)
        (xy 0.763 3.077)
        (xy 0.753 3.037)
        (xy 0.753 3.005)
        (xy 0.873 3.005)
        (xy 0.874 3.023)
        (xy 0.878 3.035)
        (xy 0.887 3.047)
        (xy 0.89 3.05)
        (xy 0.903 3.063)
        (xy 0.917 3.072)
        (xy 0.935 3.078)
        (xy 0.957 3.081)
        (xy 0.986 3.082)
        (xy 1.013 3.082)
        (xy 1.043 3.081)
        (xy 1.065 3.079)
        (xy 1.08 3.077)
        (xy 1.091 3.073)
        (xy 1.096 3.071)
        (xy 1.112 3.058)
        (xy 1.123 3.039)
        (xy 1.13 3.012)
        (xy 1.132 2.977)
        (xy 1.132 2.975)
        (xy 1.132 2.931)
        (xy 1.035 2.931)
        (xy 0.999 2.931)
        (xy 0.973 2.931)
        (xy 0.953 2.932)
        (xy 0.939 2.934)
        (xy 0.928 2.936)
        (xy 0.919 2.939)
        (xy 0.916 2.94)
        (xy 0.893 2.954)
        (xy 0.88 2.971)
        (xy 0.874 2.994)
        (xy 0.873 3.005)
        (xy 0.753 3.005)
        (xy 0.753 2.994)
        (xy 0.761 2.951)
        (xy 0.768 2.931)
        (xy 0.776 2.915)
        (xy 0.786 2.901)
        (xy 0.802 2.884)
        (xy 0.804 2.882)
        (xy 0.82 2.867)
        (xy 0.835 2.854)
        (xy 0.85 2.845)
        (xy 0.867 2.838)
        (xy 0.887 2.833)
        (xy 0.912 2.829)
        (xy 0.943 2.827)
        (xy 0.982 2.826)
        (xy 1.015 2.825)
        (xy 1.133 2.823)
        (xy 1.132 2.771)
        (xy 1.131 2.746)
        (xy 1.129 2.73)
        (xy 1.127 2.719)
        (xy 1.123 2.711)
        (xy 1.117 2.705)
        (xy 1.098 2.691)
        (xy 1.07 2.682)
        (xy 1.032 2.677)
        (xy 1.006 2.677)
        (xy 0.972 2.678)
        (xy 0.945 2.682)
        (xy 0.924 2.688)
        (xy 0.907 2.699)
        (xy 0.9 2.706)
        (xy 0.882 2.723)
        (xy 0.834 2.686)
        (xy 0.816 2.672)
        (xy 0.801 2.66)
        (xy 0.79 2.652)
        (xy 0.787 2.648)
        (xy 0.791 2.639)
        (xy 0.801 2.626)
        (xy 0.816 2.612)
        (xy 0.832 2.6)
        (xy 0.864 2.581)
        (xy 0.902 2.568)
        (xy 0.946 2.559)
        (xy 0.98 2.556)
        (xy 1.038 2.556)
      )

      (stroke (width 0.01) (type solid)) (fill solid) (layer "F.Cu"))
    (fp_poly
      (pts
        (xy -1.521 2.559)
        (xy -1.485 2.562)
        (xy -1.454 2.568)
        (xy -1.427 2.577)
        (xy -1.401 2.589)
        (xy -1.371 2.61)
        (xy -1.345 2.639)
        (xy -1.325 2.67)
        (xy -1.321 2.679)
        (xy -1.309 2.71)
        (xy -1.309 3.197)
        (xy -1.433 3.2)
        (xy -1.433 3.172)
        (xy -1.434 3.157)
        (xy -1.435 3.147)
        (xy -1.436 3.144)
        (xy -1.44 3.147)
        (xy -1.449 3.156)
        (xy -1.453 3.161)
        (xy -1.472 3.178)
        (xy -1.496 3.19)
        (xy -1.526 3.198)
        (xy -1.563 3.202)
        (xy -1.578 3.203)
        (xy -1.603 3.203)
        (xy -1.627 3.203)
        (xy -1.647 3.201)
        (xy -1.656 3.2)
        (xy -1.686 3.191)
        (xy -1.717 3.176)
        (xy -1.746 3.159)
        (xy -1.765 3.143)
        (xy -1.79 3.111)
        (xy -1.807 3.075)
        (xy -1.816 3.037)
        (xy -1.817 2.998)
        (xy -1.817 2.997)
        (xy -1.697 2.997)
        (xy -1.696 3.02)
        (xy -1.687 3.042)
        (xy -1.67 3.06)
        (xy -1.668 3.062)
        (xy -1.654 3.07)
        (xy -1.64 3.076)
        (xy -1.624 3.08)
        (xy -1.602 3.081)
        (xy -1.574 3.082)
        (xy -1.558 3.082)
        (xy -1.529 3.081)
        (xy -1.508 3.08)
        (xy -1.494 3.078)
        (xy -1.483 3.075)
        (xy -1.474 3.07)
        (xy -1.458 3.058)
        (xy -1.447 3.041)
        (xy -1.44 3.017)
        (xy -1.435 2.985)
        (xy -1.435 2.977)
        (xy -1.432 2.931)
        (xy -1.533 2.931)
        (xy -1.568 2.931)
        (xy -1.595 2.931)
        (xy -1.615 2.932)
        (xy -1.63 2.934)
        (xy -1.641 2.936)
        (xy -1.65 2.938)
        (xy -1.655 2.941)
        (xy -1.676 2.955)
        (xy -1.69 2.974)
        (xy -1.697 2.997)
        (xy -1.817 2.997)
        (xy -1.811 2.96)
        (xy -1.797 2.924)
        (xy -1.775 2.892)
        (xy -1.747 2.864)
        (xy -1.715 2.845)
        (xy -1.7 2.838)
        (xy -1.685 2.833)
        (xy -1.668 2.83)
        (xy -1.648 2.827)
        (xy -1.623 2.825)
        (xy -1.591 2.824)
        (xy -1.551 2.824)
        (xy -1.54 2.824)
        (xy -1.432 2.824)
        (xy -1.434 2.776)
        (xy -1.436 2.747)
        (xy -1.441 2.726)
        (xy -1.448 2.711)
        (xy -1.46 2.699)
        (xy -1.474 2.689)
        (xy -1.483 2.685)
        (xy -1.492 2.682)
        (xy -1.505 2.68)
        (xy -1.524 2.68)
        (xy -1.55 2.679)
        (xy -1.56 2.679)
        (xy -1.594 2.68)
        (xy -1.62 2.682)
        (xy -1.639 2.686)
        (xy -1.654 2.692)
        (xy -1.666 2.701)
        (xy -1.675 2.711)
        (xy -1.686 2.724)
        (xy -1.735 2.686)
        (xy -1.754 2.672)
        (xy -1.769 2.659)
        (xy -1.78 2.65)
        (xy -1.784 2.646)
        (xy -1.78 2.64)
        (xy -1.77 2.629)
        (xy -1.756 2.616)
        (xy -1.74 2.604)
        (xy -1.724 2.592)
        (xy -1.711 2.584)
        (xy -1.71 2.583)
        (xy -1.688 2.574)
        (xy -1.668 2.566)
        (xy -1.647 2.562)
        (xy -1.623 2.559)
        (xy -1.593 2.558)
        (xy -1.565 2.558)
        (xy -1.521 2.559)
      )

      (stroke (width 0.01) (type solid)) (fill solid) (layer "F.Cu"))
    (fp_poly
      (pts
        (xy 0.035 2.777)
        (xy 0.047 2.822)
        (xy 0.059 2.864)
        (xy 0.069 2.903)
        (xy 0.078 2.936)
        (xy 0.086 2.963)
        (xy 0.092 2.984)
        (xy 0.095 2.996)
        (xy 0.096 2.999)
        (xy 0.098 2.999)
        (xy 0.103 2.991)
        (xy 0.109 2.975)
        (xy 0.118 2.95)
        (xy 0.129 2.917)
        (xy 0.143 2.874)
        (xy 0.152 2.849)
        (xy 0.165 2.807)
        (xy 0.179 2.766)
        (xy 0.192 2.726)
        (xy 0.204 2.689)
        (xy 0.214 2.658)
        (xy 0.221 2.634)
        (xy 0.224 2.627)
        (xy 0.244 2.565)
        (xy 0.338 2.565)
        (xy 0.406 2.774)
        (xy 0.42 2.819)
        (xy 0.434 2.861)
        (xy 0.446 2.899)
        (xy 0.457 2.932)
        (xy 0.466 2.96)
        (xy 0.473 2.981)
        (xy 0.477 2.993)
        (xy 0.478 2.997)
        (xy 0.48 2.998)
        (xy 0.482 2.996)
        (xy 0.485 2.99)
        (xy 0.49 2.978)
        (xy 0.495 2.96)
        (xy 0.502 2.936)
        (xy 0.511 2.905)
        (xy 0.523 2.865)
        (xy 0.536 2.817)
        (xy 0.543 2.789)
        (xy 0.556 2.744)
        (xy 0.568 2.701)
        (xy 0.578 2.663)
        (xy 0.587 2.629)
        (xy 0.595 2.602)
        (xy 0.601 2.582)
        (xy 0.605 2.57)
        (xy 0.606 2.567)
        (xy 0.611 2.566)
        (xy 0.625 2.566)
        (xy 0.645 2.566)
        (xy 0.669 2.566)
        (xy 0.673 2.566)
        (xy 0.739 2.567)
        (xy 0.656 2.827)
        (xy 0.64 2.878)
        (xy 0.624 2.928)
        (xy 0.609 2.976)
        (xy 0.595 3.02)
        (xy 0.582 3.06)
        (xy 0.571 3.094)
        (xy 0.563 3.121)
        (xy 0.557 3.139)
        (xy 0.556 3.143)
        (xy 0.538 3.2)
        (xy 0.425 3.197)
        (xy 0.358 2.975)
        (xy 0.341 2.917)
        (xy 0.327 2.87)
        (xy 0.315 2.831)
        (xy 0.305 2.801)
        (xy 0.297 2.78)
        (xy 0.292 2.766)
        (xy 0.289 2.761)
        (xy 0.288 2.761)
        (xy 0.286 2.768)
        (xy 0.281 2.783)
        (xy 0.274 2.806)
        (xy 0.265 2.836)
        (xy 0.254 2.871)
        (xy 0.242 2.911)
        (xy 0.23 2.953)
        (xy 0.223 2.976)
        (xy 0.21 3.02)
        (xy 0.197 3.062)
        (xy 0.186 3.099)
        (xy 0.177 3.132)
        (xy 0.169 3.158)
        (xy 0.163 3.177)
        (xy 0.16 3.189)
        (xy 0.159 3.191)
        (xy 0.157 3.195)
        (xy 0.151 3.198)
        (xy 0.141 3.199)
        (xy 0.124 3.2)
        (xy 0.101 3.2)
        (xy 0.073 3.199)
        (xy 0.055 3.198)
        (xy 0.045 3.196)
        (xy 0.043 3.194)
        (xy 0.041 3.188)
        (xy 0.036 3.173)
        (xy 0.029 3.15)
        (xy 0.019 3.121)
        (xy 0.008 3.084)
        (xy -0.006 3.043)
        (xy -0.02 2.996)
        (xy -0.036 2.946)
        (xy -0.053 2.893)
        (xy -0.057 2.883)
        (xy -0.074 2.83)
        (xy -0.09 2.779)
        (xy -0.105 2.732)
        (xy -0.119 2.689)
        (xy -0.131 2.652)
        (xy -0.141 2.621)
        (xy -0.148 2.596)
        (xy -0.154 2.58)
        (xy -0.156 2.572)
        (xy -0.156 2.569)
        (xy -0.151 2.567)
        (xy -0.14 2.566)
        (xy -0.123 2.565)
        (xy -0.096 2.565)
        (xy -0.091 2.565)
        (xy -0.023 2.565)
        (xy 0.035 2.777)
      )

      (stroke (width 0.01) (type solid)) (fill solid) (layer "F.Cu"))
    (fp_poly
      (pts
        (xy -2.065 1.559)
        (xy -2.024 1.576)
        (xy -1.986 1.601)
        (xy -1.973 1.612)
        (xy -1.957 1.63)
        (xy -1.943 1.649)
        (xy -1.932 1.668)
        (xy -1.924 1.69)
        (xy -1.918 1.716)
        (xy -1.914 1.747)
        (xy -1.911 1.785)
        (xy -1.91 1.831)
        (xy -1.91 1.877)
        (xy -1.91 1.93)
        (xy -1.912 1.974)
        (xy -1.914 2.011)
        (xy -1.919 2.041)
        (xy -1.925 2.067)
        (xy -1.934 2.088)
        (xy -1.945 2.107)
        (xy -1.959 2.125)
        (xy -1.972 2.139)
        (xy -1.993 2.157)
        (xy -2.018 2.173)
        (xy -2.031 2.18)
        (xy -2.047 2.188)
        (xy -2.06 2.192)
        (xy -2.074 2.195)
        (xy -2.091 2.196)
        (xy -2.114 2.197)
        (xy -2.122 2.197)
        (xy -2.147 2.196)
        (xy -2.165 2.195)
        (xy -2.179 2.193)
        (xy -2.191 2.189)
        (xy -2.205 2.183)
        (xy -2.21 2.18)
        (xy -2.231 2.169)
        (xy -2.251 2.156)
        (xy -2.265 2.146)
        (xy -2.286 2.127)
        (xy -2.286 2.627)
        (xy -2.266 2.608)
        (xy -2.248 2.595)
        (xy -2.227 2.582)
        (xy -2.217 2.577)
        (xy -2.173 2.562)
        (xy -2.129 2.556)
        (xy -2.086 2.559)
        (xy -2.045 2.57)
        (xy -2.007 2.589)
        (xy -1.974 2.616)
        (xy -1.946 2.648)
        (xy -1.926 2.687)
        (xy -1.919 2.707)
        (xy -1.917 2.715)
        (xy -1.915 2.724)
        (xy -1.914 2.737)
        (xy -1.913 2.753)
        (xy -1.912 2.774)
        (xy -1.911 2.8)
        (xy -1.911 2.833)
        (xy -1.911 2.874)
        (xy -1.911 2.923)
        (xy -1.911 2.967)
        (xy -1.911 3.2)
        (xy -2.035 3.197)
        (xy -2.038 2.984)
        (xy -2.038 2.932)
        (xy -2.039 2.889)
        (xy -2.039 2.854)
        (xy -2.04 2.826)
        (xy -2.041 2.805)
        (xy -2.042 2.788)
        (xy -2.043 2.776)
        (xy -2.045 2.767)
        (xy -2.046 2.76)
        (xy -2.049 2.755)
        (xy -2.051 2.75)
        (xy -2.072 2.721)
        (xy -2.098 2.701)
        (xy -2.128 2.688)
        (xy -2.161 2.683)
        (xy -2.195 2.687)
        (xy -2.22 2.697)
        (xy -2.24 2.71)
        (xy -2.259 2.729)
        (xy -2.274 2.75)
        (xy -2.278 2.757)
        (xy -2.28 2.765)
        (xy -2.281 2.781)
        (xy -2.283 2.806)
        (xy -2.284 2.839)
        (xy -2.285 2.881)
        (xy -2.286 2.933)
        (xy -2.286 2.984)
        (xy -2.289 3.197)
        (xy -2.413 3.2)
        (xy -2.413 1.877)
        (xy -2.286 1.877)
        (xy -2.285 1.926)
        (xy -2.281 1.966)
        (xy -2.274 1.998)
        (xy -2.262 2.024)
        (xy -2.247 2.043)
        (xy -2.228 2.058)
        (xy -2.215 2.064)
        (xy -2.194 2.07)
        (xy -2.168 2.072)
        (xy -2.141 2.071)
        (xy -2.117 2.066)
        (xy -2.106 2.063)
        (xy -2.079 2.044)
        (xy -2.058 2.019)
        (xy -2.05 2.001)
        (xy -2.045 1.984)
        (xy -2.042 1.959)
        (xy -2.04 1.929)
        (xy -2.038 1.895)
        (xy -2.038 1.861)
        (xy -2.039 1.829)
        (xy -2.041 1.8)
        (xy -2.044 1.777)
        (xy -2.045 1.772)
        (xy -2.057 1.738)
        (xy -2.073 1.712)
        (xy -2.094 1.695)
        (xy -2.122 1.684)
        (xy -2.156 1.681)
        (xy -2.159 1.681)
        (xy -2.192 1.683)
        (xy -2.22 1.691)
        (xy -2.243 1.705)
        (xy -2.26 1.725)
        (xy -2.273 1.753)
        (xy -2.281 1.788)
        (xy -2.285 1.832)
        (xy -2.286 1.877)
        (xy -2.413 1.877)
        (xy -2.413 1.559)
        (xy -2.286 1.559)
        (xy -2.286 1.62)
        (xy -2.26 1.6)
        (xy -2.225 1.577)
        (xy -2.19 1.563)
        (xy -2.154 1.554)
        (xy -2.109 1.552)
        (xy -2.065 1.559)
      )

      (stroke (width 0.01) (type solid)) (fill solid) (layer "F.Cu"))
    (fp_poly
      (pts
        (xy 0.063 -3.201)
        (xy 0.118 -3.201)
        (xy 0.164 -3.201)
        (xy 0.202 -3.2)
        (xy 0.233 -3.2)
        (xy 0.258 -3.2)
        (xy 0.277 -3.199)
        (xy 0.292 -3.198)
        (xy 0.302 -3.197)
        (xy 0.309 -3.196)
        (xy 0.314 -3.195)
        (xy 0.317 -3.193)
        (xy 0.319 -3.192)
        (xy 0.321 -3.189)
        (xy 0.324 -3.183)
        (xy 0.327 -3.174)
        (xy 0.33 -3.161)
        (xy 0.334 -3.144)
        (xy 0.339 -3.12)
        (xy 0.345 -3.091)
        (xy 0.352 -3.054)
        (xy 0.361 -3.01)
        (xy 0.371 -2.958)
        (xy 0.382 -2.897)
        (xy 0.385 -2.878)
        (xy 0.395 -2.824)
        (xy 0.405 -2.772)
        (xy 0.414 -2.724)
        (xy 0.423 -2.68)
        (xy 0.43 -2.642)
        (xy 0.437 -2.61)
        (xy 0.442 -2.586)
        (xy 0.446 -2.569)
        (xy 0.448 -2.562)
        (xy 0.456 -2.55)
        (xy 0.464 -2.544)
        (xy 0.476 -2.539)
        (xy 0.495 -2.53)
        (xy 0.521 -2.519)
        (xy 0.552 -2.506)
        (xy 0.587 -2.492)
        (xy 0.624 -2.477)
        (xy 0.664 -2.461)
        (xy 0.704 -2.445)
        (xy 0.743 -2.43)
        (xy 0.78 -2.415)
        (xy 0.814 -2.402)
        (xy 0.843 -2.391)
        (xy 0.868 -2.382)
        (xy 0.885 -2.376)
        (xy 0.895 -2.373)
        (xy 0.896 -2.373)
        (xy 0.911 -2.376)
        (xy 0.931 -2.386)
        (xy 0.948 -2.397)
        (xy 0.962 -2.406)
        (xy 0.983 -2.421)
        (xy 1.011 -2.44)
        (xy 1.043 -2.462)
        (xy 1.079 -2.487)
        (xy 1.118 -2.513)
        (xy 1.158 -2.541)
        (xy 1.198 -2.568)
        (xy 1.238 -2.595)
        (xy 1.275 -2.621)
        (xy 1.309 -2.644)
        (xy 1.338 -2.665)
        (xy 1.362 -2.681)
        (xy 1.377 -2.691)
        (xy 1.398 -2.705)
        (xy 1.418 -2.717)
        (xy 1.433 -2.725)
        (xy 1.442 -2.728)
        (xy 1.443 -2.728)
        (xy 1.448 -2.726)
        (xy 1.456 -2.72)
        (xy 1.468 -2.71)
        (xy 1.486 -2.694)
        (xy 1.508 -2.673)
        (xy 1.535 -2.647)
        (xy 1.568 -2.614)
        (xy 1.608 -2.575)
        (xy 1.654 -2.53)
        (xy 1.675 -2.509)
        (xy 1.721 -2.462)
        (xy 1.761 -2.422)
        (xy 1.794 -2.388)
        (xy 1.822 -2.36)
        (xy 1.844 -2.337)
        (xy 1.862 -2.318)
        (xy 1.875 -2.304)
        (xy 1.884 -2.293)
        (xy 1.89 -2.284)
        (xy 1.893 -2.279)
        (xy 1.894 -2.275)
        (xy 1.892 -2.269)
        (xy 1.886 -2.257)
        (xy 1.875 -2.239)
        (xy 1.86 -2.215)
        (xy 1.839 -2.183)
        (xy 1.814 -2.145)
        (xy 1.783 -2.1)
        (xy 1.747 -2.046)
        (xy 1.721 -2.009)
        (xy 1.69 -1.964)
        (xy 1.661 -1.921)
        (xy 1.634 -1.88)
        (xy 1.609 -1.844)
        (xy 1.588 -1.811)
        (xy 1.57 -1.785)
        (xy 1.557 -1.764)
        (xy 1.549 -1.75)
        (xy 1.546 -1.743)
        (xy 1.547 -1.735)
        (xy 1.552 -1.719)
        (xy 1.56 -1.696)
        (xy 1.571 -1.667)
        (xy 1.585 -1.634)
        (xy 1.6 -1.597)
        (xy 1.616 -1.557)
        (xy 1.633 -1.516)
        (xy 1.651 -1.476)
        (xy 1.668 -1.436)
        (xy 1.685 -1.398)
        (xy 1.701 -1.363)
        (xy 1.715 -1.333)
        (xy 1.727 -1.309)
        (xy 1.736 -1.291)
        (xy 1.742 -1.281)
        (xy 1.744 -1.279)
        (xy 1.751 -1.277)
        (xy 1.767 -1.273)
        (xy 1.791 -1.268)
        (xy 1.822 -1.261)
        (xy 1.86 -1.254)
        (xy 1.903 -1.245)
        (xy 1.951 -1.236)
        (xy 2.002 -1.226)
        (xy 2.049 -1.217)
        (xy 2.103 -1.207)
        (xy 2.154 -1.198)
        (xy 2.201 -1.188)
        (xy 2.244 -1.18)
        (xy 2.281 -1.173)
        (xy 2.311 -1.166)
        (xy 2.335 -1.161)
        (xy 2.35 -1.157)
        (xy 2.355 -1.156)
        (xy 2.367 -1.148)
        (xy 2.367 -0.834)
        (xy 2.367 -0.768)
        (xy 2.367 -0.712)
        (xy 2.367 -0.664)
        (xy 2.366 -0.625)
        (xy 2.366 -0.592)
        (xy 2.365 -0.566)
        (xy 2.364 -0.546)
        (xy 2.363 -0.531)
        (xy 2.361 -0.52)
        (xy 2.358 -0.512)
        (xy 2.355 -0.507)
        (xy 2.352 -0.504)
        (xy 2.348 -0.503)
        (xy 2.343 -0.501)
        (xy 2.34 -0.501)
        (xy 2.333 -0.499)
        (xy 2.317 -0.496)
        (xy 2.293 -0.492)
        (xy 2.261 -0.486)
        (xy 2.224 -0.479)
        (xy 2.181 -0.471)
        (xy 2.134 -0.462)
        (xy 2.084 -0.453)
        (xy 2.054 -0.448)
        (xy 2.002 -0.438)
        (xy 1.953 -0.429)
        (xy 1.907 -0.42)
        (xy 1.866 -0.412)
        (xy 1.831 -0.404)
        (xy 1.802 -0.398)
        (xy 1.78 -0.394)
        (xy 1.767 -0.391)
        (xy 1.764 -0.39)
        (xy 1.76 -0.387)
        (xy 1.757 -0.384)
        (xy 1.753 -0.379)
        (xy 1.748 -0.371)
        (xy 1.742 -0.36)
        (xy 1.735 -0.344)
        (xy 1.726 -0.324)
        (xy 1.715 -0.297)
        (xy 1.701 -0.264)
        (xy 1.685 -0.223)
        (xy 1.665 -0.174)
        (xy 1.653 -0.145)
        (xy 1.63 -0.086)
        (xy 1.61 -0.037)
        (xy 1.594 0.005)
        (xy 1.582 0.038)
        (xy 1.572 0.064)
        (xy 1.566 0.084)
        (xy 1.562 0.097)
        (xy 1.561 0.104)
        (xy 1.562 0.105)
        (xy 1.565 0.111)
        (xy 1.574 0.125)
        (xy 1.587 0.146)
        (xy 1.604 0.173)
        (xy 1.626 0.205)
        (xy 1.65 0.241)
        (xy 1.677 0.281)
        (xy 1.706 0.324)
        (xy 1.729 0.358)
        (xy 1.768 0.413)
        (xy 1.8 0.461)
        (xy 1.827 0.502)
        (xy 1.85 0.535)
        (xy 1.867 0.562)
        (xy 1.88 0.583)
        (xy 1.889 0.598)
        (xy 1.893 0.608)
        (xy 1.894 0.612)
        (xy 1.893 0.616)
        (xy 1.89 0.622)
        (xy 1.885 0.63)
        (xy 1.876 0.64)
        (xy 1.863 0.655)
        (xy 1.846 0.673)
        (xy 1.825 0.695)
        (xy 1.798 0.723)
        (xy 1.765 0.756)
        (xy 1.727 0.795)
        (xy 1.682 0.839)
        (xy 1.635 0.886)
        (xy 1.595 0.926)
        (xy 1.561 0.96)
        (xy 1.532 0.989)
        (xy 1.508 1.012)
        (xy 1.488 1.03)
        (xy 1.473 1.044)
        (xy 1.461 1.054)
        (xy 1.452 1.061)
        (xy 1.445 1.065)
        (xy 1.44 1.066)
        (xy 1.438 1.066)
        (xy 1.433 1.064)
        (xy 1.421 1.055)
        (xy 1.401 1.043)
        (xy 1.376 1.026)
        (xy 1.345 1.005)
        (xy 1.31 0.981)
        (xy 1.27 0.954)
        (xy 1.228 0.925)
        (xy 1.193 0.901)
        (xy 1.138 0.864)
        (xy 1.089 0.83)
        (xy 1.046 0.802)
        (xy 1.01 0.778)
        (xy 0.981 0.759)
        (xy 0.96 0.746)
        (xy 0.946 0.738)
        (xy 0.94 0.736)
        (xy 0.932 0.738)
        (xy 0.917 0.745)
        (xy 0.895 0.755)
        (xy 0.869 0.768)
        (xy 0.84 0.783)
        (xy 0.816 0.795)
        (xy 0.781 0.814)
        (xy 0.753 0.828)
        (xy 0.732 0.838)
        (xy 0.717 0.845)
        (xy 0.707 0.849)
        (xy 0.699 0.85)
        (xy 0.694 0.849)
        (xy 0.691 0.847)
        (xy 0.687 0.84)
        (xy 0.682 0.829)
        (xy 0.674 0.814)
        (xy 0.665 0.793)
        (xy 0.653 0.767)
        (xy 0.639 0.735)
        (xy 0.623 0.696)
        (xy 0.604 0.651)
        (xy 0.582 0.598)
        (xy 0.556 0.538)
        (xy 0.528 0.469)
        (xy 0.496 0.391)
        (xy 0.47 0.329)
        (xy 0.436 0.247)
        (xy 0.406 0.173)
        (xy 0.379 0.108)
        (xy 0.355 0.05)
        (xy 0.335 0)
        (xy 0.317 -0.043)
        (xy 0.303 -0.079)
        (xy 0.291 -0.11)
        (xy 0.281 -0.135)
        (xy 0.273 -0.155)
        (xy 0.268 -0.171)
        (xy 0.264 -0.183)
        (xy 0.262 -0.191)
        (xy 0.262 -0.196)
        (xy 0.262 -0.198)
        (xy 0.269 -0.207)
        (xy 0.283 -0.219)
        (xy 0.302 -0.233)
        (xy 0.303 -0.234)
        (xy 0.354 -0.268)
        (xy 0.398 -0.3)
        (xy 0.435 -0.331)
        (xy 0.469 -0.363)
        (xy 0.5 -0.397)
        (xy 0.507 -0.405)
        (xy 0.556 -0.472)
        (xy 0.596 -0.543)
        (xy 0.627 -0.619)
        (xy 0.643 -0.672)
        (xy 0.651 -0.718)
        (xy 0.657 -0.77)
        (xy 0.66 -0.824)
        (xy 0.659 -0.878)
        (xy 0.654 -0.927)
        (xy 0.652 -0.936)
        (xy 0.634 -1.015)
        (xy 0.607 -1.09)
        (xy 0.571 -1.161)
        (xy 0.528 -1.227)
        (xy 0.477 -1.287)
        (xy 0.419 -1.341)
        (xy 0.355 -1.387)
        (xy 0.285 -1.426)
        (xy 0.21 -1.456)
        (xy 0.205 -1.458)
        (xy 0.131 -1.477)
        (xy 0.054 -1.487)
        (xy -0.025 -1.489)
        (xy -0.103 -1.482)
        (xy -0.178 -1.466)
        (xy -0.206 -1.458)
        (xy -0.281 -1.428)
        (xy -0.351 -1.39)
        (xy -0.416 -1.344)
        (xy -0.474 -1.29)
        (xy -0.526 -1.23)
        (xy -0.571 -1.164)
        (xy -0.607 -1.093)
        (xy -0.63 -1.034)
        (xy -0.649 -0.96)
        (xy -0.659 -0.883)
        (xy -0.661 -0.804)
        (xy -0.654 -0.726)
        (xy -0.638 -0.651)
        (xy -0.63 -0.623)
        (xy -0.618 -0.591)
        (xy -0.602 -0.554)
        (xy -0.584 -0.518)
        (xy -0.566 -0.485)
        (xy -0.553 -0.463)
        (xy -0.509 -0.407)
        (xy -0.457 -0.352)
        (xy -0.397 -0.299)
        (xy -0.33 -0.25)
        (xy -0.289 -0.224)
        (xy -0.273 -0.212)
        (xy -0.263 -0.2)
        (xy -0.262 -0.197)
        (xy -0.263 -0.19)
        (xy -0.268 -0.175)
        (xy -0.277 -0.151)
        (xy -0.288 -0.121)
        (xy -0.302 -0.084)
        (xy -0.319 -0.042)
        (xy -0.338 0.005)
        (xy -0.358 0.056)
        (xy -0.381 0.111)
        (xy -0.404 0.168)
        (xy -0.428 0.228)
        (xy -0.453 0.288)
        (xy -0.478 0.349)
        (xy -0.504 0.41)
        (xy -0.529 0.47)
        (xy -0.553 0.527)
        (xy -0.576 0.583)
        (xy -0.598 0.635)
        (xy -0.619 0.683)
        (xy -0.638 0.727)
        (xy -0.655 0.765)
        (xy -0.669 0.797)
        (xy -0.68 0.822)
        (xy -0.689 0.839)
        (xy -0.694 0.848)
        (xy -0.695 0.849)
        (xy -0.699 0.85)
        (xy -0.706 0.849)
        (xy -0.717 0.845)
        (xy -0.732 0.839)
        (xy -0.752 0.829)
        (xy -0.779 0.815)
        (xy -0.814 0.797)
        (xy -0.817 0.795)
        (xy -0.848 0.779)
        (xy -0.877 0.764)
        (xy -0.902 0.752)
        (xy -0.922 0.743)
        (xy -0.936 0.737)
        (xy -0.941 0.736)
        (xy -0.949 0.739)
        (xy -0.964 0.748)
        (xy -0.987 0.761)
        (xy -1.015 0.78)
        (xy -1.05 0.803)
        (xy -1.072 0.818)
        (xy -1.138 0.863)
        (xy -1.195 0.903)
        (xy -1.245 0.937)
        (xy -1.289 0.966)
        (xy -1.325 0.991)
        (xy -1.356 1.012)
        (xy -1.381 1.029)
        (xy -1.401 1.042)
        (xy -1.416 1.052)
        (xy -1.427 1.059)
        (xy -1.435 1.064)
        (xy -1.439 1.066)
        (xy -1.44 1.066)
        (xy -1.449 1.064)
        (xy -1.453 1.061)
        (xy -1.458 1.057)
        (xy -1.47 1.046)
        (xy -1.487 1.029)
        (xy -1.509 1.007)
        (xy -1.537 0.98)
        (xy -1.568 0.95)
        (xy -1.602 0.915)
        (xy -1.639 0.879)
        (xy -1.678 0.84)
        (xy -1.678 0.839)
        (xy -1.726 0.792)
        (xy -1.767 0.751)
        (xy -1.801 0.716)
        (xy -1.829 0.687)
        (xy -1.852 0.663)
        (xy -1.869 0.644)
        (xy -1.882 0.63)
        (xy -1.89 0.62)
        (xy -1.894 0.613)
        (xy -1.895 0.61)
        (xy -1.892 0.603)
        (xy -1.884 0.588)
        (xy -1.87 0.565)
        (xy -1.85 0.536)
        (xy -1.826 0.499)
        (xy -1.797 0.455)
        (xy -1.763 0.405)
        (xy -1.73 0.358)
        (xy -1.7 0.313)
        (xy -1.671 0.271)
        (xy -1.645 0.232)
        (xy -1.621 0.197)
        (xy -1.601 0.166)
        (xy -1.584 0.141)
        (xy -1.572 0.121)
        (xy -1.565 0.109)
        (xy -1.563 0.105)
        (xy -1.563 0.099)
        (xy -1.566 0.087)
        (xy -1.572 0.07)
        (xy -1.58 0.045)
        (xy -1.592 0.013)
        (xy -1.607 -0.026)
        (xy -1.626 -0.074)
        (xy -1.648 -0.13)
        (xy -1.654 -0.145)
        (xy -1.676 -0.199)
        (xy -1.695 -0.245)
        (xy -1.71 -0.282)
        (xy -1.723 -0.313)
        (xy -1.733 -0.337)
        (xy -1.741 -0.356)
        (xy -1.748 -0.369)
        (xy -1.753 -0.379)
        (xy -1.758 -0.385)
        (xy -1.761 -0.388)
        (xy -1.763 -0.389)
        (xy -1.767 -0.39)
        (xy -1.774 -0.392)
        (xy -1.784 -0.395)
        (xy -1.799 -0.398)
        (xy -1.818 -0.402)
        (xy -1.843 -0.407)
        (xy -1.873 -0.413)
        (xy -1.91 -0.42)
        (xy -1.954 -0.429)
        (xy -2.005 -0.438)
        (xy -2.065 -0.449)
        (xy -2.133 -0.462)
        (xy -2.211 -0.477)
        (xy -2.22 -0.478)
        (xy -2.26 -0.486)
        (xy -2.29 -0.491)
        (xy -2.313 -0.496)
        (xy -2.33 -0.499)
        (xy -2.341 -0.502)
        (xy -2.349 -0.504)
        (xy -2.353 -0.506)
        (xy -2.356 -0.508)
        (xy -2.359 -0.51)
        (xy -2.36 -0.511)
        (xy -2.361 -0.514)
        (xy -2.363 -0.518)
        (xy -2.364 -0.526)
        (xy -2.365 -0.536)
        (xy -2.366 -0.551)
        (xy -2.366 -0.571)
        (xy -2.367 -0.597)
        (xy -2.367 -0.629)
        (xy -2.368 -0.668)
        (xy -2.368 -0.715)
        (xy -2.368 -0.771)
        (xy -2.368 -0.834)
        (xy -2.368 -1.148)
        (xy -2.356 -1.155)
        (xy -2.349 -1.158)
        (xy -2.333 -1.162)
        (xy -2.309 -1.167)
        (xy -2.278 -1.173)
        (xy -2.24 -1.181)
        (xy -2.197 -1.189)
        (xy -2.149 -1.198)
        (xy -2.098 -1.208)
        (xy -2.051 -1.217)
        (xy -1.996 -1.227)
        (xy -1.945 -1.237)
        (xy -1.897 -1.246)
        (xy -1.854 -1.254)
        (xy -1.817 -1.262)
        (xy -1.787 -1.268)
        (xy -1.764 -1.273)
        (xy -1.75 -1.277)
        (xy -1.745 -1.279)
        (xy -1.741 -1.285)
        (xy -1.733 -1.3)
        (xy -1.722 -1.322)
        (xy -1.709 -1.35)
        (xy -1.694 -1.382)
        (xy -1.677 -1.419)
        (xy -1.66 -1.458)
        (xy -1.642 -1.498)
        (xy -1.625 -1.539)
        (xy -1.608 -1.58)
        (xy -1.592 -1.618)
        (xy -1.578 -1.653)
        (xy -1.565 -1.684)
        (xy -1.556 -1.709)
        (xy -1.549 -1.729)
        (xy -1.546 -1.74)
        (xy -1.546 -1.742)
        (xy -1.549 -1.749)
        (xy -1.558 -1.763)
        (xy -1.571 -1.784)
        (xy -1.588 -1.811)
        (xy -1.61 -1.843)
        (xy -1.634 -1.88)
        (xy -1.661 -1.92)
        (xy -1.691 -1.963)
        (xy -1.722 -2.008)
        (xy -1.762 -2.067)
        (xy -1.796 -2.117)
        (xy -1.825 -2.16)
        (xy -1.848 -2.196)
        (xy -1.867 -2.225)
        (xy -1.881 -2.247)
        (xy -1.89 -2.262)
        (xy -1.895 -2.272)
        (xy -1.895 -2.275)
        (xy -1.894 -2.279)
        (xy -1.891 -2.285)
        (xy -1.884 -2.293)
        (xy -1.875 -2.305)
        (xy -1.861 -2.32)
        (xy -1.843 -2.339)
        (xy -1.82 -2.363)
        (xy -1.792 -2.392)
        (xy -1.758 -2.426)
        (xy -1.718 -2.466)
        (xy -1.676 -2.509)
        (xy -1.627 -2.557)
        (xy -1.585 -2.599)
        (xy -1.549 -2.634)
        (xy -1.52 -2.663)
        (xy -1.495 -2.686)
        (xy -1.476 -2.704)
        (xy -1.462 -2.716)
        (xy -1.452 -2.724)
        (xy -1.446 -2.728)
        (xy -1.444 -2.728)
        (xy -1.437 -2.726)
        (xy -1.423 -2.717)
        (xy -1.401 -2.703)
        (xy -1.372 -2.685)
        (xy -1.337 -2.661)
        (xy -1.295 -2.634)
        (xy -1.248 -2.602)
        (xy -1.196 -2.566)
        (xy -1.173 -2.551)
        (xy -1.118 -2.513)
        (xy -1.071 -2.481)
        (xy -1.031 -2.454)
        (xy -0.998 -2.432)
        (xy -0.97 -2.413)
        (xy -0.948 -2.399)
        (xy -0.931 -2.389)
        (xy -0.917 -2.381)
        (xy -0.907 -2.376)
        (xy -0.901 -2.373)
        (xy -0.897 -2.373)
        (xy -0.888 -2.375)
        (xy -0.87 -2.38)
        (xy -0.845 -2.39)
        (xy -0.813 -2.402)
        (xy -0.774 -2.417)
        (xy -0.73 -2.434)
        (xy -0.681 -2.454)
        (xy -0.629 -2.475)
        (xy -0.586 -2.493)
        (xy -0.55 -2.508)
        (xy -0.522 -2.52)
        (xy -0.499 -2.529)
        (xy -0.482 -2.537)
        (xy -0.47 -2.543)
        (xy -0.461 -2.548)
        (xy -0.455 -2.551)
        (xy -0.452 -2.554)
        (xy -0.449 -2.557)
        (xy -0.448 -2.56)
        (xy -0.447 -2.566)
        (xy -0.443 -2.582)
        (xy -0.438 -2.605)
        (xy -0.432 -2.637)
        (xy -0.425 -2.674)
        (xy -0.417 -2.717)
        (xy -0.407 -2.765)
        (xy -0.398 -2.817)
        (xy -0.388 -2.871)
        (xy -0.387 -2.876)
        (xy -0.375 -2.94)
        (xy -0.364 -2.995)
        (xy -0.356 -3.042)
        (xy -0.348 -3.081)
        (xy -0.342 -3.112)
        (xy -0.337 -3.137)
        (xy -0.332 -3.157)
        (xy -0.328 -3.171)
        (xy -0.325 -3.181)
        (xy -0.323 -3.188)
        (xy -0.32 -3.191)
        (xy -0.32 -3.192)
        (xy -0.317 -3.194)
        (xy -0.313 -3.195)
        (xy -0.307 -3.197)
        (xy -0.298 -3.198)
        (xy -0.286 -3.199)
        (xy -0.269 -3.199)
        (xy -0.247 -3.2)
        (xy -0.219 -3.2)
        (xy -0.184 -3.201)
        (xy -0.142 -3.201)
        (xy -0.092 -3.201)
        (xy -0.033 -3.201)
        (xy -0.001 -3.201)
        (xy 0.063 -3.201)
      )

      (stroke (width 0.01) (type solid)) (fill solid) (layer "F.Cu"))
    (fp_poly
      (pts
        (xy -0.843 2.558)
        (xy -0.815 2.564)
        (xy -0.794 2.572)
        (xy -0.773 2.581)
        (xy -0.759 2.589)
        (xy -0.738 2.603)
        (xy -0.783 2.658)
        (xy -0.8 2.677)
        (xy -0.814 2.694)
        (xy -0.825 2.706)
        (xy -0.831 2.712)
        (xy -0.832 2.712)
        (xy -0.837 2.71)
        (xy -0.847 2.703)
        (xy -0.849 2.702)
        (xy -0.874 2.69)
        (xy -0.904 2.684)
        (xy -0.935 2.685)
        (xy -0.942 2.686)
        (xy -0.975 2.698)
        (xy -1.001 2.717)
        (xy -1.02 2.741)
        (xy -1.034 2.766)
        (xy -1.039 3.197)
        (xy -1.164 3.2)
        (xy -1.164 2.565)
        (xy -1.037 2.565)
        (xy -1.037 2.626)
        (xy -1.009 2.604)
        (xy -0.972 2.579)
        (xy -0.931 2.563)
        (xy -0.887 2.556)
        (xy -0.843 2.558)
      )

      (stroke (width 0.01) (type solid)) (fill solid) (layer "F.Mask"))
    (fp_poly
      (pts
        (xy 1.889 1.554)
        (xy 1.907 1.559)
        (xy 1.927 1.566)
        (xy 1.948 1.574)
        (xy 1.966 1.583)
        (xy 1.979 1.592)
        (xy 1.984 1.597)
        (xy 1.982 1.604)
        (xy 1.974 1.616)
        (xy 1.962 1.633)
        (xy 1.946 1.652)
        (xy 1.945 1.654)
        (xy 1.929 1.673)
        (xy 1.915 1.689)
        (xy 1.906 1.7)
        (xy 1.901 1.706)
        (xy 1.896 1.705)
        (xy 1.885 1.7)
        (xy 1.873 1.695)
        (xy 1.84 1.683)
        (xy 1.808 1.68)
        (xy 1.776 1.685)
        (xy 1.747 1.698)
        (xy 1.723 1.717)
        (xy 1.704 1.742)
        (xy 1.696 1.763)
        (xy 1.695 1.772)
        (xy 1.694 1.79)
        (xy 1.693 1.817)
        (xy 1.692 1.85)
        (xy 1.692 1.89)
        (xy 1.691 1.934)
        (xy 1.691 1.983)
        (xy 1.691 2.194)
        (xy 1.559 2.194)
        (xy 1.559 1.559)
        (xy 1.691 1.559)
        (xy 1.691 1.626)
        (xy 1.71 1.607)
        (xy 1.739 1.585)
        (xy 1.775 1.568)
        (xy 1.814 1.556)
        (xy 1.855 1.552)
        (xy 1.889 1.554)
      )

      (stroke (width 0.01) (type solid)) (fill solid) (layer "F.Mask"))
    (fp_poly
      (pts
        (xy -0.837 1.56)
        (xy -0.797 1.576)
        (xy -0.761 1.6)
        (xy -0.73 1.63)
        (xy -0.706 1.667)
        (xy -0.69 1.709)
        (xy -0.687 1.721)
        (xy -0.685 1.734)
        (xy -0.684 1.757)
        (xy -0.683 1.79)
        (xy -0.682 1.833)
        (xy -0.681 1.884)
        (xy -0.681 1.945)
        (xy -0.681 1.971)
        (xy -0.681 2.194)
        (xy -0.808 2.194)
        (xy -0.809 1.984)
        (xy -0.811 1.774)
        (xy -0.826 1.744)
        (xy -0.845 1.716)
        (xy -0.868 1.697)
        (xy -0.897 1.686)
        (xy -0.925 1.682)
        (xy -0.947 1.682)
        (xy -0.967 1.684)
        (xy -0.979 1.686)
        (xy -1.001 1.698)
        (xy -1.023 1.716)
        (xy -1.041 1.738)
        (xy -1.049 1.752)
        (xy -1.052 1.758)
        (xy -1.054 1.765)
        (xy -1.056 1.773)
        (xy -1.057 1.783)
        (xy -1.058 1.797)
        (xy -1.059 1.815)
        (xy -1.06 1.839)
        (xy -1.06 1.869)
        (xy -1.061 1.907)
        (xy -1.061 1.953)
        (xy -1.061 1.985)
        (xy -1.063 2.194)
        (xy -1.189 2.194)
        (xy -1.189 1.559)
        (xy -1.062 1.559)
        (xy -1.062 1.625)
        (xy -1.033 1.602)
        (xy -1.001 1.579)
        (xy -0.969 1.564)
        (xy -0.934 1.555)
        (xy -0.927 1.554)
        (xy -0.881 1.553)
        (xy -0.837 1.56)
      )

      (stroke (width 0.01) (type solid)) (fill solid) (layer "F.Mask"))
    (fp_poly
      (pts
        (xy 1.042 1.769)
        (xy 1.043 1.979)
        (xy 1.059 2.009)
        (xy 1.077 2.036)
        (xy 1.1 2.056)
        (xy 1.129 2.067)
        (xy 1.159 2.071)
        (xy 1.193 2.07)
        (xy 1.221 2.063)
        (xy 1.245 2.047)
        (xy 1.258 2.034)
        (xy 1.266 2.025)
        (xy 1.273 2.016)
        (xy 1.278 2.008)
        (xy 1.282 1.997)
        (xy 1.286 1.985)
        (xy 1.288 1.969)
        (xy 1.29 1.948)
        (xy 1.291 1.922)
        (xy 1.292 1.89)
        (xy 1.293 1.85)
        (xy 1.293 1.801)
        (xy 1.294 1.766)
        (xy 1.295 1.559)
        (xy 1.422 1.559)
        (xy 1.422 2.194)
        (xy 1.295 2.194)
        (xy 1.295 2.161)
        (xy 1.295 2.144)
        (xy 1.293 2.132)
        (xy 1.292 2.128)
        (xy 1.287 2.131)
        (xy 1.278 2.14)
        (xy 1.271 2.147)
        (xy 1.256 2.159)
        (xy 1.236 2.171)
        (xy 1.219 2.181)
        (xy 1.202 2.188)
        (xy 1.186 2.193)
        (xy 1.17 2.196)
        (xy 1.148 2.197)
        (xy 1.135 2.198)
        (xy 1.107 2.198)
        (xy 1.087 2.197)
        (xy 1.07 2.194)
        (xy 1.059 2.19)
        (xy 1.036 2.181)
        (xy 1.019 2.172)
        (xy 1.003 2.161)
        (xy 0.985 2.146)
        (xy 0.981 2.141)
        (xy 0.952 2.107)
        (xy 0.931 2.068)
        (xy 0.92 2.033)
        (xy 0.918 2.019)
        (xy 0.917 1.996)
        (xy 0.916 1.963)
        (xy 0.915 1.92)
        (xy 0.914 1.869)
        (xy 0.914 1.808)
        (xy 0.914 1.782)
        (xy 0.914 1.559)
        (xy 1.04 1.559)
        (xy 1.042 1.769)
      )

      (stroke (width 0.01) (type solid)) (fill solid) (layer "F.Mask"))
    (fp_poly
      (pts
        (xy 1.753 2.563)
        (xy 1.768 2.568)
        (xy 1.787 2.577)
        (xy 1.804 2.586)
        (xy 1.818 2.595)
        (xy 1.826 2.602)
        (xy 1.827 2.606)
        (xy 1.824 2.611)
        (xy 1.815 2.621)
        (xy 1.803 2.636)
        (xy 1.789 2.654)
        (xy 1.775 2.671)
        (xy 1.761 2.688)
        (xy 1.749 2.701)
        (xy 1.742 2.71)
        (xy 1.739 2.712)
        (xy 1.735 2.71)
        (xy 1.724 2.704)
        (xy 1.713 2.698)
        (xy 1.697 2.69)
        (xy 1.682 2.686)
        (xy 1.664 2.685)
        (xy 1.653 2.685)
        (xy 1.618 2.688)
        (xy 1.59 2.699)
        (xy 1.566 2.718)
        (xy 1.561 2.723)
        (xy 1.554 2.732)
        (xy 1.548 2.74)
        (xy 1.544 2.748)
        (xy 1.54 2.758)
        (xy 1.537 2.769)
        (xy 1.534 2.785)
        (xy 1.533 2.804)
        (xy 1.532 2.829)
        (xy 1.531 2.861)
        (xy 1.53 2.899)
        (xy 1.53 2.947)
        (xy 1.53 2.988)
        (xy 1.528 3.2)
        (xy 1.468 3.2)
        (xy 1.444 3.2)
        (xy 1.425 3.199)
        (xy 1.411 3.198)
        (xy 1.405 3.197)
        (xy 1.404 3.191)
        (xy 1.404 3.176)
        (xy 1.403 3.153)
        (xy 1.403 3.122)
        (xy 1.402 3.085)
        (xy 1.402 3.042)
        (xy 1.402 2.993)
        (xy 1.402 2.941)
        (xy 1.402 2.886)
        (xy 1.402 2.565)
        (xy 1.529 2.565)
        (xy 1.529 2.595)
        (xy 1.529 2.611)
        (xy 1.53 2.623)
        (xy 1.532 2.626)
        (xy 1.537 2.623)
        (xy 1.547 2.615)
        (xy 1.554 2.608)
        (xy 1.588 2.584)
        (xy 1.627 2.567)
        (xy 1.669 2.558)
        (xy 1.712 2.556)
        (xy 1.753 2.563)
      )

      (stroke (width 0.01) (type solid)) (fill solid) (layer "F.Mask"))
    (fp_poly
      (pts
        (xy 2.316 1.557)
        (xy 2.365 1.57)
        (xy 2.41 1.593)
        (xy 2.453 1.625)
        (xy 2.46 1.631)
        (xy 2.491 1.661)
        (xy 2.466 1.684)
        (xy 2.448 1.699)
        (xy 2.43 1.715)
        (xy 2.419 1.725)
        (xy 2.397 1.743)
        (xy 2.376 1.724)
        (xy 2.345 1.701)
        (xy 2.312 1.687)
        (xy 2.274 1.681)
        (xy 2.265 1.681)
        (xy 2.226 1.684)
        (xy 2.195 1.693)
        (xy 2.167 1.708)
        (xy 2.159 1.715)
        (xy 2.136 1.741)
        (xy 2.118 1.776)
        (xy 2.107 1.817)
        (xy 2.103 1.866)
        (xy 2.103 1.876)
        (xy 2.106 1.926)
        (xy 2.116 1.97)
        (xy 2.132 2.006)
        (xy 2.155 2.034)
        (xy 2.184 2.055)
        (xy 2.219 2.067)
        (xy 2.259 2.072)
        (xy 2.274 2.071)
        (xy 2.309 2.066)
        (xy 2.339 2.056)
        (xy 2.366 2.038)
        (xy 2.377 2.028)
        (xy 2.386 2.02)
        (xy 2.393 2.016)
        (xy 2.4 2.015)
        (xy 2.409 2.018)
        (xy 2.42 2.027)
        (xy 2.436 2.041)
        (xy 2.456 2.059)
        (xy 2.491 2.092)
        (xy 2.476 2.108)
        (xy 2.449 2.132)
        (xy 2.416 2.155)
        (xy 2.38 2.174)
        (xy 2.35 2.186)
        (xy 2.327 2.193)
        (xy 2.306 2.197)
        (xy 2.283 2.199)
        (xy 2.259 2.199)
        (xy 2.233 2.198)
        (xy 2.209 2.196)
        (xy 2.189 2.193)
        (xy 2.182 2.191)
        (xy 2.133 2.173)
        (xy 2.089 2.146)
        (xy 2.053 2.112)
        (xy 2.023 2.071)
        (xy 2.012 2.051)
        (xy 2 2.023)
        (xy 1.991 1.999)
        (xy 1.984 1.975)
        (xy 1.981 1.948)
        (xy 1.979 1.917)
        (xy 1.978 1.879)
        (xy 1.978 1.877)
        (xy 1.979 1.838)
        (xy 1.98 1.806)
        (xy 1.984 1.78)
        (xy 1.99 1.756)
        (xy 1.999 1.731)
        (xy 2.011 1.704)
        (xy 2.012 1.701)
        (xy 2.039 1.657)
        (xy 2.072 1.62)
        (xy 2.111 1.591)
        (xy 2.156 1.57)
        (xy 2.207 1.557)
        (xy 2.263 1.552)
        (xy 2.316 1.557)
      )

      (stroke (width 0.01) (type solid)) (fill solid) (layer "F.Mask"))
    (fp_poly
      (pts
        (xy -1.494 1.56)
        (xy -1.447 1.576)
        (xy -1.405 1.6)
        (xy -1.368 1.633)
        (xy -1.341 1.668)
        (xy -1.326 1.692)
        (xy -1.316 1.716)
        (xy -1.308 1.743)
        (xy -1.302 1.774)
        (xy -1.299 1.811)
        (xy -1.297 1.845)
        (xy -1.294 1.925)
        (xy -1.692 1.925)
        (xy -1.692 1.942)
        (xy -1.687 1.977)
        (xy -1.673 2.011)
        (xy -1.65 2.039)
        (xy -1.626 2.059)
        (xy -1.601 2.071)
        (xy -1.572 2.078)
        (xy -1.537 2.079)
        (xy -1.497 2.074)
        (xy -1.458 2.06)
        (xy -1.422 2.036)
        (xy -1.421 2.036)
        (xy -1.402 2.021)
        (xy -1.359 2.057)
        (xy -1.342 2.072)
        (xy -1.327 2.085)
        (xy -1.317 2.094)
        (xy -1.314 2.098)
        (xy -1.316 2.103)
        (xy -1.324 2.113)
        (xy -1.338 2.126)
        (xy -1.354 2.139)
        (xy -1.372 2.152)
        (xy -1.389 2.163)
        (xy -1.399 2.168)
        (xy -1.421 2.178)
        (xy -1.445 2.187)
        (xy -1.461 2.191)
        (xy -1.488 2.196)
        (xy -1.522 2.199)
        (xy -1.557 2.199)
        (xy -1.591 2.196)
        (xy -1.62 2.192)
        (xy -1.629 2.19)
        (xy -1.677 2.171)
        (xy -1.718 2.146)
        (xy -1.752 2.114)
        (xy -1.779 2.074)
        (xy -1.8 2.026)
        (xy -1.802 2.02)
        (xy -1.81 1.989)
        (xy -1.815 1.951)
        (xy -1.818 1.908)
        (xy -1.819 1.865)
        (xy -1.818 1.823)
        (xy -1.816 1.804)
        (xy -1.692 1.804)
        (xy -1.692 1.818)
        (xy -1.428 1.818)
        (xy -1.428 1.801)
        (xy -1.432 1.775)
        (xy -1.442 1.748)
        (xy -1.457 1.722)
        (xy -1.469 1.707)
        (xy -1.495 1.688)
        (xy -1.526 1.676)
        (xy -1.56 1.672)
        (xy -1.593 1.676)
        (xy -1.619 1.685)
        (xy -1.646 1.704)
        (xy -1.668 1.73)
        (xy -1.683 1.76)
        (xy -1.691 1.792)
        (xy -1.692 1.804)
        (xy -1.816 1.804)
        (xy -1.814 1.786)
        (xy -1.812 1.777)
        (xy -1.797 1.724)
        (xy -1.775 1.676)
        (xy -1.747 1.636)
        (xy -1.713 1.603)
        (xy -1.673 1.578)
        (xy -1.629 1.561)
        (xy -1.597 1.554)
        (xy -1.544 1.552)
        (xy -1.494 1.56)
      )

      (stroke (width 0.01) (type solid)) (fill solid) (layer "F.Mask"))
    (fp_poly
      (pts
        (xy 2.835 1.557)
        (xy 2.883 1.57)
        (xy 2.926 1.592)
        (xy 2.964 1.621)
        (xy 2.996 1.657)
        (xy 3.021 1.699)
        (xy 3.038 1.747)
        (xy 3.04 1.757)
        (xy 3.043 1.776)
        (xy 3.045 1.802)
        (xy 3.047 1.832)
        (xy 3.047 1.858)
        (xy 3.047 1.925)
        (xy 2.65 1.925)
        (xy 2.653 1.951)
        (xy 2.663 1.991)
        (xy 2.68 2.024)
        (xy 2.703 2.049)
        (xy 2.733 2.067)
        (xy 2.77 2.077)
        (xy 2.801 2.079)
        (xy 2.845 2.075)
        (xy 2.883 2.063)
        (xy 2.916 2.042)
        (xy 2.92 2.039)
        (xy 2.929 2.031)
        (xy 2.935 2.026)
        (xy 2.941 2.025)
        (xy 2.949 2.027)
        (xy 2.959 2.034)
        (xy 2.974 2.047)
        (xy 2.994 2.064)
        (xy 3.01 2.078)
        (xy 3.023 2.088)
        (xy 3.03 2.095)
        (xy 3.032 2.096)
        (xy 3.03 2.1)
        (xy 3.022 2.11)
        (xy 3.01 2.122)
        (xy 3.009 2.123)
        (xy 2.98 2.147)
        (xy 2.945 2.169)
        (xy 2.906 2.185)
        (xy 2.887 2.191)
        (xy 2.861 2.196)
        (xy 2.828 2.198)
        (xy 2.793 2.198)
        (xy 2.759 2.197)
        (xy 2.729 2.193)
        (xy 2.721 2.191)
        (xy 2.675 2.175)
        (xy 2.634 2.15)
        (xy 2.599 2.118)
        (xy 2.569 2.077)
        (xy 2.547 2.029)
        (xy 2.536 1.996)
        (xy 2.532 1.973)
        (xy 2.529 1.942)
        (xy 2.527 1.906)
        (xy 2.527 1.869)
        (xy 2.528 1.832)
        (xy 2.529 1.818)
        (xy 2.65 1.818)
        (xy 2.922 1.818)
        (xy 2.918 1.799)
        (xy 2.908 1.758)
        (xy 2.891 1.725)
        (xy 2.869 1.7)
        (xy 2.84 1.683)
        (xy 2.826 1.678)
        (xy 2.788 1.672)
        (xy 2.753 1.675)
        (xy 2.722 1.687)
        (xy 2.695 1.706)
        (xy 2.674 1.734)
        (xy 2.659 1.768)
        (xy 2.654 1.794)
        (xy 2.65 1.818)
        (xy 2.529 1.818)
        (xy 2.53 1.798)
        (xy 2.534 1.769)
        (xy 2.536 1.76)
        (xy 2.554 1.707)
        (xy 2.578 1.662)
        (xy 2.609 1.624)
        (xy 2.645 1.593)
        (xy 2.687 1.571)
        (xy 2.734 1.557)
        (xy 2.783 1.553)
        (xy 2.835 1.557)
      )

      (stroke (width 0.01) (type solid)) (fill solid) (layer "F.Mask"))
    (fp_poly
      (pts
        (xy -2.733 1.557)
        (xy -2.685 1.57)
        (xy -2.642 1.592)
        (xy -2.604 1.622)
        (xy -2.581 1.649)
        (xy -2.562 1.676)
        (xy -2.548 1.706)
        (xy -2.537 1.739)
        (xy -2.53 1.777)
        (xy -2.527 1.821)
        (xy -2.526 1.873)
        (xy -2.527 1.907)
        (xy -2.529 1.956)
        (xy -2.534 1.997)
        (xy -2.542 2.031)
        (xy -2.553 2.06)
        (xy -2.567 2.086)
        (xy -2.587 2.111)
        (xy -2.603 2.129)
        (xy -2.637 2.158)
        (xy -2.673 2.178)
        (xy -2.714 2.192)
        (xy -2.76 2.198)
        (xy -2.789 2.199)
        (xy -2.813 2.198)
        (xy -2.835 2.196)
        (xy -2.852 2.194)
        (xy -2.857 2.194)
        (xy -2.898 2.179)
        (xy -2.937 2.155)
        (xy -2.97 2.126)
        (xy -2.993 2.101)
        (xy -3.011 2.077)
        (xy -3.024 2.051)
        (xy -3.034 2.022)
        (xy -3.041 1.988)
        (xy -3.045 1.947)
        (xy -3.047 1.91)
        (xy -3.047 1.882)
        (xy -2.919 1.882)
        (xy -2.919 1.968)
        (xy -2.903 2.001)
        (xy -2.885 2.031)
        (xy -2.863 2.051)
        (xy -2.837 2.064)
        (xy -2.804 2.07)
        (xy -2.779 2.07)
        (xy -2.755 2.069)
        (xy -2.737 2.065)
        (xy -2.722 2.058)
        (xy -2.717 2.055)
        (xy -2.697 2.041)
        (xy -2.681 2.025)
        (xy -2.67 2.004)
        (xy -2.662 1.978)
        (xy -2.657 1.945)
        (xy -2.654 1.903)
        (xy -2.654 1.899)
        (xy -2.653 1.848)
        (xy -2.656 1.806)
        (xy -2.662 1.772)
        (xy -2.673 1.744)
        (xy -2.687 1.722)
        (xy -2.707 1.705)
        (xy -2.723 1.695)
        (xy -2.755 1.684)
        (xy -2.788 1.68)
        (xy -2.821 1.684)
        (xy -2.851 1.695)
        (xy -2.877 1.713)
        (xy -2.892 1.729)
        (xy -2.901 1.745)
        (xy -2.908 1.76)
        (xy -2.913 1.778)
        (xy -2.916 1.8)
        (xy -2.918 1.828)
        (xy -2.919 1.864)
        (xy -2.919 1.882)
        (xy -3.047 1.882)
        (xy -3.048 1.844)
        (xy -3.043 1.786)
        (xy -3.034 1.736)
        (xy -3.021 1.695)
        (xy -3.004 1.664)
        (xy -2.972 1.624)
        (xy -2.935 1.594)
        (xy -2.893 1.571)
        (xy -2.846 1.558)
        (xy -2.794 1.553)
        (xy -2.787 1.553)
        (xy -2.733 1.557)
      )

      (stroke (width 0.01) (type solid)) (fill solid) (layer "F.Mask"))
    (fp_poly
      (pts
        (xy 2.148 2.561)
        (xy 2.193 2.574)
        (xy 2.235 2.595)
        (xy 2.273 2.623)
        (xy 2.304 2.657)
        (xy 2.326 2.691)
        (xy 2.338 2.718)
        (xy 2.346 2.745)
        (xy 2.352 2.774)
        (xy 2.355 2.808)
        (xy 2.357 2.85)
        (xy 2.357 2.858)
        (xy 2.357 2.931)
        (xy 1.96 2.931)
        (xy 1.963 2.955)
        (xy 1.973 2.993)
        (xy 1.991 3.026)
        (xy 2.015 3.053)
        (xy 2.039 3.069)
        (xy 2.057 3.076)
        (xy 2.08 3.08)
        (xy 2.103 3.082)
        (xy 2.144 3.081)
        (xy 2.18 3.071)
        (xy 2.214 3.054)
        (xy 2.227 3.045)
        (xy 2.24 3.035)
        (xy 2.25 3.029)
        (xy 2.253 3.027)
        (xy 2.258 3.03)
        (xy 2.269 3.039)
        (xy 2.284 3.05)
        (xy 2.3 3.064)
        (xy 2.315 3.078)
        (xy 2.329 3.09)
        (xy 2.338 3.099)
        (xy 2.341 3.103)
        (xy 2.337 3.11)
        (xy 2.327 3.121)
        (xy 2.312 3.134)
        (xy 2.294 3.148)
        (xy 2.276 3.161)
        (xy 2.259 3.171)
        (xy 2.252 3.175)
        (xy 2.204 3.192)
        (xy 2.152 3.202)
        (xy 2.098 3.204)
        (xy 2.046 3.198)
        (xy 2.032 3.195)
        (xy 1.984 3.178)
        (xy 1.943 3.154)
        (xy 1.909 3.123)
        (xy 1.881 3.084)
        (xy 1.859 3.037)
        (xy 1.847 3.003)
        (xy 1.841 2.972)
        (xy 1.838 2.934)
        (xy 1.836 2.893)
        (xy 1.837 2.851)
        (xy 1.839 2.824)
        (xy 1.96 2.824)
        (xy 2.23 2.824)
        (xy 2.23 2.813)
        (xy 2.225 2.783)
        (xy 2.214 2.753)
        (xy 2.196 2.725)
        (xy 2.175 2.702)
        (xy 2.151 2.686)
        (xy 2.128 2.68)
        (xy 2.101 2.677)
        (xy 2.072 2.678)
        (xy 2.051 2.683)
        (xy 2.023 2.696)
        (xy 2 2.717)
        (xy 1.981 2.746)
        (xy 1.968 2.779)
        (xy 1.963 2.8)
        (xy 1.96 2.824)
        (xy 1.839 2.824)
        (xy 1.839 2.811)
        (xy 1.844 2.776)
        (xy 1.848 2.76)
        (xy 1.866 2.708)
        (xy 1.889 2.663)
        (xy 1.919 2.627)
        (xy 1.954 2.598)
        (xy 1.996 2.575)
        (xy 2.007 2.571)
        (xy 2.054 2.559)
        (xy 2.101 2.556)
        (xy 2.148 2.561)
      )

      (stroke (width 0.01) (type solid)) (fill solid) (layer "F.Mask"))
    (fp_poly
      (pts
        (xy -0.229 3.2)
        (xy -0.354 3.197)
        (xy -0.355 3.165)
        (xy -0.357 3.133)
        (xy -0.374 3.148)
        (xy -0.411 3.175)
        (xy -0.453 3.193)
        (xy -0.497 3.203)
        (xy -0.542 3.204)
        (xy -0.585 3.195)
        (xy -0.586 3.195)
        (xy -0.621 3.181)
        (xy -0.651 3.16)
        (xy -0.673 3.141)
        (xy -0.689 3.123)
        (xy -0.702 3.106)
        (xy -0.712 3.086)
        (xy -0.72 3.064)
        (xy -0.726 3.038)
        (xy -0.73 3.007)
        (xy -0.732 2.968)
        (xy -0.733 2.922)
        (xy -0.733 2.88)
        (xy -0.602 2.88)
        (xy -0.602 2.915)
        (xy -0.602 2.942)
        (xy -0.601 2.962)
        (xy -0.6 2.977)
        (xy -0.598 2.988)
        (xy -0.596 2.998)
        (xy -0.592 3.007)
        (xy -0.591 3.01)
        (xy -0.574 3.039)
        (xy -0.552 3.059)
        (xy -0.525 3.071)
        (xy -0.492 3.076)
        (xy -0.472 3.076)
        (xy -0.442 3.072)
        (xy -0.418 3.063)
        (xy -0.398 3.048)
        (xy -0.382 3.029)
        (xy -0.371 3.004)
        (xy -0.363 2.972)
        (xy -0.358 2.933)
        (xy -0.356 2.885)
        (xy -0.356 2.88)
        (xy -0.358 2.828)
        (xy -0.363 2.785)
        (xy -0.373 2.75)
        (xy -0.387 2.724)
        (xy -0.406 2.704)
        (xy -0.43 2.692)
        (xy -0.46 2.686)
        (xy -0.483 2.685)
        (xy -0.517 2.687)
        (xy -0.544 2.696)
        (xy -0.565 2.711)
        (xy -0.583 2.734)
        (xy -0.591 2.751)
        (xy -0.595 2.76)
        (xy -0.598 2.769)
        (xy -0.6 2.779)
        (xy -0.601 2.793)
        (xy -0.602 2.811)
        (xy -0.602 2.836)
        (xy -0.602 2.869)
        (xy -0.602 2.88)
        (xy -0.733 2.88)
        (xy -0.733 2.827)
        (xy -0.732 2.783)
        (xy -0.729 2.746)
        (xy -0.725 2.716)
        (xy -0.719 2.691)
        (xy -0.71 2.67)
        (xy -0.699 2.651)
        (xy -0.685 2.633)
        (xy -0.668 2.616)
        (xy -0.668 2.615)
        (xy -0.632 2.587)
        (xy -0.592 2.567)
        (xy -0.55 2.557)
        (xy -0.506 2.556)
        (xy -0.463 2.564)
        (xy -0.421 2.582)
        (xy -0.411 2.587)
        (xy -0.394 2.598)
        (xy -0.377 2.61)
        (xy -0.373 2.614)
        (xy -0.356 2.627)
        (xy -0.356 2.306)
        (xy -0.229 2.306)
        (xy -0.229 3.2)
      )

      (stroke (width 0.01) (type solid)) (fill solid) (layer "F.Mask"))
    (fp_poly
      (pts
        (xy 0.605 1.558)
        (xy 0.651 1.574)
        (xy 0.694 1.598)
        (xy 0.728 1.627)
        (xy 0.75 1.652)
        (xy 0.768 1.678)
        (xy 0.781 1.707)
        (xy 0.791 1.739)
        (xy 0.797 1.777)
        (xy 0.801 1.822)
        (xy 0.802 1.876)
        (xy 0.802 1.877)
        (xy 0.801 1.929)
        (xy 0.798 1.973)
        (xy 0.792 2.009)
        (xy 0.784 2.04)
        (xy 0.774 2.062)
        (xy 0.748 2.103)
        (xy 0.715 2.139)
        (xy 0.675 2.167)
        (xy 0.632 2.187)
        (xy 0.626 2.189)
        (xy 0.599 2.195)
        (xy 0.567 2.198)
        (xy 0.532 2.199)
        (xy 0.499 2.197)
        (xy 0.471 2.193)
        (xy 0.466 2.192)
        (xy 0.428 2.177)
        (xy 0.391 2.155)
        (xy 0.359 2.129)
        (xy 0.354 2.123)
        (xy 0.332 2.098)
        (xy 0.316 2.073)
        (xy 0.303 2.047)
        (xy 0.294 2.017)
        (xy 0.287 1.983)
        (xy 0.284 1.943)
        (xy 0.282 1.894)
        (xy 0.282 1.877)
        (xy 0.409 1.877)
        (xy 0.41 1.918)
        (xy 0.412 1.95)
        (xy 0.416 1.976)
        (xy 0.423 1.997)
        (xy 0.432 2.015)
        (xy 0.445 2.03)
        (xy 0.451 2.037)
        (xy 0.471 2.054)
        (xy 0.491 2.064)
        (xy 0.514 2.07)
        (xy 0.543 2.072)
        (xy 0.569 2.07)
        (xy 0.59 2.065)
        (xy 0.601 2.06)
        (xy 0.625 2.047)
        (xy 0.642 2.031)
        (xy 0.656 2.009)
        (xy 0.661 1.998)
        (xy 0.665 1.989)
        (xy 0.668 1.98)
        (xy 0.67 1.969)
        (xy 0.671 1.954)
        (xy 0.672 1.935)
        (xy 0.673 1.909)
        (xy 0.673 1.877)
        (xy 0.673 1.842)
        (xy 0.672 1.817)
        (xy 0.671 1.798)
        (xy 0.67 1.784)
        (xy 0.668 1.773)
        (xy 0.665 1.764)
        (xy 0.661 1.755)
        (xy 0.647 1.73)
        (xy 0.632 1.712)
        (xy 0.612 1.698)
        (xy 0.601 1.693)
        (xy 0.569 1.683)
        (xy 0.535 1.681)
        (xy 0.501 1.686)
        (xy 0.471 1.7)
        (xy 0.447 1.719)
        (xy 0.434 1.736)
        (xy 0.424 1.753)
        (xy 0.417 1.774)
        (xy 0.412 1.8)
        (xy 0.41 1.833)
        (xy 0.409 1.873)
        (xy 0.409 1.877)
        (xy 0.282 1.877)
        (xy 0.283 1.824)
        (xy 0.286 1.78)
        (xy 0.292 1.742)
        (xy 0.301 1.711)
        (xy 0.313 1.683)
        (xy 0.33 1.657)
        (xy 0.35 1.633)
        (xy 0.351 1.632)
        (xy 0.385 1.601)
        (xy 0.42 1.578)
        (xy 0.46 1.563)
        (xy 0.505 1.554)
        (xy 0.555 1.551)
        (xy 0.605 1.558)
      )

      (stroke (width 0.01) (type solid)) (fill solid) (layer "F.Mask"))
    (fp_poly
      (pts
        (xy 0.004 1.556)
        (xy 0.054 1.566)
        (xy 0.102 1.582)
        (xy 0.146 1.605)
        (xy 0.154 1.61)
        (xy 0.193 1.636)
        (xy 0.178 1.655)
        (xy 0.166 1.668)
        (xy 0.152 1.686)
        (xy 0.138 1.7)
        (xy 0.114 1.727)
        (xy 0.07 1.705)
        (xy 0.032 1.688)
        (xy -0.007 1.677)
        (xy -0.044 1.672)
        (xy -0.079 1.672)
        (xy -0.11 1.678)
        (xy -0.136 1.69)
        (xy -0.154 1.707)
        (xy -0.162 1.724)
        (xy -0.164 1.745)
        (xy -0.164 1.761)
        (xy -0.159 1.772)
        (xy -0.15 1.782)
        (xy -0.149 1.783)
        (xy -0.139 1.791)
        (xy -0.128 1.797)
        (xy -0.114 1.802)
        (xy -0.095 1.805)
        (xy -0.07 1.808)
        (xy -0.037 1.811)
        (xy -0.02 1.813)
        (xy 0.027 1.817)
        (xy 0.065 1.823)
        (xy 0.096 1.832)
        (xy 0.122 1.842)
        (xy 0.14 1.854)
        (xy 0.166 1.879)
        (xy 0.186 1.91)
        (xy 0.2 1.947)
        (xy 0.206 1.987)
        (xy 0.206 2.018)
        (xy 0.198 2.06)
        (xy 0.181 2.097)
        (xy 0.155 2.129)
        (xy 0.122 2.156)
        (xy 0.08 2.177)
        (xy 0.042 2.189)
        (xy 0.005 2.196)
        (xy -0.038 2.199)
        (xy -0.083 2.198)
        (xy -0.125 2.194)
        (xy -0.153 2.189)
        (xy -0.177 2.181)
        (xy -0.204 2.171)
        (xy -0.229 2.16)
        (xy -0.232 2.159)
        (xy -0.251 2.148)
        (xy -0.272 2.136)
        (xy -0.292 2.122)
        (xy -0.309 2.109)
        (xy -0.323 2.098)
        (xy -0.33 2.09)
        (xy -0.331 2.088)
        (xy -0.327 2.084)
        (xy -0.318 2.073)
        (xy -0.304 2.059)
        (xy -0.288 2.043)
        (xy -0.246 2)
        (xy -0.221 2.021)
        (xy -0.184 2.047)
        (xy -0.145 2.065)
        (xy -0.102 2.075)
        (xy -0.053 2.079)
        (xy -0.049 2.079)
        (xy -0.023 2.079)
        (xy -0.004 2.078)
        (xy 0.011 2.074)
        (xy 0.025 2.069)
        (xy 0.029 2.068)
        (xy 0.054 2.052)
        (xy 0.071 2.033)
        (xy 0.079 2.01)
        (xy 0.078 1.986)
        (xy 0.074 1.975)
        (xy 0.068 1.964)
        (xy 0.06 1.956)
        (xy 0.048 1.949)
        (xy 0.031 1.944)
        (xy 0.007 1.939)
        (xy -0.024 1.935)
        (xy -0.052 1.932)
        (xy -0.089 1.929)
        (xy -0.119 1.925)
        (xy -0.142 1.921)
        (xy -0.16 1.917)
        (xy -0.176 1.912)
        (xy -0.192 1.906)
        (xy -0.201 1.901)
        (xy -0.235 1.879)
        (xy -0.262 1.85)
        (xy -0.28 1.816)
        (xy -0.29 1.776)
        (xy -0.292 1.75)
        (xy -0.291 1.727)
        (xy -0.289 1.705)
        (xy -0.286 1.689)
        (xy -0.286 1.688)
        (xy -0.273 1.659)
        (xy -0.253 1.63)
        (xy -0.229 1.604)
        (xy -0.221 1.599)
        (xy -0.185 1.577)
        (xy -0.143 1.562)
        (xy -0.096 1.554)
        (xy -0.047 1.552)
        (xy 0.004 1.556)
      )

      (stroke (width 0.01) (type solid)) (fill solid) (layer "F.Mask"))
    (fp_poly
      (pts
        (xy 1.038 2.556)
        (xy 1.091 2.563)
        (xy 1.137 2.576)
        (xy 1.177 2.595)
        (xy 1.209 2.62)
        (xy 1.234 2.65)
        (xy 1.242 2.665)
        (xy 1.247 2.677)
        (xy 1.251 2.691)
        (xy 1.255 2.708)
        (xy 1.258 2.727)
        (xy 1.26 2.751)
        (xy 1.262 2.78)
        (xy 1.263 2.815)
        (xy 1.263 2.858)
        (xy 1.264 2.908)
        (xy 1.263 2.967)
        (xy 1.263 2.989)
        (xy 1.262 3.197)
        (xy 1.135 3.197)
        (xy 1.133 3.171)
        (xy 1.132 3.144)
        (xy 1.119 3.159)
        (xy 1.096 3.179)
        (xy 1.065 3.193)
        (xy 1.026 3.202)
        (xy 0.98 3.204)
        (xy 0.976 3.204)
        (xy 0.955 3.204)
        (xy 0.937 3.203)
        (xy 0.925 3.202)
        (xy 0.924 3.201)
        (xy 0.879 3.189)
        (xy 0.839 3.17)
        (xy 0.806 3.144)
        (xy 0.781 3.113)
        (xy 0.763 3.077)
        (xy 0.753 3.037)
        (xy 0.753 3.005)
        (xy 0.873 3.005)
        (xy 0.874 3.023)
        (xy 0.878 3.035)
        (xy 0.887 3.047)
        (xy 0.89 3.05)
        (xy 0.903 3.063)
        (xy 0.917 3.072)
        (xy 0.935 3.078)
        (xy 0.957 3.081)
        (xy 0.986 3.082)
        (xy 1.013 3.082)
        (xy 1.043 3.081)
        (xy 1.065 3.079)
        (xy 1.08 3.077)
        (xy 1.091 3.073)
        (xy 1.096 3.071)
        (xy 1.112 3.058)
        (xy 1.123 3.039)
        (xy 1.13 3.012)
        (xy 1.132 2.977)
        (xy 1.132 2.975)
        (xy 1.132 2.931)
        (xy 1.035 2.931)
        (xy 0.999 2.931)
        (xy 0.973 2.931)
        (xy 0.953 2.932)
        (xy 0.939 2.934)
        (xy 0.928 2.936)
        (xy 0.919 2.939)
        (xy 0.916 2.94)
        (xy 0.893 2.954)
        (xy 0.88 2.971)
        (xy 0.874 2.994)
        (xy 0.873 3.005)
        (xy 0.753 3.005)
        (xy 0.753 2.994)
        (xy 0.761 2.951)
        (xy 0.768 2.931)
        (xy 0.776 2.915)
        (xy 0.786 2.901)
        (xy 0.802 2.884)
        (xy 0.804 2.882)
        (xy 0.82 2.867)
        (xy 0.835 2.854)
        (xy 0.85 2.845)
        (xy 0.867 2.838)
        (xy 0.887 2.833)
        (xy 0.912 2.829)
        (xy 0.943 2.827)
        (xy 0.982 2.826)
        (xy 1.015 2.825)
        (xy 1.133 2.823)
        (xy 1.132 2.771)
        (xy 1.131 2.746)
        (xy 1.129 2.73)
        (xy 1.127 2.719)
        (xy 1.123 2.711)
        (xy 1.117 2.705)
        (xy 1.098 2.691)
        (xy 1.07 2.682)
        (xy 1.032 2.677)
        (xy 1.006 2.677)
        (xy 0.972 2.678)
        (xy 0.945 2.682)
        (xy 0.924 2.688)
        (xy 0.907 2.699)
        (xy 0.9 2.706)
        (xy 0.882 2.723)
        (xy 0.834 2.686)
        (xy 0.816 2.672)
        (xy 0.801 2.66)
        (xy 0.79 2.652)
        (xy 0.787 2.648)
        (xy 0.791 2.639)
        (xy 0.801 2.626)
        (xy 0.816 2.612)
        (xy 0.832 2.6)
        (xy 0.864 2.581)
        (xy 0.902 2.568)
        (xy 0.946 2.559)
        (xy 0.98 2.556)
        (xy 1.038 2.556)
      )

      (stroke (width 0.01) (type solid)) (fill solid) (layer "F.Mask"))
    (fp_poly
      (pts
        (xy -1.521 2.559)
        (xy -1.485 2.562)
        (xy -1.454 2.568)
        (xy -1.427 2.577)
        (xy -1.401 2.589)
        (xy -1.371 2.61)
        (xy -1.345 2.639)
        (xy -1.325 2.67)
        (xy -1.321 2.679)
        (xy -1.309 2.71)
        (xy -1.309 3.197)
        (xy -1.433 3.2)
        (xy -1.433 3.172)
        (xy -1.434 3.157)
        (xy -1.435 3.147)
        (xy -1.436 3.144)
        (xy -1.44 3.147)
        (xy -1.449 3.156)
        (xy -1.453 3.161)
        (xy -1.472 3.178)
        (xy -1.496 3.19)
        (xy -1.526 3.198)
        (xy -1.563 3.202)
        (xy -1.578 3.203)
        (xy -1.603 3.203)
        (xy -1.627 3.203)
        (xy -1.647 3.201)
        (xy -1.656 3.2)
        (xy -1.686 3.191)
        (xy -1.717 3.176)
        (xy -1.746 3.159)
        (xy -1.765 3.143)
        (xy -1.79 3.111)
        (xy -1.807 3.075)
        (xy -1.816 3.037)
        (xy -1.817 2.998)
        (xy -1.817 2.997)
        (xy -1.697 2.997)
        (xy -1.696 3.02)
        (xy -1.687 3.042)
        (xy -1.67 3.06)
        (xy -1.668 3.062)
        (xy -1.654 3.07)
        (xy -1.64 3.076)
        (xy -1.624 3.08)
        (xy -1.602 3.081)
        (xy -1.574 3.082)
        (xy -1.558 3.082)
        (xy -1.529 3.081)
        (xy -1.508 3.08)
        (xy -1.494 3.078)
        (xy -1.483 3.075)
        (xy -1.474 3.07)
        (xy -1.458 3.058)
        (xy -1.447 3.041)
        (xy -1.44 3.017)
        (xy -1.435 2.985)
        (xy -1.435 2.977)
        (xy -1.432 2.931)
        (xy -1.533 2.931)
        (xy -1.568 2.931)
        (xy -1.595 2.931)
        (xy -1.615 2.932)
        (xy -1.63 2.934)
        (xy -1.641 2.936)
        (xy -1.65 2.938)
        (xy -1.655 2.941)
        (xy -1.676 2.955)
        (xy -1.69 2.974)
        (xy -1.697 2.997)
        (xy -1.817 2.997)
        (xy -1.811 2.96)
        (xy -1.797 2.924)
        (xy -1.775 2.892)
        (xy -1.747 2.864)
        (xy -1.715 2.845)
        (xy -1.7 2.838)
        (xy -1.685 2.833)
        (xy -1.668 2.83)
        (xy -1.648 2.827)
        (xy -1.623 2.825)
        (xy -1.591 2.824)
        (xy -1.551 2.824)
        (xy -1.54 2.824)
        (xy -1.432 2.824)
        (xy -1.434 2.776)
        (xy -1.436 2.747)
        (xy -1.441 2.726)
        (xy -1.448 2.711)
        (xy -1.46 2.699)
        (xy -1.474 2.689)
        (xy -1.483 2.685)
        (xy -1.492 2.682)
        (xy -1.505 2.68)
        (xy -1.524 2.68)
        (xy -1.55 2.679)
        (xy -1.56 2.679)
        (xy -1.594 2.68)
        (xy -1.62 2.682)
        (xy -1.639 2.686)
        (xy -1.654 2.692)
        (xy -1.666 2.701)
        (xy -1.675 2.711)
        (xy -1.686 2.724)
        (xy -1.735 2.686)
        (xy -1.754 2.672)
        (xy -1.769 2.659)
        (xy -1.78 2.65)
        (xy -1.784 2.646)
        (xy -1.78 2.64)
        (xy -1.77 2.629)
        (xy -1.756 2.616)
        (xy -1.74 2.604)
        (xy -1.724 2.592)
        (xy -1.711 2.584)
        (xy -1.71 2.583)
        (xy -1.688 2.574)
        (xy -1.668 2.566)
        (xy -1.647 2.562)
        (xy -1.623 2.559)
        (xy -1.593 2.558)
        (xy -1.565 2.558)
        (xy -1.521 2.559)
      )

      (stroke (width 0.01) (type solid)) (fill solid) (layer "F.Mask"))
    (fp_poly
      (pts
        (xy 0.035 2.777)
        (xy 0.047 2.822)
        (xy 0.059 2.864)
        (xy 0.069 2.903)
        (xy 0.078 2.936)
        (xy 0.086 2.963)
        (xy 0.092 2.984)
        (xy 0.095 2.996)
        (xy 0.096 2.999)
        (xy 0.098 2.999)
        (xy 0.103 2.991)
        (xy 0.109 2.975)
        (xy 0.118 2.95)
        (xy 0.129 2.917)
        (xy 0.143 2.874)
        (xy 0.152 2.849)
        (xy 0.165 2.807)
        (xy 0.179 2.766)
        (xy 0.192 2.726)
        (xy 0.204 2.689)
        (xy 0.214 2.658)
        (xy 0.221 2.634)
        (xy 0.224 2.627)
        (xy 0.244 2.565)
        (xy 0.338 2.565)
        (xy 0.406 2.774)
        (xy 0.42 2.819)
        (xy 0.434 2.861)
        (xy 0.446 2.899)
        (xy 0.457 2.932)
        (xy 0.466 2.96)
        (xy 0.473 2.981)
        (xy 0.477 2.993)
        (xy 0.478 2.997)
        (xy 0.48 2.998)
        (xy 0.482 2.996)
        (xy 0.485 2.99)
        (xy 0.49 2.978)
        (xy 0.495 2.96)
        (xy 0.502 2.936)
        (xy 0.511 2.905)
        (xy 0.523 2.865)
        (xy 0.536 2.817)
        (xy 0.543 2.789)
        (xy 0.556 2.744)
        (xy 0.568 2.701)
        (xy 0.578 2.663)
        (xy 0.587 2.629)
        (xy 0.595 2.602)
        (xy 0.601 2.582)
        (xy 0.605 2.57)
        (xy 0.606 2.567)
        (xy 0.611 2.566)
        (xy 0.625 2.566)
        (xy 0.645 2.566)
        (xy 0.669 2.566)
        (xy 0.673 2.566)
        (xy 0.739 2.567)
        (xy 0.656 2.827)
        (xy 0.64 2.878)
        (xy 0.624 2.928)
        (xy 0.609 2.976)
        (xy 0.595 3.02)
        (xy 0.582 3.06)
        (xy 0.571 3.094)
        (xy 0.563 3.121)
        (xy 0.557 3.139)
        (xy 0.556 3.143)
        (xy 0.538 3.2)
        (xy 0.425 3.197)
        (xy 0.358 2.975)
        (xy 0.341 2.917)
        (xy 0.327 2.87)
        (xy 0.315 2.831)
        (xy 0.305 2.801)
        (xy 0.297 2.78)
        (xy 0.292 2.766)
        (xy 0.289 2.761)
        (xy 0.288 2.761)
        (xy 0.286 2.768)
        (xy 0.281 2.783)
        (xy 0.274 2.806)
        (xy 0.265 2.836)
        (xy 0.254 2.871)
        (xy 0.242 2.911)
        (xy 0.23 2.953)
        (xy 0.223 2.976)
        (xy 0.21 3.02)
        (xy 0.197 3.062)
        (xy 0.186 3.099)
        (xy 0.177 3.132)
        (xy 0.169 3.158)
        (xy 0.163 3.177)
        (xy 0.16 3.189)
        (xy 0.159 3.191)
        (xy 0.157 3.195)
        (xy 0.151 3.198)
        (xy 0.141 3.199)
        (xy 0.124 3.2)
        (xy 0.101 3.2)
        (xy 0.073 3.199)
        (xy 0.055 3.198)
        (xy 0.045 3.196)
        (xy 0.043 3.194)
        (xy 0.041 3.188)
        (xy 0.036 3.173)
        (xy 0.029 3.15)
        (xy 0.019 3.121)
        (xy 0.008 3.084)
        (xy -0.006 3.043)
        (xy -0.02 2.996)
        (xy -0.036 2.946)
        (xy -0.053 2.893)
        (xy -0.057 2.883)
        (xy -0.074 2.83)
        (xy -0.09 2.779)
        (xy -0.105 2.732)
        (xy -0.119 2.689)
        (xy -0.131 2.652)
        (xy -0.141 2.621)
        (xy -0.148 2.596)
        (xy -0.154 2.58)
        (xy -0.156 2.572)
        (xy -0.156 2.569)
        (xy -0.151 2.567)
        (xy -0.14 2.566)
        (xy -0.123 2.565)
        (xy -0.096 2.565)
        (xy -0.091 2.565)
        (xy -0.023 2.565)
        (xy 0.035 2.777)
      )

      (stroke (width 0.01) (type solid)) (fill solid) (layer "F.Mask"))
    (fp_poly
      (pts
        (xy -2.065 1.559)
        (xy -2.024 1.576)
        (xy -1.986 1.601)
        (xy -1.973 1.612)
        (xy -1.957 1.63)
        (xy -1.943 1.649)
        (xy -1.932 1.668)
        (xy -1.924 1.69)
        (xy -1.918 1.716)
        (xy -1.914 1.747)
        (xy -1.911 1.785)
        (xy -1.91 1.831)
        (xy -1.91 1.877)
        (xy -1.91 1.93)
        (xy -1.912 1.974)
        (xy -1.914 2.011)
        (xy -1.919 2.041)
        (xy -1.925 2.067)
        (xy -1.934 2.088)
        (xy -1.945 2.107)
        (xy -1.959 2.125)
        (xy -1.972 2.139)
        (xy -1.993 2.157)
        (xy -2.018 2.173)
        (xy -2.031 2.18)
        (xy -2.047 2.188)
        (xy -2.06 2.192)
        (xy -2.074 2.195)
        (xy -2.091 2.196)
        (xy -2.114 2.197)
        (xy -2.122 2.197)
        (xy -2.147 2.196)
        (xy -2.165 2.195)
        (xy -2.179 2.193)
        (xy -2.191 2.189)
        (xy -2.205 2.183)
        (xy -2.21 2.18)
        (xy -2.231 2.169)
        (xy -2.251 2.156)
        (xy -2.265 2.146)
        (xy -2.286 2.127)
        (xy -2.286 2.627)
        (xy -2.266 2.608)
        (xy -2.248 2.595)
        (xy -2.227 2.582)
        (xy -2.217 2.577)
        (xy -2.173 2.562)
        (xy -2.129 2.556)
        (xy -2.086 2.559)
        (xy -2.045 2.57)
        (xy -2.007 2.589)
        (xy -1.974 2.616)
        (xy -1.946 2.648)
        (xy -1.926 2.687)
        (xy -1.919 2.707)
        (xy -1.917 2.715)
        (xy -1.915 2.724)
        (xy -1.914 2.737)
        (xy -1.913 2.753)
        (xy -1.912 2.774)
        (xy -1.911 2.8)
        (xy -1.911 2.833)
        (xy -1.911 2.874)
        (xy -1.911 2.923)
        (xy -1.911 2.967)
        (xy -1.911 3.2)
        (xy -2.035 3.197)
        (xy -2.038 2.984)
        (xy -2.038 2.932)
        (xy -2.039 2.889)
        (xy -2.039 2.854)
        (xy -2.04 2.826)
        (xy -2.041 2.805)
        (xy -2.042 2.788)
        (xy -2.043 2.776)
        (xy -2.045 2.767)
        (xy -2.046 2.76)
        (xy -2.049 2.755)
        (xy -2.051 2.75)
        (xy -2.072 2.721)
        (xy -2.098 2.701)
        (xy -2.128 2.688)
        (xy -2.161 2.683)
        (xy -2.195 2.687)
        (xy -2.22 2.697)
        (xy -2.24 2.71)
        (xy -2.259 2.729)
        (xy -2.274 2.75)
        (xy -2.278 2.757)
        (xy -2.28 2.765)
        (xy -2.281 2.781)
        (xy -2.283 2.806)
        (xy -2.284 2.839)
        (xy -2.285 2.881)
        (xy -2.286 2.933)
        (xy -2.286 2.984)
        (xy -2.289 3.197)
        (xy -2.413 3.2)
        (xy -2.413 1.877)
        (xy -2.286 1.877)
        (xy -2.285 1.926)
        (xy -2.281 1.966)
        (xy -2.274 1.998)
        (xy -2.262 2.024)
        (xy -2.247 2.043)
        (xy -2.228 2.058)
        (xy -2.215 2.064)
        (xy -2.194 2.07)
        (xy -2.168 2.072)
        (xy -2.141 2.071)
        (xy -2.117 2.066)
        (xy -2.106 2.063)
        (xy -2.079 2.044)
        (xy -2.058 2.019)
        (xy -2.05 2.001)
        (xy -2.045 1.984)
        (xy -2.042 1.959)
        (xy -2.04 1.929)
        (xy -2.038 1.895)
        (xy -2.038 1.861)
        (xy -2.039 1.829)
        (xy -2.041 1.8)
        (xy -2.044 1.777)
        (xy -2.045 1.772)
        (xy -2.057 1.738)
        (xy -2.073 1.712)
        (xy -2.094 1.695)
        (xy -2.122 1.684)
        (xy -2.156 1.681)
        (xy -2.159 1.681)
        (xy -2.192 1.683)
        (xy -2.22 1.691)
        (xy -2.243 1.705)
        (xy -2.26 1.725)
        (xy -2.273 1.753)
        (xy -2.281 1.788)
        (xy -2.285 1.832)
        (xy -2.286 1.877)
        (xy -2.413 1.877)
        (xy -2.413 1.559)
        (xy -2.286 1.559)
        (xy -2.286 1.62)
        (xy -2.26 1.6)
        (xy -2.225 1.577)
        (xy -2.19 1.563)
        (xy -2.154 1.554)
        (xy -2.109 1.552)
        (xy -2.065 1.559)
      )

      (stroke (width 0.01) (type solid)) (fill solid) (layer "F.Mask"))
    (fp_poly
      (pts
        (xy 0.063 -3.201)
        (xy 0.118 -3.201)
        (xy 0.164 -3.201)
        (xy 0.202 -3.2)
        (xy 0.233 -3.2)
        (xy 0.258 -3.2)
        (xy 0.277 -3.199)
        (xy 0.292 -3.198)
        (xy 0.302 -3.197)
        (xy 0.309 -3.196)
        (xy 0.314 -3.195)
        (xy 0.317 -3.193)
        (xy 0.319 -3.192)
        (xy 0.321 -3.189)
        (xy 0.324 -3.183)
        (xy 0.327 -3.174)
        (xy 0.33 -3.161)
        (xy 0.334 -3.144)
        (xy 0.339 -3.12)
        (xy 0.345 -3.091)
        (xy 0.352 -3.054)
        (xy 0.361 -3.01)
        (xy 0.371 -2.958)
        (xy 0.382 -2.897)
        (xy 0.385 -2.878)
        (xy 0.395 -2.824)
        (xy 0.405 -2.772)
        (xy 0.414 -2.724)
        (xy 0.423 -2.68)
        (xy 0.43 -2.642)
        (xy 0.437 -2.61)
        (xy 0.442 -2.586)
        (xy 0.446 -2.569)
        (xy 0.448 -2.562)
        (xy 0.456 -2.55)
        (xy 0.464 -2.544)
        (xy 0.476 -2.539)
        (xy 0.495 -2.53)
        (xy 0.521 -2.519)
        (xy 0.552 -2.506)
        (xy 0.587 -2.492)
        (xy 0.624 -2.477)
        (xy 0.664 -2.461)
        (xy 0.704 -2.445)
        (xy 0.743 -2.43)
        (xy 0.78 -2.415)
        (xy 0.814 -2.402)
        (xy 0.843 -2.391)
        (xy 0.868 -2.382)
        (xy 0.885 -2.376)
        (xy 0.895 -2.373)
        (xy 0.896 -2.373)
        (xy 0.911 -2.376)
        (xy 0.931 -2.386)
        (xy 0.948 -2.397)
        (xy 0.962 -2.406)
        (xy 0.983 -2.421)
        (xy 1.011 -2.44)
        (xy 1.043 -2.462)
        (xy 1.079 -2.487)
        (xy 1.118 -2.513)
        (xy 1.158 -2.541)
        (xy 1.198 -2.568)
        (xy 1.238 -2.595)
        (xy 1.275 -2.621)
        (xy 1.309 -2.644)
        (xy 1.338 -2.665)
        (xy 1.362 -2.681)
        (xy 1.377 -2.691)
        (xy 1.398 -2.705)
        (xy 1.418 -2.717)
        (xy 1.433 -2.725)
        (xy 1.442 -2.728)
        (xy 1.443 -2.728)
        (xy 1.448 -2.726)
        (xy 1.456 -2.72)
        (xy 1.468 -2.71)
        (xy 1.486 -2.694)
        (xy 1.508 -2.673)
        (xy 1.535 -2.647)
        (xy 1.568 -2.614)
        (xy 1.608 -2.575)
        (xy 1.654 -2.53)
        (xy 1.675 -2.509)
        (xy 1.721 -2.462)
        (xy 1.761 -2.422)
        (xy 1.794 -2.388)
        (xy 1.822 -2.36)
        (xy 1.844 -2.337)
        (xy 1.862 -2.318)
        (xy 1.875 -2.304)
        (xy 1.884 -2.293)
        (xy 1.89 -2.284)
        (xy 1.893 -2.279)
        (xy 1.894 -2.275)
        (xy 1.892 -2.269)
        (xy 1.886 -2.257)
        (xy 1.875 -2.239)
        (xy 1.86 -2.215)
        (xy 1.839 -2.183)
        (xy 1.814 -2.145)
        (xy 1.783 -2.1)
        (xy 1.747 -2.046)
        (xy 1.721 -2.009)
        (xy 1.69 -1.964)
        (xy 1.661 -1.921)
        (xy 1.634 -1.88)
        (xy 1.609 -1.844)
        (xy 1.588 -1.811)
        (xy 1.57 -1.785)
        (xy 1.557 -1.764)
        (xy 1.549 -1.75)
        (xy 1.546 -1.743)
        (xy 1.547 -1.735)
        (xy 1.552 -1.719)
        (xy 1.56 -1.696)
        (xy 1.571 -1.667)
        (xy 1.585 -1.634)
        (xy 1.6 -1.597)
        (xy 1.616 -1.557)
        (xy 1.633 -1.516)
        (xy 1.651 -1.476)
        (xy 1.668 -1.436)
        (xy 1.685 -1.398)
        (xy 1.701 -1.363)
        (xy 1.715 -1.333)
        (xy 1.727 -1.309)
        (xy 1.736 -1.291)
        (xy 1.742 -1.281)
        (xy 1.744 -1.279)
        (xy 1.751 -1.277)
        (xy 1.767 -1.273)
        (xy 1.791 -1.268)
        (xy 1.822 -1.261)
        (xy 1.86 -1.254)
        (xy 1.903 -1.245)
        (xy 1.951 -1.236)
        (xy 2.002 -1.226)
        (xy 2.049 -1.217)
        (xy 2.103 -1.207)
        (xy 2.154 -1.198)
        (xy 2.201 -1.188)
        (xy 2.244 -1.18)
        (xy 2.281 -1.173)
        (xy 2.311 -1.166)
        (xy 2.335 -1.161)
        (xy 2.35 -1.157)
        (xy 2.355 -1.156)
        (xy 2.367 -1.148)
        (xy 2.367 -0.834)
        (xy 2.367 -0.768)
        (xy 2.367 -0.712)
        (xy 2.367 -0.664)
        (xy 2.366 -0.625)
        (xy 2.366 -0.592)
        (xy 2.365 -0.566)
        (xy 2.364 -0.546)
        (xy 2.363 -0.531)
        (xy 2.361 -0.52)
        (xy 2.358 -0.512)
        (xy 2.355 -0.507)
        (xy 2.352 -0.504)
        (xy 2.348 -0.503)
        (xy 2.343 -0.501)
        (xy 2.34 -0.501)
        (xy 2.333 -0.499)
        (xy 2.317 -0.496)
        (xy 2.293 -0.492)
        (xy 2.261 -0.486)
        (xy 2.224 -0.479)
        (xy 2.181 -0.471)
        (xy 2.134 -0.462)
        (xy 2.084 -0.453)
        (xy 2.054 -0.448)
        (xy 2.002 -0.438)
        (xy 1.953 -0.429)
        (xy 1.907 -0.42)
        (xy 1.866 -0.412)
        (xy 1.831 -0.404)
        (xy 1.802 -0.398)
        (xy 1.78 -0.394)
        (xy 1.767 -0.391)
        (xy 1.764 -0.39)
        (xy 1.76 -0.387)
        (xy 1.757 -0.384)
        (xy 1.753 -0.379)
        (xy 1.748 -0.371)
        (xy 1.742 -0.36)
        (xy 1.735 -0.344)
        (xy 1.726 -0.324)
        (xy 1.715 -0.297)
        (xy 1.701 -0.264)
        (xy 1.685 -0.223)
        (xy 1.665 -0.174)
        (xy 1.653 -0.145)
        (xy 1.63 -0.086)
        (xy 1.61 -0.037)
        (xy 1.594 0.005)
        (xy 1.582 0.038)
        (xy 1.572 0.064)
        (xy 1.566 0.084)
        (xy 1.562 0.097)
        (xy 1.561 0.104)
        (xy 1.562 0.105)
        (xy 1.565 0.111)
        (xy 1.574 0.125)
        (xy 1.587 0.146)
        (xy 1.604 0.173)
        (xy 1.626 0.205)
        (xy 1.65 0.241)
        (xy 1.677 0.281)
        (xy 1.706 0.324)
        (xy 1.729 0.358)
        (xy 1.768 0.413)
        (xy 1.8 0.461)
        (xy 1.827 0.502)
        (xy 1.85 0.535)
        (xy 1.867 0.562)
        (xy 1.88 0.583)
        (xy 1.889 0.598)
        (xy 1.893 0.608)
        (xy 1.894 0.612)
        (xy 1.893 0.616)
        (xy 1.89 0.622)
        (xy 1.885 0.63)
        (xy 1.876 0.64)
        (xy 1.863 0.655)
        (xy 1.846 0.673)
        (xy 1.825 0.695)
        (xy 1.798 0.723)
        (xy 1.765 0.756)
        (xy 1.727 0.795)
        (xy 1.682 0.839)
        (xy 1.635 0.886)
        (xy 1.595 0.926)
        (xy 1.561 0.96)
        (xy 1.532 0.989)
        (xy 1.508 1.012)
        (xy 1.488 1.03)
        (xy 1.473 1.044)
        (xy 1.461 1.054)
        (xy 1.452 1.061)
        (xy 1.445 1.065)
        (xy 1.44 1.066)
        (xy 1.438 1.066)
        (xy 1.433 1.064)
        (xy 1.421 1.055)
        (xy 1.401 1.043)
        (xy 1.376 1.026)
        (xy 1.345 1.005)
        (xy 1.31 0.981)
        (xy 1.27 0.954)
        (xy 1.228 0.925)
        (xy 1.193 0.901)
        (xy 1.138 0.864)
        (xy 1.089 0.83)
        (xy 1.046 0.802)
        (xy 1.01 0.778)
        (xy 0.981 0.759)
        (xy 0.96 0.746)
        (xy 0.946 0.738)
        (xy 0.94 0.736)
        (xy 0.932 0.738)
        (xy 0.917 0.745)
        (xy 0.895 0.755)
        (xy 0.869 0.768)
        (xy 0.84 0.783)
        (xy 0.816 0.795)
        (xy 0.781 0.814)
        (xy 0.753 0.828)
        (xy 0.732 0.838)
        (xy 0.717 0.845)
        (xy 0.707 0.849)
        (xy 0.699 0.85)
        (xy 0.694 0.849)
        (xy 0.691 0.847)
        (xy 0.687 0.84)
        (xy 0.682 0.829)
        (xy 0.674 0.814)
        (xy 0.665 0.793)
        (xy 0.653 0.767)
        (xy 0.639 0.735)
        (xy 0.623 0.696)
        (xy 0.604 0.651)
        (xy 0.582 0.598)
        (xy 0.556 0.538)
        (xy 0.528 0.469)
        (xy 0.496 0.391)
        (xy 0.47 0.329)
        (xy 0.436 0.247)
        (xy 0.406 0.173)
        (xy 0.379 0.108)
        (xy 0.355 0.05)
        (xy 0.335 0)
        (xy 0.317 -0.043)
        (xy 0.303 -0.079)
        (xy 0.291 -0.11)
        (xy 0.281 -0.135)
        (xy 0.273 -0.155)
        (xy 0.268 -0.171)
        (xy 0.264 -0.183)
        (xy 0.262 -0.191)
        (xy 0.262 -0.196)
        (xy 0.262 -0.198)
        (xy 0.269 -0.207)
        (xy 0.283 -0.219)
        (xy 0.302 -0.233)
        (xy 0.303 -0.234)
        (xy 0.354 -0.268)
        (xy 0.398 -0.3)
        (xy 0.435 -0.331)
        (xy 0.469 -0.363)
        (xy 0.5 -0.397)
        (xy 0.507 -0.405)
        (xy 0.556 -0.472)
        (xy 0.596 -0.543)
        (xy 0.627 -0.619)
        (xy 0.643 -0.672)
        (xy 0.651 -0.718)
        (xy 0.657 -0.77)
        (xy 0.66 -0.824)
        (xy 0.659 -0.878)
        (xy 0.654 -0.927)
        (xy 0.652 -0.936)
        (xy 0.634 -1.015)
        (xy 0.607 -1.09)
        (xy 0.571 -1.161)
        (xy 0.528 -1.227)
        (xy 0.477 -1.287)
        (xy 0.419 -1.341)
        (xy 0.355 -1.387)
        (xy 0.285 -1.426)
        (xy 0.21 -1.456)
        (xy 0.205 -1.458)
        (xy 0.131 -1.477)
        (xy 0.054 -1.487)
        (xy -0.025 -1.489)
        (xy -0.103 -1.482)
        (xy -0.178 -1.466)
        (xy -0.206 -1.458)
        (xy -0.281 -1.428)
        (xy -0.351 -1.39)
        (xy -0.416 -1.344)
        (xy -0.474 -1.29)
        (xy -0.526 -1.23)
        (xy -0.571 -1.164)
        (xy -0.607 -1.093)
        (xy -0.63 -1.034)
        (xy -0.649 -0.96)
        (xy -0.659 -0.883)
        (xy -0.661 -0.804)
        (xy -0.654 -0.726)
        (xy -0.638 -0.651)
        (xy -0.63 -0.623)
        (xy -0.618 -0.591)
        (xy -0.602 -0.554)
        (xy -0.584 -0.518)
        (xy -0.566 -0.485)
        (xy -0.553 -0.463)
        (xy -0.509 -0.407)
        (xy -0.457 -0.352)
        (xy -0.397 -0.299)
        (xy -0.33 -0.25)
        (xy -0.289 -0.224)
        (xy -0.273 -0.212)
        (xy -0.263 -0.2)
        (xy -0.262 -0.197)
        (xy -0.263 -0.19)
        (xy -0.268 -0.175)
        (xy -0.277 -0.151)
        (xy -0.288 -0.121)
        (xy -0.302 -0.084)
        (xy -0.319 -0.042)
        (xy -0.338 0.005)
        (xy -0.358 0.056)
        (xy -0.381 0.111)
        (xy -0.404 0.168)
        (xy -0.428 0.228)
        (xy -0.453 0.288)
        (xy -0.478 0.349)
        (xy -0.504 0.41)
        (xy -0.529 0.47)
        (xy -0.553 0.527)
        (xy -0.576 0.583)
        (xy -0.598 0.635)
        (xy -0.619 0.683)
        (xy -0.638 0.727)
        (xy -0.655 0.765)
        (xy -0.669 0.797)
        (xy -0.68 0.822)
        (xy -0.689 0.839)
        (xy -0.694 0.848)
        (xy -0.695 0.849)
        (xy -0.699 0.85)
        (xy -0.706 0.849)
        (xy -0.717 0.845)
        (xy -0.732 0.839)
        (xy -0.752 0.829)
        (xy -0.779 0.815)
        (xy -0.814 0.797)
        (xy -0.817 0.795)
        (xy -0.848 0.779)
        (xy -0.877 0.764)
        (xy -0.902 0.752)
        (xy -0.922 0.743)
        (xy -0.936 0.737)
        (xy -0.941 0.736)
        (xy -0.949 0.739)
        (xy -0.964 0.748)
        (xy -0.987 0.761)
        (xy -1.015 0.78)
        (xy -1.05 0.803)
        (xy -1.072 0.818)
        (xy -1.138 0.863)
        (xy -1.195 0.903)
        (xy -1.245 0.937)
        (xy -1.289 0.966)
        (xy -1.325 0.991)
        (xy -1.356 1.012)
        (xy -1.381 1.029)
        (xy -1.401 1.042)
        (xy -1.416 1.052)
        (xy -1.427 1.059)
        (xy -1.435 1.064)
        (xy -1.439 1.066)
        (xy -1.44 1.066)
        (xy -1.449 1.064)
        (xy -1.453 1.061)
        (xy -1.458 1.057)
        (xy -1.47 1.046)
        (xy -1.487 1.029)
        (xy -1.509 1.007)
        (xy -1.537 0.98)
        (xy -1.568 0.95)
        (xy -1.602 0.915)
        (xy -1.639 0.879)
        (xy -1.678 0.84)
        (xy -1.678 0.839)
        (xy -1.726 0.792)
        (xy -1.767 0.751)
        (xy -1.801 0.716)
        (xy -1.829 0.687)
        (xy -1.852 0.663)
        (xy -1.869 0.644)
        (xy -1.882 0.63)
        (xy -1.89 0.62)
        (xy -1.894 0.613)
        (xy -1.895 0.61)
        (xy -1.892 0.603)
        (xy -1.884 0.588)
        (xy -1.87 0.565)
        (xy -1.85 0.536)
        (xy -1.826 0.499)
        (xy -1.797 0.455)
        (xy -1.763 0.405)
        (xy -1.73 0.358)
        (xy -1.7 0.313)
        (xy -1.671 0.271)
        (xy -1.645 0.232)
        (xy -1.621 0.197)
        (xy -1.601 0.166)
        (xy -1.584 0.141)
        (xy -1.572 0.121)
        (xy -1.565 0.109)
        (xy -1.563 0.105)
        (xy -1.563 0.099)
        (xy -1.566 0.087)
        (xy -1.572 0.07)
        (xy -1.58 0.045)
        (xy -1.592 0.013)
        (xy -1.607 -0.026)
        (xy -1.626 -0.074)
        (xy -1.648 -0.13)
        (xy -1.654 -0.145)
        (xy -1.676 -0.199)
        (xy -1.695 -0.245)
        (xy -1.71 -0.282)
        (xy -1.723 -0.313)
        (xy -1.733 -0.337)
        (xy -1.741 -0.356)
        (xy -1.748 -0.369)
        (xy -1.753 -0.379)
        (xy -1.758 -0.385)
        (xy -1.761 -0.388)
        (xy -1.763 -0.389)
        (xy -1.767 -0.39)
        (xy -1.774 -0.392)
        (xy -1.784 -0.395)
        (xy -1.799 -0.398)
        (xy -1.818 -0.402)
        (xy -1.843 -0.407)
        (xy -1.873 -0.413)
        (xy -1.91 -0.42)
        (xy -1.954 -0.429)
        (xy -2.005 -0.438)
        (xy -2.065 -0.449)
        (xy -2.133 -0.462)
        (xy -2.211 -0.477)
        (xy -2.22 -0.478)
        (xy -2.26 -0.486)
        (xy -2.29 -0.491)
        (xy -2.313 -0.496)
        (xy -2.33 -0.499)
        (xy -2.341 -0.502)
        (xy -2.349 -0.504)
        (xy -2.353 -0.506)
        (xy -2.356 -0.508)
        (xy -2.359 -0.51)
        (xy -2.36 -0.511)
        (xy -2.361 -0.514)
        (xy -2.363 -0.518)
        (xy -2.364 -0.526)
        (xy -2.365 -0.536)
        (xy -2.366 -0.551)
        (xy -2.366 -0.571)
        (xy -2.367 -0.597)
        (xy -2.367 -0.629)
        (xy -2.368 -0.668)
        (xy -2.368 -0.715)
        (xy -2.368 -0.771)
        (xy -2.368 -0.834)
        (xy -2.368 -1.148)
        (xy -2.356 -1.155)
        (xy -2.349 -1.158)
        (xy -2.333 -1.162)
        (xy -2.309 -1.167)
        (xy -2.278 -1.173)
        (xy -2.24 -1.181)
        (xy -2.197 -1.189)
        (xy -2.149 -1.198)
        (xy -2.098 -1.208)
        (xy -2.051 -1.217)
        (xy -1.996 -1.227)
        (xy -1.945 -1.237)
        (xy -1.897 -1.246)
        (xy -1.854 -1.254)
        (xy -1.817 -1.262)
        (xy -1.787 -1.268)
        (xy -1.764 -1.273)
        (xy -1.75 -1.277)
        (xy -1.745 -1.279)
        (xy -1.741 -1.285)
        (xy -1.733 -1.3)
        (xy -1.722 -1.322)
        (xy -1.709 -1.35)
        (xy -1.694 -1.382)
        (xy -1.677 -1.419)
        (xy -1.66 -1.458)
        (xy -1.642 -1.498)
        (xy -1.625 -1.539)
        (xy -1.608 -1.58)
        (xy -1.592 -1.618)
        (xy -1.578 -1.653)
        (xy -1.565 -1.684)
        (xy -1.556 -1.709)
        (xy -1.549 -1.729)
        (xy -1.546 -1.74)
        (xy -1.546 -1.742)
        (xy -1.549 -1.749)
        (xy -1.558 -1.763)
        (xy -1.571 -1.784)
        (xy -1.588 -1.811)
        (xy -1.61 -1.843)
        (xy -1.634 -1.88)
        (xy -1.661 -1.92)
        (xy -1.691 -1.963)
        (xy -1.722 -2.008)
        (xy -1.762 -2.067)
        (xy -1.796 -2.117)
        (xy -1.825 -2.16)
        (xy -1.848 -2.196)
        (xy -1.867 -2.225)
        (xy -1.881 -2.247)
        (xy -1.89 -2.262)
        (xy -1.895 -2.272)
        (xy -1.895 -2.275)
        (xy -1.894 -2.279)
        (xy -1.891 -2.285)
        (xy -1.884 -2.293)
        (xy -1.875 -2.305)
        (xy -1.861 -2.32)
        (xy -1.843 -2.339)
        (xy -1.82 -2.363)
        (xy -1.792 -2.392)
        (xy -1.758 -2.426)
        (xy -1.718 -2.466)
        (xy -1.676 -2.509)
        (xy -1.627 -2.557)
        (xy -1.585 -2.599)
        (xy -1.549 -2.634)
        (xy -1.52 -2.663)
        (xy -1.495 -2.686)
        (xy -1.476 -2.704)
        (xy -1.462 -2.716)
        (xy -1.452 -2.724)
        (xy -1.446 -2.728)
        (xy -1.444 -2.728)
        (xy -1.437 -2.726)
        (xy -1.423 -2.717)
        (xy -1.401 -2.703)
        (xy -1.372 -2.685)
        (xy -1.337 -2.661)
        (xy -1.295 -2.634)
        (xy -1.248 -2.602)
        (xy -1.196 -2.566)
        (xy -1.173 -2.551)
        (xy -1.118 -2.513)
        (xy -1.071 -2.481)
        (xy -1.031 -2.454)
        (xy -0.998 -2.432)
        (xy -0.97 -2.413)
        (xy -0.948 -2.399)
        (xy -0.931 -2.389)
        (xy -0.917 -2.381)
        (xy -0.907 -2.376)
        (xy -0.901 -2.373)
        (xy -0.897 -2.373)
        (xy -0.888 -2.375)
        (xy -0.87 -2.38)
        (xy -0.845 -2.39)
        (xy -0.813 -2.402)
        (xy -0.774 -2.417)
        (xy -0.73 -2.434)
        (xy -0.681 -2.454)
        (xy -0.629 -2.475)
        (xy -0.586 -2.493)
        (xy -0.55 -2.508)
        (xy -0.522 -2.52)
        (xy -0.499 -2.529)
        (xy -0.482 -2.537)
        (xy -0.47 -2.543)
        (xy -0.461 -2.548)
        (xy -0.455 -2.551)
        (xy -0.452 -2.554)
        (xy -0.449 -2.557)
        (xy -0.448 -2.56)
        (xy -0.447 -2.566)
        (xy -0.443 -2.582)
        (xy -0.438 -2.605)
        (xy -0.432 -2.637)
        (xy -0.425 -2.674)
        (xy -0.417 -2.717)
        (xy -0.407 -2.765)
        (xy -0.398 -2.817)
        (xy -0.388 -2.871)
        (xy -0.387 -2.876)
        (xy -0.375 -2.94)
        (xy -0.364 -2.995)
        (xy -0.356 -3.042)
        (xy -0.348 -3.081)
        (xy -0.342 -3.112)
        (xy -0.337 -3.137)
        (xy -0.332 -3.157)
        (xy -0.328 -3.171)
        (xy -0.325 -3.181)
        (xy -0.323 -3.188)
        (xy -0.32 -3.191)
        (xy -0.32 -3.192)
        (xy -0.317 -3.194)
        (xy -0.313 -3.195)
        (xy -0.307 -3.197)
        (xy -0.298 -3.198)
        (xy -0.286 -3.199)
        (xy -0.269 -3.199)
        (xy -0.247 -3.2)
        (xy -0.219 -3.2)
        (xy -0.184 -3.201)
        (xy -0.142 -3.201)
        (xy -0.092 -3.201)
        (xy -0.033 -3.201)
        (xy -0.001 -3.201)
        (xy 0.063 -3.201)
      )

      (stroke (width 0.01) (type solid)) (fill solid) (layer "F.Mask"))
  )

  (footprint "kria-k26-devboard-footprints:CONV_PDQE30-Q48-S5-D" (layer "F.Cu")
    (at 187.658 90.642 -90)
    (property "Author" "Antmicro")
    (property "License" "Apache-2.0")
    (property "MPN" "PDQE30-Q48-S12-D")
    (property "Manufacturer" "CUI Inc")
    (property "Sheetfile" "PoE.kicad_sch")
    (property "Sheetname" "PoE")
    (property "ki_description" "Isolated Through Hole DC/DC Converter, ITE, 4:1, 30 W, 1 Output, 12 V, 2.5 A")
    (property "ki_keywords" "THT, PMIC, IC, DC-DC, CONVERTER")
    (attr through_hole)
    (fp_text reference "PS1" (at 0 -3.726 -90) (layer "F.SilkS")
        (effects (font (size 0.7 0.7) (thickness 0.15)) (justify left bottom))
    )
    (fp_text value "PDQE30-Q48-S12-D" (at 10.32 24.312 -90) (layer "F.Fab") hide
        (effects (font (size 0.7 0.7) (thickness 0.15)) (justify left bottom))
    )
    (fp_text user "Author: Antmicro" (at -3.912 26.312 -90) (layer "F.Fab") hide
        (effects (font (size 0.7 0.7) (thickness 0.15)) (justify left bottom))
    )
    (fp_text user "License: Apache-2.0" (at -3.912 27.51 -90) (layer "F.Fab") hide
        (effects (font (size 0.7 0.7) (thickness 0.15)) (justify left bottom))
    )
    (fp_text user "${REFERENCE}" (at -3.912 28.711 -90) (layer "F.Fab") hide
        (effects (font (size 0.7 0.7) (thickness 0.15)) (justify left bottom))
    )
    (fp_line (start -2.54 -2.54) (end 22.859 -2.54)
      (stroke (width 0.15) (type solid)) (layer "F.SilkS"))
    (fp_line (start -2.54 22.859) (end -2.54 -2.54)
      (stroke (width 0.15) (type solid)) (layer "F.SilkS"))
    (fp_line (start 22.859 -2.54) (end 22.859 22.859)
      (stroke (width 0.15) (type solid)) (layer "F.SilkS"))
    (fp_line (start 22.859 22.859) (end -2.54 22.859)
      (stroke (width 0.15) (type solid)) (layer "F.SilkS"))
    (fp_circle (center -2.921 0) (end -2.82 0)
      (stroke (width 0.15) (type solid)) (fill none) (layer "F.SilkS"))
    (fp_circle (center 0 -3.84) (end 0.05 -3.84)
      (stroke (width 0.15) (type solid)) (fill solid) (layer "F.SilkS"))
    (fp_circle (center 0 -3.84) (end 0.05 -3.84)
      (stroke (width 0.15) (type solid)) (fill solid) (layer "F.SilkS"))
    (fp_rect (start -2.667 -2.667) (end 22.987 22.987)
      (stroke (width 0.05) (type solid)) (fill none) (layer "F.CrtYd"))
    (fp_line (start -2.54 -2.54) (end 22.859 -2.54)
      (stroke (width 0.15) (type solid)) (layer "F.Fab"))
    (fp_line (start -2.54 22.859) (end -2.54 -2.54)
      (stroke (width 0.15) (type solid)) (layer "F.Fab"))
    (fp_line (start 22.859 -2.54) (end 22.859 22.859)
      (stroke (width 0.15) (type solid)) (layer "F.Fab"))
    (fp_line (start 22.859 22.859) (end -2.54 22.859)
      (stroke (width 0.15) (type solid)) (layer "F.Fab"))
    (fp_circle (center -2.921 0) (end -2.82 0)
      (stroke (width 0.15) (type solid)) (fill none) (layer "F.Fab"))
    (pad "1" thru_hole rect (at 0 0 270) (size 2.25 2.25) (drill 1.5) (layers "*.Cu" "*.Mask")
      (net 12 "/Power Supply/PoE/POE_ACTIVE") (pinfunction "CTRL") (pintype "input"))
    (pad "2" thru_hole circle (at 0 7.618 270) (size 2.25 2.25) (drill 1.5) (layers "*.Cu" "*.Mask")
      (net 11 "GNDD") (pinfunction "GND") (pintype "power_in"))
    (pad "3" thru_hole circle (at 0 12.698 270) (size 2.25 2.25) (drill 1.5) (layers "*.Cu" "*.Mask")
      (net 9 "/Power Supply/PoE/VDD_POE_IN") (pinfunction "V_{IN}") (pintype "power_in"))
    (pad "4" thru_hole circle (at 20.318 20.318 270) (size 2.25 2.25) (drill 1.5) (layers "*.Cu" "*.Mask")
      (net 13 "/Power Supply/PoE/POE_12V") (pinfunction "V_{O}") (pintype "power_out"))
    (pad "5" thru_hole circle (at 20.318 10.159 270) (size 2.25 2.25) (drill 1.5) (layers "*.Cu" "*.Mask")
      (net 414 "unconnected-(PS1-TRIM-Pad5)") (pinfunction "TRIM") (pintype "passive+no_connect"))
    (pad "6" thru_hole circle (at 20.318 0 270) (size 2.25 2.25) (drill 1.5) (layers "*.Cu" "*.Mask")
      (net 1 "GND") (pinfunction "0V") (pintype "power_out"))
  )

  (footprint "kria-k26-devboard-footprints:R_0402_1005Metric" (layer "F.Cu")
    (at 154.33 67.55 90)
    (descr "Resistor SMD 0402")
    (tags "resistor SMD 0402")
    (property "Author" "Antmicro")
    (property "License" "Apache-2.0")
    (property "MPN" "CR0402-FX-3300GLF")
    (property "Manufacturer" "Bourns")
    (property "Sheetfile" "eth.kicad_sch")
    (property "Sheetname" "Ethernet")
    (property "Tolerance" "1%")
    (property "Val" "330R")
    (property "ki_description" "330R resistor in 0402 package with 1% tolerance")
    (attr smd)
    (fp_text reference "R77" (at 2.3 0.92 90) (layer "F.SilkS")
        (effects (font (size 0.7 0.7) (thickness 0.15)) (justify left bottom))
    )
    (fp_text value "R_330R_0402" (at 0 1.4 90) (layer "F.Fab") hide
        (effects (font (size 0.7 0.7) (thickness 0.15)) (justify left bottom))
    )
    (fp_text user "${REFERENCE}" (at -0.95 3.168 90) (layer "F.Fab") hide
        (effects (font (size 0.7 0.7) (thickness 0.15)) (justify left bottom))
    )
    (fp_text user "License: Apache-2.0" (at -0.95 5.169 90) (layer "F.Fab") hide
        (effects (font (size 0.7 0.7) (thickness 0.15)) (justify left bottom))
    )
    (fp_text user "Author: Antmicro" (at -0.95 4.169 90) (layer "F.Fab") hide
        (effects (font (size 0.7 0.7) (thickness 0.15)) (justify left bottom))
    )
    (fp_rect (start -0.93 -0.47) (end 0.93 0.47)
      (stroke (width 0.05) (type solid)) (fill none) (layer "F.CrtYd"))
    (fp_rect (start -0.5 -0.25) (end 0.5 0.25)
      (stroke (width 0.15) (type solid)) (fill none) (layer "F.Fab"))
    (pad "1" smd roundrect (at -0.485 0 90) (size 0.59 0.64) (layers "F.Cu" "F.Paste" "F.Mask") (roundrect_rratio 0.25)
      (net 16 "PS_2V5") (pintype "passive"))
    (pad "2" smd roundrect (at 0.485 0 90) (size 0.59 0.64) (layers "F.Cu" "F.Paste" "F.Mask") (roundrect_rratio 0.25)
      (net 350 "Net-(J5-LED_GRN+)") (pintype "passive"))
  )

  (footprint "kria-k26-devboard-footprints:R_0402_1005Metric" (layer "F.Cu")
    (at 153.27 67.57 90)
    (descr "Resistor SMD 0402")
    (tags "resistor SMD 0402")
    (property "Author" "Antmicro")
    (property "License" "Apache-2.0")
    (property "MPN" "CR0402-FX-3300GLF")
    (property "Manufacturer" "Bourns")
    (property "Sheetfile" "eth.kicad_sch")
    (property "Sheetname" "Ethernet")
    (property "Tolerance" "1%")
    (property "Val" "330R")
    (property "ki_description" "330R resistor in 0402 package with 1% tolerance")
    (attr smd)
    (fp_text reference "R78" (at 2.3 0.92 90) (layer "F.SilkS")
        (effects (font (size 0.7 0.7) (thickness 0.15)) (justify left bottom))
    )
    (fp_text value "R_330R_0402" (at 0 1.4 90) (layer "F.Fab") hide
        (effects (font (size 0.7 0.7) (thickness 0.15)) (justify left bottom))
    )
    (fp_text user "License: Apache-2.0" (at -0.95 5.169 90) (layer "F.Fab") hide
        (effects (font (size 0.7 0.7) (thickness 0.15)) (justify left bottom))
    )
    (fp_text user "${REFERENCE}" (at -0.95 3.168 90) (layer "F.Fab") hide
        (effects (font (size 0.7 0.7) (thickness 0.15)) (justify left bottom))
    )
    (fp_text user "Author: Antmicro" (at -0.95 4.169 90) (layer "F.Fab") hide
        (effects (font (size 0.7 0.7) (thickness 0.15)) (justify left bottom))
    )
    (fp_rect (start -0.93 -0.47) (end 0.93 0.47)
      (stroke (width 0.05) (type solid)) (fill none) (layer "F.CrtYd"))
    (fp_rect (start -0.5 -0.25) (end 0.5 0.25)
      (stroke (width 0.15) (type solid)) (fill none) (layer "F.Fab"))
    (pad "1" smd roundrect (at -0.485 0 90) (size 0.59 0.64) (layers "F.Cu" "F.Paste" "F.Mask") (roundrect_rratio 0.25)
      (net 16 "PS_2V5") (pintype "passive"))
    (pad "2" smd roundrect (at 0.485 0 90) (size 0.59 0.64) (layers "F.Cu" "F.Paste" "F.Mask") (roundrect_rratio 0.25)
      (net 352 "Net-(J5-LED_YEL+)") (pintype "passive"))
  )

  (footprint "kria-k26-devboard-footprints:R_0402_1005Metric" (layer "F.Cu")
    (at 122 95.3)
    (descr "Resistor SMD 0402")
    (tags "resistor SMD 0402")
    (property "Author" "Antmicro")
    (property "License" "Apache-2.0")
    (property "MPN" "CR0402-FX-1002GLF")
    (property "Manufacturer" "Bourns")
    (property "Sheetfile" "usb.kicad_sch")
    (property "Sheetname" "USB")
    (property "Tolerance" "1%")
    (property "Val" "10k")
    (property "ki_description" "10k resistor in 0402 package with 1% tolerance")
    (attr smd)
    (fp_text reference "R66" (at 0.84 0.31) (layer "F.SilkS")
        (effects (font (size 0.7 0.7) (thickness 0.15)) (justify left bottom))
    )
    (fp_text value "R_10k_0402" (at 0 1.4) (layer "F.Fab") hide
        (effects (font (size 0.7 0.7) (thickness 0.15)) (justify left bottom))
    )
    (fp_text user "License: Apache-2.0" (at -0.95 5.169) (layer "F.Fab") hide
        (effects (font (size 0.7 0.7) (thickness 0.15)) (justify left bottom))
    )
    (fp_text user "${REFERENCE}" (at -0.95 3.168) (layer "F.Fab") hide
        (effects (font (size 0.7 0.7) (thickness 0.15)) (justify left bottom))
    )
    (fp_text user "Author: Antmicro" (at -0.95 4.169) (layer "F.Fab") hide
        (effects (font (size 0.7 0.7) (thickness 0.15)) (justify left bottom))
    )
    (fp_rect (start -0.93 -0.47) (end 0.93 0.47)
      (stroke (width 0.05) (type solid)) (fill none) (layer "F.CrtYd"))
    (fp_rect (start -0.5 -0.25) (end 0.5 0.25)
      (stroke (width 0.15) (type solid)) (fill none) (layer "F.Fab"))
    (pad "1" smd roundrect (at -0.485 0) (size 0.59 0.64) (layers "F.Cu" "F.Paste" "F.Mask") (roundrect_rratio 0.25)
      (net 8 "SOM_5V0") (pintype "passive"))
    (pad "2" smd roundrect (at 0.485 0) (size 0.59 0.64) (layers "F.Cu" "F.Paste" "F.Mask") (roundrect_rratio 0.25)
      (net 669 "Net-(U23-VBUS)") (pintype "passive"))
  )

  (footprint "kria-k26-devboard-footprints:R_0402_1005Metric" (layer "F.Cu")
    (at 125.69 137.6 180)
    (descr "Resistor SMD 0402")
    (tags "resistor SMD 0402")
    (property "Author" "Antmicro")
    (property "License" "Apache-2.0")
    (property "MPN" "CR0402-FX-1002GLF")
    (property "Manufacturer" "Bourns")
    (property "Sheetfile" "sd-3-card.kicad_sch")
    (property "Sheetname" "SD 3.0 card")
    (property "Tolerance" "1%")
    (property "Val" "10k")
    (property "ki_description" "10k resistor in 0402 package with 1% tolerance")
    (attr smd)
    (fp_text reference "R18" (at 1.11 0.43 180) (layer "F.SilkS")
        (effects (font (size 0.7 0.7) (thickness 0.15)) (justify left bottom))
    )
    (fp_text value "R_10k_0402" (at 0 1.4 180) (layer "F.Fab") hide
        (effects (font (size 0.7 0.7) (thickness 0.15)) (justify left bottom))
    )
    (fp_text user "License: Apache-2.0" (at -0.95 5.169 180) (layer "F.Fab") hide
        (effects (font (size 0.7 0.7) (thickness 0.15)) (justify left bottom))
    )
    (fp_text user "${REFERENCE}" (at -0.95 3.168 180) (layer "F.Fab") hide
        (effects (font (size 0.7 0.7) (thickness 0.15)) (justify left bottom))
    )
    (fp_text user "Author: Antmicro" (at -0.95 4.169 180) (layer "F.Fab") hide
        (effects (font (size 0.7 0.7) (thickness 0.15)) (justify left bottom))
    )
    (fp_rect (start -0.93 -0.47) (end 0.93 0.47)
      (stroke (width 0.05) (type solid)) (fill none) (layer "F.CrtYd"))
    (fp_rect (start -0.5 -0.25) (end 0.5 0.25)
      (stroke (width 0.15) (type solid)) (fill none) (layer "F.Fab"))
    (pad "1" smd roundrect (at -0.485 0 180) (size 0.59 0.64) (layers "F.Cu" "F.Paste" "F.Mask") (roundrect_rratio 0.25)
      (net 17 "PS_1V8") (pintype "passive"))
    (pad "2" smd roundrect (at 0.485 0 180) (size 0.59 0.64) (layers "F.Cu" "F.Paste" "F.Mask") (roundrect_rratio 0.25)
      (net 106 "/SD 3.0 card/MIO45") (pintype "passive"))
  )

  (footprint "kria-k26-devboard-footprints:R_0402_1005Metric" (layer "F.Cu")
    (at 145.625 109.575 180)
    (descr "Resistor SMD 0402")
    (tags "resistor SMD 0402")
    (property "Author" "Antmicro")
    (property "License" "Apache-2.0")
    (property "MPN" "CR0402-FX-1003GLF")
    (property "Manufacturer" "Bourns")
    (property "Sheetfile" "debug.kicad_sch")
    (property "Sheetname" "Debug and JTAG")
    (property "Tolerance" "1%")
    (property "Val" "100k")
    (property "ki_description" "100k resistor in 0402 package with 1% tolerance")
    (attr smd)
    (fp_text reference "R104" (at -0.785 0.465 270) (layer "F.SilkS")
        (effects (font (size 0.7 0.7) (thickness 0.15)) (justify left bottom))
    )
    (fp_text value "R_100k_0402" (at 0 1.4 180) (layer "F.Fab") hide
        (effects (font (size 0.7 0.7) (thickness 0.15)) (justify left bottom))
    )
    (fp_text user "${REFERENCE}" (at -0.95 3.168 180) (layer "F.Fab") hide
        (effects (font (size 0.7 0.7) (thickness 0.15)) (justify left bottom))
    )
    (fp_text user "Author: Antmicro" (at -0.95 4.169 180) (layer "F.Fab") hide
        (effects (font (size 0.7 0.7) (thickness 0.15)) (justify left bottom))
    )
    (fp_text user "License: Apache-2.0" (at -0.95 5.169 180) (layer "F.Fab") hide
        (effects (font (size 0.7 0.7) (thickness 0.15)) (justify left bottom))
    )
    (fp_rect (start -0.93 -0.47) (end 0.93 0.47)
      (stroke (width 0.05) (type solid)) (fill none) (layer "F.CrtYd"))
    (fp_rect (start -0.5 -0.25) (end 0.5 0.25)
      (stroke (width 0.15) (type solid)) (fill none) (layer "F.Fab"))
    (pad "1" smd roundrect (at -0.485 0 180) (size 0.59 0.64) (layers "F.Cu" "F.Paste" "F.Mask") (roundrect_rratio 0.25)
      (net 265 "/Debug and JTAG/USBC_VBUS") (pintype "passive"))
    (pad "2" smd roundrect (at 0.485 0 180) (size 0.59 0.64) (layers "F.Cu" "F.Paste" "F.Mask") (roundrect_rratio 0.25)
      (net 136 "/Debug and JTAG/PD1_SVBUS") (pintype "passive"))
  )

  (footprint "kria-k26-devboard-footprints:R_0603_1608Metric" (layer "F.Cu")
    (at 143.4 109.575 180)
    (descr "Resistor SMD 0603")
    (tags "resistor SMD 0603")
    (property "Author" "Antmicro")
    (property "License" "Apache-2.0")
    (property "MPN" "CR0603-FX-1502ELF")
    (property "Manufacturer" "Bourns")
    (property "Sheetfile" "debug.kicad_sch")
    (property "Sheetname" "Debug and JTAG")
    (property "Tolerance" "1%")
    (property "Val" "15k")
    (property "ki_description" "15k resistor in 0603 package with 1% tolerance")
    (attr smd)
    (fp_text reference "R105" (at 1.89 1.825 180) (layer "F.SilkS")
        (effects (font (size 0.7 0.7) (thickness 0.15)) (justify left bottom))
    )
    (fp_text value "R_15k_0603" (at 0 1.6 180) (layer "F.Fab") hide
        (effects (font (size 0.7 0.7) (thickness 0.15)) (justify left bottom))
    )
    (fp_text user "${REFERENCE}" (at -1.25 3.898 180) (layer "F.Fab") hide
        (effects (font (size 0.7 0.7) (thickness 0.15)) (justify left bottom))
    )
    (fp_text user "License: Apache-2.0" (at -1.25 5.9 180) (layer "F.Fab") hide
        (effects (font (size 0.7 0.7) (thickness 0.15)) (justify left bottom))
    )
    (fp_text user "Author: Antmicro" (at -1.25 4.9 180) (layer "F.Fab") hide
        (effects (font (size 0.7 0.7) (thickness 0.15)) (justify left bottom))
    )
    (fp_line (start -0.3 -0.3) (end 0.3 -0.3)
      (stroke (width 0.15) (type solid)) (layer "F.SilkS"))
    (fp_line (start -0.3 0.3) (end 0.3 0.3)
      (stroke (width 0.15) (type solid)) (layer "F.SilkS"))
    (fp_rect (start -1.25 -0.7) (end 1.25 0.7)
      (stroke (width 0.05) (type solid)) (fill none) (layer "F.CrtYd"))
    (fp_rect (start -0.8 -0.4) (end 0.8 0.4)
      (stroke (width 0.15) (type solid)) (fill none) (layer "F.Fab"))
    (pad "1" smd roundrect (at -0.7 0 180) (size 0.6 0.8) (layers "F.Cu" "F.Paste" "F.Mask") (roundrect_rratio 0.2)
      (net 136 "/Debug and JTAG/PD1_SVBUS") (pintype "passive"))
    (pad "2" smd roundrect (at 0.7 0 180) (size 0.6 0.8) (layers "F.Cu" "F.Paste" "F.Mask") (roundrect_rratio 0.2)
      (net 1 "GND") (pintype "passive"))
  )

  (footprint "kria-k26-devboard-footprints:R_0402_1005Metric" (layer "F.Cu")
    (at 118.8 118.8 180)
    (descr "Resistor SMD 0402")
    (tags "resistor SMD 0402")
    (property "Author" "Antmicro")
    (property "License" "Apache-2.0")
    (property "MPN" "CR0402-FX-1002GLF")
    (property "Manufacturer" "Bourns")
    (property "Sheetfile" "clock.kicad_sch")
    (property "Sheetname" "Clock distribution")
    (property "Tolerance" "1%")
    (property "Val" "10k")
    (property "ki_description" "10k resistor in 0402 package with 1% tolerance")
    (attr smd)
    (fp_text reference "R19" (at 0.98 0.53 180) (layer "F.SilkS")
        (effects (font (size 0.7 0.7) (thickness 0.15)) (justify left bottom))
    )
    (fp_text value "R_10k_0402" (at 0 1.4 180) (layer "F.Fab") hide
        (effects (font (size 0.7 0.7) (thickness 0.15)) (justify left bottom))
    )
    (fp_text user "License: Apache-2.0" (at -0.95 5.169 180) (layer "F.Fab") hide
        (effects (font (size 0.7 0.7) (thickness 0.15)) (justify left bottom))
    )
    (fp_text user "${REFERENCE}" (at -0.95 3.168 180) (layer "F.Fab") hide
        (effects (font (size 0.7 0.7) (thickness 0.15)) (justify left bottom))
    )
    (fp_text user "Author: Antmicro" (at -0.95 4.169 180) (layer "F.Fab") hide
        (effects (font (size 0.7 0.7) (thickness 0.15)) (justify left bottom))
    )
    (fp_rect (start -0.93 -0.47) (end 0.93 0.47)
      (stroke (width 0.05) (type solid)) (fill none) (layer "F.CrtYd"))
    (fp_rect (start -0.5 -0.25) (end 0.5 0.25)
      (stroke (width 0.15) (type solid)) (fill none) (layer "F.Fab"))
    (pad "1" smd roundrect (at -0.485 0 180) (size 0.59 0.64) (layers "F.Cu" "F.Paste" "F.Mask") (roundrect_rratio 0.25)
      (net 15 "PS_3V3") (pintype "passive"))
    (pad "2" smd roundrect (at 0.485 0 180) (size 0.59 0.64) (layers "F.Cu" "F.Paste" "F.Mask") (roundrect_rratio 0.25)
      (net 429 "Net-(Q3-C)") (pintype "passive"))
  )

  (footprint "kria-k26-devboard-footprints:R_0402_1005Metric" (layer "F.Cu")
    (at 109.35 136.01 90)
    (descr "Resistor SMD 0402")
    (tags "resistor SMD 0402")
    (property "Author" "Antmicro")
    (property "License" "Apache-2.0")
    (property "MPN" "CR0402-FX-1002GLF")
    (property "Manufacturer" "Bourns")
    (property "Sheetfile" "reset.kicad_sch")
    (property "Sheetname" "Reset logic")
    (property "Tolerance" "1%")
    (property "Val" "10k")
    (property "ki_description" "10k resistor in 0402 package with 1% tolerance")
    (attr smd)
    (fp_text reference "R84" (at 0.74 0.35 90) (layer "F.SilkS")
        (effects (font (size 0.7 0.7) (thickness 0.15)) (justify left bottom))
    )
    (fp_text value "R_10k_0402" (at 0 1.4 90) (layer "F.Fab") hide
        (effects (font (size 0.7 0.7) (thickness 0.15)) (justify left bottom))
    )
    (fp_text user "License: Apache-2.0" (at -0.95 5.169 90) (layer "F.Fab") hide
        (effects (font (size 0.7 0.7) (thickness 0.15)) (justify left bottom))
    )
    (fp_text user "Author: Antmicro" (at -0.95 4.169 90) (layer "F.Fab") hide
        (effects (font (size 0.7 0.7) (thickness 0.15)) (justify left bottom))
    )
    (fp_text user "${REFERENCE}" (at -0.95 3.168 90) (layer "F.Fab") hide
        (effects (font (size 0.7 0.7) (thickness 0.15)) (justify left bottom))
    )
    (fp_rect (start -0.93 -0.47) (end 0.93 0.47)
      (stroke (width 0.05) (type solid)) (fill none) (layer "F.CrtYd"))
    (fp_rect (start -0.5 -0.25) (end 0.5 0.25)
      (stroke (width 0.15) (type solid)) (fill none) (layer "F.Fab"))
    (pad "1" smd roundrect (at -0.485 0 90) (size 0.59 0.64) (layers "F.Cu" "F.Paste" "F.Mask") (roundrect_rratio 0.25)
      (net 17 "PS_1V8") (pintype "passive"))
    (pad "2" smd roundrect (at 0.485 0 90) (size 0.59 0.64) (layers "F.Cu" "F.Paste" "F.Mask") (roundrect_rratio 0.25)
      (net 151 "/Debug and JTAG/~{PS_POR}") (pintype "passive"))
  )

  (footprint "kria-k26-devboard-footprints:R_0402_1005Metric" (layer "F.Cu")
    (at 87.3 117.8 180)
    (descr "Resistor SMD 0402")
    (tags "resistor SMD 0402")
    (property "Author" "Antmicro")
    (property "License" "Apache-2.0")
    (property "MPN" "CR0402-FX-4700GLF")
    (property "Manufacturer" "Bourns")
    (property "Sheetfile" "k26_som.kicad_sch")
    (property "Sheetname" "Xilinx K26 SOM")
    (property "Tolerance" "1%")
    (property "Val" "470R")
    (property "ki_description" "470R resistor in 0402 package with 1% tolerance")
    (attr smd)
    (fp_text reference "R80" (at 0.81 5.32 180) (layer "F.SilkS")
        (effects (font (size 0.7 0.7) (thickness 0.15)) (justify left bottom))
    )
    (fp_text value "R_470R_0402" (at 0 1.4 180) (layer "F.Fab") hide
        (effects (font (size 0.7 0.7) (thickness 0.15)) (justify left bottom))
    )
    (fp_text user "License: Apache-2.0" (at -0.95 5.169 180) (layer "F.Fab") hide
        (effects (font (size 0.7 0.7) (thickness 0.15)) (justify left bottom))
    )
    (fp_text user "Author: Antmicro" (at -0.95 4.169 180) (layer "F.Fab") hide
        (effects (font (size 0.7 0.7) (thickness 0.15)) (justify left bottom))
    )
    (fp_text user "${REFERENCE}" (at -0.95 3.168 180) (layer "F.Fab") hide
        (effects (font (size 0.7 0.7) (thickness 0.15)) (justify left bottom))
    )
    (fp_rect (start -0.93 -0.47) (end 0.93 0.47)
      (stroke (width 0.05) (type solid)) (fill none) (layer "F.CrtYd"))
    (fp_rect (start -0.5 -0.25) (end 0.5 0.25)
      (stroke (width 0.15) (type solid)) (fill none) (layer "F.Fab"))
    (pad "1" smd roundrect (at -0.485 0 180) (size 0.59 0.64) (layers "F.Cu" "F.Paste" "F.Mask") (roundrect_rratio 0.25)
      (net 4 "/Xilinx K26 SOM/MODE2_C2M") (pintype "passive"))
    (pad "2" smd roundrect (at 0.485 0 180) (size 0.59 0.64) (layers "F.Cu" "F.Paste" "F.Mask") (roundrect_rratio 0.25)
      (net 1 "GND") (pintype "passive"))
  )

  (footprint "kria-k26-devboard-footprints:R_0402_1005Metric" (layer "F.Cu")
    (at 87.29 118.78 180)
    (descr "Resistor SMD 0402")
    (tags "resistor SMD 0402")
    (property "Author" "Antmicro")
    (property "DNP" "DNP")
    (property "License" "Apache-2.0")
    (property "MPN" "CR0402-FX-4700GLF")
    (property "Manufacturer" "Bourns")
    (property "Sheetfile" "k26_som.kicad_sch")
    (property "Sheetname" "Xilinx K26 SOM")
    (property "Tolerance" "1%")
    (property "Val" "470R")
    (property "dnp" "")
    (property "exclude_from_bom" "")
    (property "ki_description" "470R resistor in 0402 package with 1% tolerance")
    (attr exclude_from_pos_files exclude_from_bom)
    (fp_text reference "R81" (at 0.81 5.32 180) (layer "F.SilkS")
        (effects (font (size 0.7 0.7) (thickness 0.15)) (justify left bottom))
    )
    (fp_text value "R_470R_0402" (at 0 1.4 180) (layer "F.Fab") hide
        (effects (font (size 0.7 0.7) (thickness 0.15)) (justify left bottom))
    )
    (fp_text user "Author: Antmicro" (at -0.95 4.169 180) (layer "F.Fab") hide
        (effects (font (size 0.7 0.7) (thickness 0.15)) (justify left bottom))
    )
    (fp_text user "${REFERENCE}" (at -0.95 3.168 180) (layer "F.Fab") hide
        (effects (font (size 0.7 0.7) (thickness 0.15)) (justify left bottom))
    )
    (fp_text user "License: Apache-2.0" (at -0.95 5.169 180) (layer "F.Fab") hide
        (effects (font (size 0.7 0.7) (thickness 0.15)) (justify left bottom))
    )
    (fp_rect (start -0.93 -0.47) (end 0.93 0.47)
      (stroke (width 0.05) (type solid)) (fill none) (layer "F.CrtYd"))
    (fp_rect (start -0.5 -0.25) (end 0.5 0.25)
      (stroke (width 0.15) (type solid)) (fill none) (layer "F.Fab"))
    (pad "1" smd roundrect (at -0.485 0 180) (size 0.59 0.64) (layers "F.Cu" "F.Paste" "F.Mask") (roundrect_rratio 0.25)
      (net 3 "/Xilinx K26 SOM/MODE1_C2M") (pintype "passive"))
    (pad "2" smd roundrect (at 0.485 0 180) (size 0.59 0.64) (layers "F.Cu" "F.Paste" "F.Mask") (roundrect_rratio 0.25)
      (net 1 "GND") (pintype "passive"))
  )

  (footprint "kria-k26-devboard-footprints:R_0402_1005Metric" (layer "F.Cu")
    (at 87.29 119.77 180)
    (descr "Resistor SMD 0402")
    (tags "resistor SMD 0402")
    (property "Author" "Antmicro")
    (property "License" "Apache-2.0")
    (property "MPN" "CR0402-FX-4700GLF")
    (property "Manufacturer" "Bourns")
    (property "Sheetfile" "k26_som.kicad_sch")
    (property "Sheetname" "Xilinx K26 SOM")
    (property "Tolerance" "1%")
    (property "Val" "470R")
    (property "ki_description" "470R resistor in 0402 package with 1% tolerance")
    (attr smd)
    (fp_text reference "R82" (at 0.81 5.32 180) (layer "F.SilkS")
        (effects (font (size 0.7 0.7) (thickness 0.15)) (justify left bottom))
    )
    (fp_text value "R_470R_0402" (at 0 1.4 180) (layer "F.Fab") hide
        (effects (font (size 0.7 0.7) (thickness 0.15)) (justify left bottom))
    )
    (fp_text user "Author: Antmicro" (at -0.95 4.169 180) (layer "F.Fab") hide
        (effects (font (size 0.7 0.7) (thickness 0.15)) (justify left bottom))
    )
    (fp_text user "${REFERENCE}" (at -0.95 3.168 180) (layer "F.Fab") hide
        (effects (font (size 0.7 0.7) (thickness 0.15)) (justify left bottom))
    )
    (fp_text user "License: Apache-2.0" (at -0.95 5.169 180) (layer "F.Fab") hide
        (effects (font (size 0.7 0.7) (thickness 0.15)) (justify left bottom))
    )
    (fp_rect (start -0.93 -0.47) (end 0.93 0.47)
      (stroke (width 0.05) (type solid)) (fill none) (layer "F.CrtYd"))
    (fp_rect (start -0.5 -0.25) (end 0.5 0.25)
      (stroke (width 0.15) (type solid)) (fill none) (layer "F.Fab"))
    (pad "1" smd roundrect (at -0.485 0 180) (size 0.59 0.64) (layers "F.Cu" "F.Paste" "F.Mask") (roundrect_rratio 0.25)
      (net 2 "/Xilinx K26 SOM/MODE0_C2M") (pintype "passive"))
    (pad "2" smd roundrect (at 0.485 0 180) (size 0.59 0.64) (layers "F.Cu" "F.Paste" "F.Mask") (roundrect_rratio 0.25)
      (net 1 "GND") (pintype "passive"))
  )

  (footprint "kria-k26-devboard-footprints:Spacer_Drill4.45mm_H5mm_9774050960R" (layer "F.Cu")
    (at 160.206999 90.7935)
    (property "Author" "Antmicro")
    (property "License" "Apache-2.0")
    (property "MPN" "9774050960R")
    (property "Manufacturer" "Würth Elektronik")
    (property "Sheetfile" "k26_som.kicad_sch")
    (property "Sheetname" "Xilinx K26 SOM")
    (property "ki_description" "Spacer, SMT, Non Stop, Steel, Swage Round, 6 mm x 5 mm, 3.3 mm Internal, WA-SMST Series")
    (property "ki_keywords" "SPACER")
    (clearance 0.6)
    (attr smd)
    (fp_text reference "SP3" (at 0 -3.4) (layer "F.SilkS")
        (effects (font (size 0.7 0.7) (thickness 0.15)) (justify left bottom))
    )
    (fp_text value "Spacer_Drill4.45mm_H5mm_9774050960R" (at 0 4.2) (layer "F.Fab")
        (effects (font (size 0.7 0.7) (thickness 0.15)) (justify left bottom))
    )
    (fp_text user "${REFERENCE}" (at -3.25 7.4) (layer "F.Fab") hide
        (effects (font (size 0.7 0.7) (thickness 0.15)) (justify left bottom))
    )
    (fp_text user "Author: Antmicro" (at -3.25 8.6) (layer "F.Fab") hide
        (effects (font (size 0.7 0.7) (thickness 0.15)) (justify left bottom))
    )
    (fp_text user "License: Apache-2.0" (at -3.25 6.2) (layer "F.Fab") hide
        (effects (font (size 0.7 0.7) (thickness 0.15)) (justify left bottom))
    )
    (fp_circle (center 0 0) (end 3.25 0)
      (stroke (width 0.05) (type solid)) (fill none) (layer "F.CrtYd"))
    (fp_circle (center 0 0) (end 2.564 0)
      (stroke (width 0.15) (type solid)) (fill none) (layer "F.Fab"))
    (pad "1" thru_hole circle (at 0 0) (size 6 6) (drill 4.45) (layers "*.Cu" "*.Mask" "F.Paste")
      (net 1 "GND") (pintype "passive") (solder_paste_margin_ratio -0.05))
  )

  (footprint "kria-k26-devboard-footprints:SOT1161-2" (layer "F.Cu")
    (at 129.925 136.975 -90)
    (descr "SOT1161-2")
    (tags "Integrated Circuit")
    (property "Author" "Antmicro")
    (property "License" "Apache-2.0")
    (property "MPN" "NVT4858HKZ")
    (property "Manufacturer" "NXP")
    (property "Sheetfile" "sd-3-card.kicad_sch")
    (property "Sheetname" "SD 3.0 card")
    (property "ki_description" "Level Translator, 4 Input, 1.08 V to 1.98 V, xQFN-16")
    (property "ki_keywords" "SMT, LEVEL-SHIFTER, IC, LOGIC")
    (attr smd)
    (fp_text reference "U5" (at -1.415 1.175) (layer "F.SilkS")
        (effects (font (size 0.7 0.7) (thickness 0.15)) (justify left bottom))
    )
    (fp_text value "NVT4858_XQFN" (at 0 2.7 -90) (layer "F.Fab") hide
        (effects (font (size 0.7 0.7) (thickness 0.15)) (justify left bottom))
    )
    (fp_text user "Author: Antmicro" (at -1.5 4.498 -90) (layer "F.Fab") hide
        (effects (font (size 0.7 0.7) (thickness 0.15)) (justify left bottom))
    )
    (fp_text user "License: Apache-2.0" (at -1.5 5.7 -90) (layer "F.Fab") hide
        (effects (font (size 0.7 0.7) (thickness 0.15)) (justify left bottom))
    )
    (fp_line (start -0.902 0.9) (end -0.902 1.3)
      (stroke (width 0.15) (type solid)) (layer "F.SilkS"))
    (fp_line (start -0.9 -0.9) (end -0.9 -1.3)
      (stroke (width 0.15) (type solid)) (layer "F.SilkS"))
    (fp_line (start 0.9 -0.901) (end 0.9 -1.301)
      (stroke (width 0.15) (type solid)) (layer "F.SilkS"))
    (fp_line (start 0.9 0.9) (end 0.9 1.3)
      (stroke (width 0.15) (type solid)) (layer "F.SilkS"))
    (fp_circle (center -1.6 -1.7) (end -1.55 -1.7)
      (stroke (width 0.15) (type solid)) (fill solid) (layer "F.SilkS"))
    (fp_rect (start -1.3 -1.7) (end 1.3 1.7)
      (stroke (width 0.05) (type solid)) (fill none) (layer "F.CrtYd"))
    (fp_line (start -0.902 -1.301) (end 0.9 -1.301)
      (stroke (width 0.15) (type solid)) (layer "F.Fab"))
    (fp_line (start -0.902 1.3) (end -0.902 -1.301)
      (stroke (width 0.15) (type solid)) (layer "F.Fab"))
    (fp_line (start 0.9 -1.301) (end 0.9 1.3)
      (stroke (width 0.15) (type solid)) (layer "F.Fab"))
    (fp_line (start 0.9 1.3) (end -0.902 1.3)
      (stroke (width 0.15) (type solid)) (layer "F.Fab"))
    (pad "1" smd roundrect (at -0.6 -0.6) (size 0.22 0.9) (layers "F.Cu" "F.Paste" "F.Mask") (roundrect_rratio 0.25)
      (net 640 "Net-(R15-R2.2)") (pinfunction "DAT2_{A}") (pintype "bidirectional"))
    (pad "2" smd roundrect (at -0.625 -0.202) (size 0.22 0.9) (layers "F.Cu" "F.Paste" "F.Mask") (roundrect_rratio 0.25)
      (net 641 "Net-(R15-R1.2)") (pinfunction "DAT3_{A}") (pintype "bidirectional"))
    (pad "3" smd roundrect (at -0.625 0.2) (size 0.22 0.9) (layers "F.Cu" "F.Paste" "F.Mask") (roundrect_rratio 0.25)
      (net 638 "Net-(R15-R4.2)") (pinfunction "DAT0_{A}") (pintype "bidirectional"))
    (pad "4" smd roundrect (at -0.625 0.598) (size 0.22 0.9) (layers "F.Cu" "F.Paste" "F.Mask") (roundrect_rratio 0.25)
      (net 639 "Net-(R15-R3.2)") (pinfunction "DAT1_{A}") (pintype "bidirectional"))
    (pad "5" smd roundrect (at -0.6 1.175 270) (size 0.22 0.55) (layers "F.Cu" "F.Paste" "F.Mask") (roundrect_rratio 0.25)
      (net 436 "Net-(U5-CLK_{A})") (pinfunction "CLK_{A}") (pintype "input"))
    (pad "6" smd roundrect (at -0.202 1.175 270) (size 0.22 0.55) (layers "F.Cu" "F.Paste" "F.Mask") (roundrect_rratio 0.25)
      (net 705 "unconnected-(U5-CLK_{FB}-Pad6)") (pinfunction "CLK_{FB}") (pintype "output+no_connect"))
    (pad "7" smd roundrect (at 0.2 1.175 270) (size 0.22 0.55) (layers "F.Cu" "F.Paste" "F.Mask") (roundrect_rratio 0.25)
      (net 1 "GND") (pinfunction "GND") (pintype "power_in"))
    (pad "8" smd roundrect (at 0.598 1.175 270) (size 0.22 0.55) (layers "F.Cu" "F.Paste" "F.Mask") (roundrect_rratio 0.25)
      (net 261 "/SD 3.0 card/SD_CLK") (pinfunction "CLK_{B}") (pintype "output"))
    (pad "9" smd roundrect (at 0.623 0.598) (size 0.22 0.9) (layers "F.Cu" "F.Paste" "F.Mask") (roundrect_rratio 0.25)
      (net 259 "/SD 3.0 card/SD_DAT1") (pinfunction "DAT1_{B}") (pintype "bidirectional"))
    (pad "10" smd roundrect (at 0.623 0.2) (size 0.22 0.9) (layers "F.Cu" "F.Paste" "F.Mask") (roundrect_rratio 0.25)
      (net 260 "/SD 3.0 card/SD_DAT0") (pinfunction "DAT0_{B}") (pintype "bidirectional"))
    (pad "11" smd roundrect (at 0.623 -0.202) (size 0.22 0.9) (layers "F.Cu" "F.Paste" "F.Mask") (roundrect_rratio 0.25)
      (net 263 "/SD 3.0 card/SD_DAT3") (pinfunction "DAT3_{B}") (pintype "bidirectional"))
    (pad "12" smd roundrect (at 0.623 -0.6) (size 0.22 0.9) (layers "F.Cu" "F.Paste" "F.Mask") (roundrect_rratio 0.25)
      (net 264 "/SD 3.0 card/SD_DAT2") (pinfunction "DAT2_{B}") (pintype "bidirectional"))
    (pad "13" smd roundrect (at 0.598 -1.176 270) (size 0.22 0.55) (layers "F.Cu" "F.Paste" "F.Mask") (roundrect_rratio 0.25)
      (net 262 "/SD 3.0 card/SD_CMD") (pinfunction "CMD_{B}") (pintype "bidirectional"))
    (pad "14" smd roundrect (at 0.2 -1.176 270) (size 0.22 0.55) (layers "F.Cu" "F.Paste" "F.Mask") (roundrect_rratio 0.25)
      (net 104 "/SD 3.0 card/VCCB") (pinfunction "VCC_{B}") (pintype "power_in"))
    (pad "15" smd roundrect (at -0.202 -1.176 270) (size 0.22 0.55) (layers "F.Cu" "F.Paste" "F.Mask") (roundrect_rratio 0.25)
      (net 17 "PS_1V8") (pinfunction "VCC_{A}") (pintype "power_in"))
    (pad "16" smd roundrect (at -0.6 -1.176 270) (size 0.22 0.55) (layers "F.Cu" "F.Paste" "F.Mask") (roundrect_rratio 0.25)
      (net 435 "Net-(U5-CMD_{A})") (pinfunction "CMD_{A}") (pintype "bidirectional"))
  )

  (footprint "kria-k26-devboard-footprints:SOIC-8_3.9x4.9x1.75mm_P1.27mm" (layer "F.Cu")
    (at 110.2 101.675 -90)
    (tags "Integrated Circuit")
    (property "Author" "Antmicro")
    (property "License" "Apache-2.0")
    (property "MPN" "SN65LVDS1DR")
    (property "Manufacturer" "Texas Instruments")
    (property "Sheetfile" "clock.kicad_sch")
    (property "Sheetname" "Clock distribution")
    (property "ki_description" "LVDS Interface IC Single LVDS Transmitter")
    (property "ki_keywords" "SMT, INTERFACE, IC, LVDS")
    (attr smd)
    (fp_text reference "U8" (at 0.635 -3.58 -90) (layer "F.SilkS")
        (effects (font (size 0.7 0.7) (thickness 0.15)) (justify left bottom))
    )
    (fp_text value "SN65LVDS1_SOIC" (at 0 3.65 -90) (layer "F.Fab")
        (effects (font (size 0.7 0.7) (thickness 0.15)) (justify left bottom))
    )
    (fp_text user "License: Apache-2.0" (at -3.476 5.099 -90) (layer "F.Fab") hide
        (effects (font (size 0.7 0.7) (thickness 0.15)) (justify left bottom))
    )
    (fp_text user "Author: Antmicro" (at -3.476 6.099 -90) (layer "F.Fab") hide
        (effects (font (size 0.7 0.7) (thickness 0.15)) (justify left bottom))
    )
    (fp_text user "${REFERENCE}" (at -3.476 7.099 -90) (layer "F.Fab") hide
        (effects (font (size 0.7 0.7) (thickness 0.15)) (justify left bottom))
    )
    (fp_line (start -1.95 -2.452) (end 1.95 -2.45)
      (stroke (width 0.15) (type solid)) (layer "F.SilkS"))
    (fp_line (start -1.95 2.45) (end 1.95 2.45)
      (stroke (width 0.15) (type solid)) (layer "F.SilkS"))
    (fp_circle (center -2.4 -2.45) (end -2.35 -2.4)
      (stroke (width 0.15) (type solid)) (fill solid) (layer "F.SilkS"))
    (fp_rect (start -3.625 -2.7) (end 3.625 2.7)
      (stroke (width 0.05) (type solid)) (fill none) (layer "F.CrtYd"))
    (fp_line (start -1.95 -1.18) (end -0.683 -2.452)
      (stroke (width 0.15) (type solid)) (layer "F.Fab"))
    (fp_line (start -1.95 2.45) (end -1.95 -1.18)
      (stroke (width 0.15) (type solid)) (layer "F.Fab"))
    (fp_line (start -0.683 -2.452) (end 1.949 -2.452)
      (stroke (width 0.15) (type solid)) (layer "F.Fab"))
    (fp_line (start 1.949 -2.452) (end 1.949 2.45)
      (stroke (width 0.15) (type solid)) (layer "F.Fab"))
    (fp_line (start 1.949 2.45) (end -1.95 2.45)
      (stroke (width 0.15) (type solid)) (layer "F.Fab"))
    (pad "1" smd roundrect (at -2.714 -1.905) (size 0.65 1.525) (layers "F.Cu" "F.Paste" "F.Mask") (roundrect_rratio 0.25)
      (net 15 "PS_3V3") (pinfunction "VDD") (pintype "power_in"))
    (pad "2" smd roundrect (at -2.714 -0.635) (size 0.65 1.525) (layers "F.Cu" "F.Paste" "F.Mask") (roundrect_rratio 0.25)
      (net 698 "Net-(U8-IN)") (pinfunction "IN") (pintype "input"))
    (pad "3" smd roundrect (at -2.714 0.632) (size 0.65 1.525) (layers "F.Cu" "F.Paste" "F.Mask") (roundrect_rratio 0.25)
      (net 706 "unconnected-(U8-NC-Pad3)") (pinfunction "NC") (pintype "no_connect"))
    (pad "4" smd roundrect (at -2.714 1.902) (size 0.65 1.525) (layers "F.Cu" "F.Paste" "F.Mask") (roundrect_rratio 0.25)
      (net 1 "GND") (pinfunction "GND") (pintype "power_in"))
    (pad "5" smd roundrect (at 2.712 1.902) (size 0.65 1.525) (layers "F.Cu" "F.Paste" "F.Mask") (roundrect_rratio 0.25)
      (net 707 "unconnected-(U8-NC-Pad5)") (pinfunction "NC") (pintype "no_connect"))
    (pad "6" smd roundrect (at 2.712 0.632) (size 0.65 1.525) (layers "F.Cu" "F.Paste" "F.Mask") (roundrect_rratio 0.25)
      (net 708 "unconnected-(U8-NC-Pad6)") (pinfunction "NC") (pintype "no_connect"))
    (pad "7" smd roundrect (at 2.712 -0.635) (size 0.65 1.525) (layers "F.Cu" "F.Paste" "F.Mask") (roundrect_rratio 0.25)
      (net 179 "/Clock distribution/GTR_REFCLK1_C2M_P") (pinfunction "OUT+") (pintype "output"))
    (pad "8" smd roundrect (at 2.712 -1.905) (size 0.65 1.525) (layers "F.Cu" "F.Paste" "F.Mask") (roundrect_rratio 0.25)
      (net 180 "/Clock distribution/GTR_REFCLK1_C2M_N") (pinfunction "OUT-") (pintype "output"))
  )

  (footprint "kria-k26-devboard-footprints:Oscillator_SMD_ECS_2520MV_2.5x2mm" (layer "F.Cu")
    (at 109.025 96.3)
    (descr "Miniature Crystal Clock Oscillator ECS 2520MV series")
    (tags "Crystal Clock Oscillator ECS 2520MV SMD")
    (property "Author" "Antmicro")
    (property "License" "Apache-2.0")
    (property "MPN" "ECS-2520MVLC-260-CM-TR")
    (property "Manufacturer" "ECS Inc. International")
    (property "Sheetfile" "clock.kicad_sch")
    (property "Sheetname" "Clock distribution")
    (property "Val" "26 MHz")
    (property "ki_description" "Oscillator, 26 MHz, CMOS, 25 ppm, SMD, 2.5mm x 2mm, 3.6 V, MultiVolt ECS-2520MVLC Series")
    (property "ki_keywords" "OSCILLATOR")
    (attr smd)
    (fp_text reference "Y2" (at -0.705 -1.56) (layer "F.SilkS")
        (effects (font (size 0.7 0.7) (thickness 0.15)) (justify left bottom))
    )
    (fp_text value "Oscillator_26MHz_ESC_2520MV" (at 0 2.499) (layer "F.Fab") hide
        (effects (font (size 0.7 0.7) (thickness 0.15)) (justify left bottom))
    )
    (fp_text user "${REFERENCE}" (at -1.25 3.9) (layer "F.Fab") hide
        (effects (font (size 0.7 0.7) (thickness 0.15)) (justify left bottom))
    )
    (fp_text user "License: Apache-2.0" (at -1.25 6.302) (layer "F.Fab") hide
        (effects (font (size 0.7 0.7) (thickness 0.15)) (justify left bottom))
    )
    (fp_text user "Author: Antmicro" (at -1.25 5.102) (layer "F.Fab") hide
        (effects (font (size 0.7 0.7) (thickness 0.15)) (justify left bottom))
    )
    (fp_line (start -1.111 0.32) (end -1.111 -0.32)
      (stroke (width 0.15) (type solid)) (layer "F.SilkS"))
    (fp_line (start -0.172 1.36) (end 0.17 1.36)
      (stroke (width 0.15) (type solid)) (layer "F.SilkS"))
    (fp_line (start -0.16 -1.361) (end 0.17 -1.361)
      (stroke (width 0.15) (type solid)) (layer "F.SilkS"))
    (fp_line (start 1.11 0.32) (end 1.11 -0.32)
      (stroke (width 0.15) (type solid)) (layer "F.SilkS"))
    (fp_circle (center -1.1 -1.5) (end -1.049 -1.5)
      (stroke (width 0.15) (type solid)) (fill solid) (layer "F.SilkS"))
    (fp_rect (start -1.25 -1.5) (end 1.25 1.5)
      (stroke (width 0.05) (type solid)) (fill none) (layer "F.CrtYd"))
    (fp_line (start -1 -0.75) (end -0.5 -1.25)
      (stroke (width 0.15) (type solid)) (layer "F.Fab"))
    (fp_rect (start 1 1.249) (end -1 -1.25)
      (stroke (width 0.15) (type solid)) (fill none) (layer "F.Fab"))
    (pad "1" smd roundrect (at -0.725 -0.927) (size 0.8 0.9) (layers "F.Cu" "F.Paste" "F.Mask") (roundrect_rratio 0.25)
      (net 185 "/Clock distribution/PS_CLK_EN") (pinfunction "EN") (pintype "input"))
    (pad "2" smd roundrect (at -0.725 0.925) (size 0.8 0.9) (layers "F.Cu" "F.Paste" "F.Mask") (roundrect_rratio 0.25)
      (net 1 "GND") (pinfunction "GND") (pintype "power_in"))
    (pad "3" smd roundrect (at 0.723 0.925) (size 0.8 0.9) (layers "F.Cu" "F.Paste" "F.Mask") (roundrect_rratio 0.25)
      (net 698 "Net-(U8-IN)") (pinfunction "OUT") (pintype "output"))
    (pad "4" smd roundrect (at 0.723 -0.927) (size 0.8 0.9) (layers "F.Cu" "F.Paste" "F.Mask") (roundrect_rratio 0.25)
      (net 15 "PS_3V3") (pinfunction "VDD") (pintype "power_in"))
  )

  (footprint "kria-k26-devboard-footprints:SOIC-8-1EP_3.9x4.9x1.75mm_P1.27mm" (layer "F.Cu")
    (at 188.6 81.09 -90)
    (tags "Integrated Circuit")
    (property "Author" "Antmicro")
    (property "License" "Apache-2.0")
    (property "MPN" "TPS2378DDA")
    (property "Manufacturer" "Texas Instruments")
    (property "Sheetfile" "PoE.kicad_sch")
    (property "Sheetname" "PoE")
    (property "ki_description" "Power Over Ethernet (POE) Controller, 57 V/ 500 µA, 40 V UVLO Threshold, SOIC-8")
    (property "ki_keywords" "SMT, POE, IC, INTERFACE")
    (attr smd)
    (fp_text reference "IC1" (at 4.43 0.58) (layer "F.SilkS")
        (effects (font (size 0.7 0.7) (thickness 0.15)) (justify left bottom))
    )
    (fp_text value "TPS2378DDA" (at 0 3.65 -90) (layer "F.Fab")
        (effects (font (size 0.7 0.7) (thickness 0.15)) (justify left bottom))
    )
    (fp_text user "Author: Antmicro" (at -3.476 6.099 -90) (layer "F.Fab") hide
        (effects (font (size 0.7 0.7) (thickness 0.15)) (justify left bottom))
    )
    (fp_text user "${REFERENCE}" (at -3.476 7.099 -90) (layer "F.Fab") hide
        (effects (font (size 0.7 0.7) (thickness 0.15)) (justify left bottom))
    )
    (fp_text user "License: Apache-2.0" (at -3.476 5.099 -90) (layer "F.Fab") hide
        (effects (font (size 0.7 0.7) (thickness 0.15)) (justify left bottom))
    )
    (fp_line (start 1.95 -2.55) (end -1.95 -2.55)
      (stroke (width 0.15) (type solid)) (layer "F.SilkS"))
    (fp_line (start 1.95 2.55) (end -1.95 2.55)
      (stroke (width 0.15) (type solid)) (layer "F.SilkS"))
    (fp_circle (center -2.5 -2.45) (end -2.45 -2.4)
      (stroke (width 0.15) (type solid)) (fill solid) (layer "F.SilkS"))
    (fp_rect (start -3.55 -2.7) (end 3.55 2.7)
      (stroke (width 0.05) (type solid)) (fill none) (layer "F.CrtYd"))
    (fp_line (start -1.95 -1.18) (end -0.683 -2.452)
      (stroke (width 0.15) (type solid)) (layer "F.Fab"))
    (fp_line (start -1.95 2.45) (end -1.95 -1.18)
      (stroke (width 0.15) (type solid)) (layer "F.Fab"))
    (fp_line (start -0.683 -2.452) (end 1.949 -2.452)
      (stroke (width 0.15) (type solid)) (layer "F.Fab"))
    (fp_line (start 1.949 -2.452) (end 1.949 2.45)
      (stroke (width 0.15) (type solid)) (layer "F.Fab"))
    (fp_line (start 1.949 2.45) (end -1.95 2.45)
      (stroke (width 0.15) (type solid)) (layer "F.Fab"))
    (pad "1" smd roundrect (at -2.714 -1.905) (size 0.65 1.525) (layers "F.Cu" "F.Paste" "F.Mask") (roundrect_rratio 0.25)
      (net 9 "/Power Supply/PoE/VDD_POE_IN") (pinfunction "VDD") (pintype "power_in"))
    (pad "2" smd roundrect (at -2.714 -0.635) (size 0.65 1.525) (layers "F.Cu" "F.Paste" "F.Mask") (roundrect_rratio 0.25)
      (net 341 "Net-(IC1-DEN)") (pinfunction "DEN") (pintype "passive"))
    (pad "3" smd roundrect (at -2.714 0.632) (size 0.65 1.525) (layers "F.Cu" "F.Paste" "F.Mask") (roundrect_rratio 0.25)
      (net 342 "Net-(IC1-CLS)") (pinfunction "CLS") (pintype "passive"))
    (pad "4" smd roundrect (at -2.714 1.902) (size 0.65 1.525) (layers "F.Cu" "F.Paste" "F.Mask") (roundrect_rratio 0.25)
      (net 10 "/Power Supply/PoE/VSS_POE_IN") (pinfunction "VSS") (pintype "power_in"))
    (pad "5" smd roundrect (at 2.712 1.902) (size 0.65 1.525) (layers "F.Cu" "F.Paste" "F.Mask") (roundrect_rratio 0.25)
      (net 11 "GNDD") (pinfunction "RTN") (pintype "passive"))
    (pad "6" smd roundrect (at 2.712 0.632) (size 0.65 1.525) (layers "F.Cu" "F.Paste" "F.Mask") (roundrect_rratio 0.25)
      (net 12 "/Power Supply/PoE/POE_ACTIVE") (pinfunction "CDB") (pintype "passive"))
    (pad "7" smd roundrect (at 2.712 -0.635) (size 0.65 1.525) (layers "F.Cu" "F.Paste" "F.Mask") (roundrect_rratio 0.25)
      (net 343 "unconnected-(IC1-T2P-Pad7)") (pinfunction "T2P") (pintype "passive+no_connect"))
    (pad "8" smd roundrect (at 2.712 -1.905) (size 0.65 1.525) (layers "F.Cu" "F.Paste" "F.Mask") (roundrect_rratio 0.25)
      (net 11 "GNDD") (pinfunction "APD") (pintype "passive"))
    (pad "9" smd roundrect (at 0 0 270) (size 2.29 3.1) (layers "F.Cu" "F.Paste" "F.Mask") (roundrect_rratio 0.05)
      (net 10 "/Power Supply/PoE/VSS_POE_IN") (pinfunction "EP") (pintype "power_in"))
  )

  (footprint "kria-k26-devboard-footprints:R_0402_1005Metric" (layer "F.Cu")
    (at 189.75 76.75 180)
    (descr "Resistor SMD 0402")
    (tags "resistor SMD 0402")
    (property "Author" "Antmicro")
    (property "License" "Apache-2.0")
    (property "MPN" "CR0402-FX-2492GLF")
    (property "Manufacturer" "Bourns")
    (property "Sheetfile" "PoE.kicad_sch")
    (property "Sheetname" "PoE")
    (property "Tolerance" "1%")
    (property "Val" "24k9")
    (property "ki_description" "24k9 resistor in 0402 package with 1% tolerance")
    (attr smd)
    (fp_text reference "R115" (at 1.21 0.56 180) (layer "F.SilkS")
        (effects (font (size 0.7 0.7) (thickness 0.15)) (justify left bottom))
    )
    (fp_text value "R_24k9_0402" (at 0 1.4 180) (layer "F.Fab") hide
        (effects (font (size 0.7 0.7) (thickness 0.15)) (justify left bottom))
    )
    (fp_text user "${REFERENCE}" (at -0.95 3.168 180) (layer "F.Fab") hide
        (effects (font (size 0.7 0.7) (thickness 0.15)) (justify left bottom))
    )
    (fp_text user "Author: Antmicro" (at -0.95 4.169 180) (layer "F.Fab") hide
        (effects (font (size 0.7 0.7) (thickness 0.15)) (justify left bottom))
    )
    (fp_text user "License: Apache-2.0" (at -0.95 5.169 180) (layer "F.Fab") hide
        (effects (font (size 0.7 0.7) (thickness 0.15)) (justify left bottom))
    )
    (fp_rect (start -0.93 -0.47) (end 0.93 0.47)
      (stroke (width 0.05) (type solid)) (fill none) (layer "F.CrtYd"))
    (fp_rect (start -0.5 -0.25) (end 0.5 0.25)
      (stroke (width 0.15) (type solid)) (fill none) (layer "F.Fab"))
    (pad "1" smd roundrect (at -0.485 0 180) (size 0.59 0.64) (layers "F.Cu" "F.Paste" "F.Mask") (roundrect_rratio 0.25)
      (net 9 "/Power Supply/PoE/VDD_POE_IN") (pintype "passive"))
    (pad "2" smd roundrect (at 0.485 0 180) (size 0.59 0.64) (layers "F.Cu" "F.Paste" "F.Mask") (roundrect_rratio 0.25)
      (net 341 "Net-(IC1-DEN)") (pintype "passive"))
  )

  (footprint "kria-k26-devboard-footprints:C_2220_5650Metric" (layer "F.Cu")
    (at 182.87 82.95 90)
    (descr "Capacitor SMD 2220")
    (tags "capacitor SMD 2220")
    (property "Author" "Antmicro")
    (property "Dielectric" "")
    (property "License" "Apache-2.0")
    (property "MPN" "C5750X7S2A226M280KB")
    (property "Manufacturer" "TDK")
    (property "Sheetfile" "PoE.kicad_sch")
    (property "Sheetname" "PoE")
    (property "Val" "22u/100V")
    (property "Voltage" "")
    (property "ki_description" " ")
    (attr smd)
    (fp_text reference "C174" (at -1.39 -20.82 90) (layer "F.SilkS")
        (effects (font (size 0.7 0.7) (thickness 0.15)) (justify left bottom))
    )
    (fp_text value "C_22u_100V_2220" (at 0 3.9 90) (layer "F.Fab") hide
        (effects (font (size 0.7 0.7) (thickness 0.15)) (justify left bottom))
    )
    (fp_text user "Author: Antmicro" (at -3.7 7.9 90) (layer "F.Fab") hide
        (effects (font (size 0.7 0.7) (thickness 0.15)) (justify left bottom))
    )
    (fp_text user "${REFERENCE}" (at -3.7 5.9 90) (layer "F.Fab") hide
        (effects (font (size 0.7 0.7) (thickness 0.15)) (justify left bottom))
    )
    (fp_text user "License: Apache-2.0" (at -3.7 6.9 90) (layer "F.Fab") hide
        (effects (font (size 0.7 0.7) (thickness 0.15)) (justify left bottom))
    )
    (fp_line (start -1.415 -2.61) (end 1.415 -2.61)
      (stroke (width 0.15) (type solid)) (layer "F.SilkS"))
    (fp_line (start -1.415 2.61) (end 1.415 2.61)
      (stroke (width 0.15) (type solid)) (layer "F.SilkS"))
    (fp_rect (start -3.7 -2.95) (end 3.7 2.95)
      (stroke (width 0.05) (type solid)) (fill none) (layer "F.CrtYd"))
    (fp_rect (start -2.85 -2.5) (end 2.85 2.5)
      (stroke (width 0.15) (type solid)) (fill none) (layer "F.Fab"))
    (pad "1" smd roundrect (at -2.55 0 90) (size 1.8 5.4) (layers "F.Cu" "F.Paste" "F.Mask") (roundrect_rratio 0.138889)
      (net 9 "/Power Supply/PoE/VDD_POE_IN") (pintype "passive"))
    (pad "2" smd roundrect (at 2.55 0 90) (size 1.8 5.4) (layers "F.Cu" "F.Paste" "F.Mask") (roundrect_rratio 0.138889)
      (net 11 "GNDD") (pintype "passive"))
  )

  (footprint "kria-k26-devboard-footprints:C_0402_1005Metric" (layer "F.Cu")
    (at 149.5 60.74)
    (descr "Capacitor SMD 0402")
    (tags "capacitor SMD 0402")
    (property "Author" "Antmicro")
    (property "Dielectric" "")
    (property "License" "Apache-2.0")
    (property "MPN" "GRM155R71H104KE14D")
    (property "Manufacturer" "Murata")
    (property "Sheetfile" "usbc-socket.kicad_sch")
    (property "Sheetname" "USB-C socket")
    (property "Val" "100n/50V")
    (property "Voltage" "")
    (property "ki_description" " ")
    (attr smd)
    (fp_text reference "C231" (at 0.82 0.39) (layer "F.SilkS")
        (effects (font (size 0.7 0.7) (thickness 0.15)) (justify left bottom))
    )
    (fp_text value "C_100n_50V_0402" (at 0 1.4) (layer "F.Fab") hide
        (effects (font (size 0.7 0.7) (thickness 0.15)) (justify left bottom))
    )
    (fp_text user "Author: Antmicro" (at -0.932 4.17) (layer "F.Fab") hide
        (effects (font (size 0.7 0.7) (thickness 0.15)) (justify left bottom))
    )
    (fp_text user "License: Apache-2.0" (at -0.932 5.17) (layer "F.Fab") hide
        (effects (font (size 0.7 0.7) (thickness 0.15)) (justify left bottom))
    )
    (fp_text user "${REFERENCE}" (at -0.932 3.168) (layer "F.Fab") hide
        (effects (font (size 0.7 0.7) (thickness 0.15)) (justify left bottom))
    )
    (fp_rect (start -0.94 -0.47) (end 0.94 0.47)
      (stroke (width 0.05) (type solid)) (fill none) (layer "F.CrtYd"))
    (fp_rect (start -0.499 -0.249) (end 0.499 0.249)
      (stroke (width 0.15) (type solid)) (fill none) (layer "F.Fab"))
    (pad "1" smd roundrect (at -0.484 0) (size 0.59 0.64) (layers "F.Cu" "F.Paste" "F.Mask") (roundrect_rratio 0.25)
      (net 265 "/Debug and JTAG/USBC_VBUS") (pintype "passive"))
    (pad "2" smd roundrect (at 0.484 0) (size 0.59 0.64) (layers "F.Cu" "F.Paste" "F.Mask") (roundrect_rratio 0.25)
      (net 1 "GND") (pintype "passive"))
  )

  (footprint "kria-k26-devboard-footprints:USB-C_Receptacle_GCT_USB4105-GF-A" (layer "F.Cu")
    (at 146.699 55.855 180)
    (property "Author" "Antmicro")
    (property "License" "Apache-2.0")
    (property "MPN" "USB4105-GF-A")
    (property "Manufacturer" "GCT")
    (property "Sheetfile" "usbc-socket.kicad_sch")
    (property "Sheetname" "USB-C socket")
    (property "VSD_Class" "USB-C")
    (property "ki_description" "USB-C (USB TYPE-C) USB 2.0 Receptacle Connector 24 (16+8 Dummy) Position Surface Mount, Right Angle")
    (property "ki_keywords" "USB, CONNECTOR, SMT, HORIZONTAL")
    (attr smd)
    (fp_text reference "J10" (at 4.719 -5.015 180) (layer "F.SilkS")
        (effects (font (size 0.7 0.7) (thickness 0.15)) (justify left bottom))
    )
    (fp_text value "USB-C_GCT_USB4105-GF-A" (at 0 5 180) (layer "F.Fab") hide
        (effects (font (size 0.7 0.7) (thickness 0.15)) (justify left bottom))
    )
    (fp_text user "PCB-EDGE" (at -4.79 5.853 180) (layer "F.Fab") hide
        (effects (font (size 0.7 0.7) (thickness 0.15)) (justify left bottom))
    )
    (fp_text user "License: Apache-2.0" (at -4.79 8.855 180) (layer "F.Fab") hide
        (effects (font (size 0.7 0.7) (thickness 0.15)) (justify left bottom))
    )
    (fp_text user "${REFERENCE}" (at -4.79 6.853 180) (layer "F.Fab") hide
        (effects (font (size 0.7 0.7) (thickness 0.15)) (justify left bottom))
    )
    (fp_text user "Author: Antmicro" (at -4.79 7.853 180) (layer "F.Fab") hide
        (effects (font (size 0.7 0.7) (thickness 0.15)) (justify left bottom))
    )
    (fp_line (start -4.79 -1.395) (end -4.79 -0.145)
      (stroke (width 0.15) (type solid)) (layer "F.SilkS"))
    (fp_line (start -4.79 2.575) (end -4.79 3.854)
      (stroke (width 0.15) (type solid)) (layer "F.SilkS"))
    (fp_line (start -4.79 3.854) (end 4.788 3.854)
      (stroke (width 0.15) (type solid)) (layer "F.SilkS"))
    (fp_line (start 4.788 -1.395) (end 4.788 -0.145)
      (stroke (width 0.15) (type solid)) (layer "F.SilkS"))
    (fp_line (start 4.788 3.854) (end 4.788 2.575)
      (stroke (width 0.15) (type solid)) (layer "F.SilkS"))
    (fp_circle (center -3.8 -4.27071) (end -3.75 -4.22071)
      (stroke (width 0.15) (type solid)) (fill solid) (layer "F.SilkS"))
    (fp_rect (start -5.1 -4.4) (end 5.1 3.9)
      (stroke (width 0.05) (type solid)) (fill none) (layer "F.CrtYd"))
    (fp_line (start -4.79 -3.676) (end 4.788 -3.676)
      (stroke (width 0.15) (type solid)) (layer "F.Fab"))
    (fp_line (start -4.79 3.854) (end -4.79 -3.676)
      (stroke (width 0.15) (type solid)) (layer "F.Fab"))
    (fp_line (start -4.702 3.854) (end 4.788 3.854)
      (stroke (width 0.15) (type solid)) (layer "F.Fab"))
    (fp_line (start 4.788 -3.676) (end 4.788 3.854)
      (stroke (width 0.15) (type solid)) (layer "F.Fab"))
    (fp_line (start 4.788 3.854) (end -4.79 3.854)
      (stroke (width 0.15) (type solid)) (layer "F.Fab"))
    (pad "" np_thru_hole circle (at -2.891 -2.426 180) (size 0.65 0.65) (drill 0.65) (layers "*.Cu" "*.Mask"))
    (pad "" np_thru_hole circle (at 2.89 -2.426 180) (size 0.65 0.65) (drill 0.65) (layers "*.Cu" "*.Mask"))
    (pad "A1" smd roundrect (at -3.202 -3.5 180) (size 0.6 1.15) (layers "F.Cu" "F.Paste" "F.Mask") (roundrect_rratio 0.25)
      (net 1 "GND") (pinfunction "GND") (pintype "power_in"))
    (pad "A4" smd roundrect (at -2.4 -3.5 180) (size 0.6 1.15) (layers "F.Cu" "F.Paste" "F.Mask") (roundrect_rratio 0.25)
      (net 265 "/Debug and JTAG/USBC_VBUS") (pinfunction "VBUS") (pintype "passive"))
    (pad "A5" smd roundrect (at -1.25 -3.5 180) (size 0.3 1.15) (layers "F.Cu" "F.Paste" "F.Mask") (roundrect_rratio 0.25)
      (net 301 "/Power Supply/USB-C socket/USBC_TVS_CC1") (pinfunction "CC_{1}") (pintype "bidirectional"))
    (pad "A6" smd roundrect (at -0.25 -3.5 180) (size 0.3 1.15) (layers "F.Cu" "F.Paste" "F.Mask") (roundrect_rratio 0.25)
      (net 299 "/Power Supply/USB-C socket/USBC_TVS_P") (pinfunction "D_{A}+") (pintype "bidirectional"))
    (pad "A7" smd roundrect (at 0.248 -3.5 180) (size 0.3 1.15) (layers "F.Cu" "F.Paste" "F.Mask") (roundrect_rratio 0.25)
      (net 298 "/Power Supply/USB-C socket/USBC_TVS_N") (pinfunction "D_{A}-") (pintype "bidirectional"))
    (pad "A8" smd roundrect (at 1.249 -3.5 180) (size 0.3 1.15) (layers "F.Cu" "F.Paste" "F.Mask") (roundrect_rratio 0.25)
      (net 367 "unconnected-(J10-SBU_{1}-PadA8)") (pinfunction "SBU_{1}") (pintype "bidirectional+no_connect"))
    (pad "A9" smd roundrect (at 2.398 -3.5 180) (size 0.6 1.15) (layers "F.Cu" "F.Paste" "F.Mask") (roundrect_rratio 0.25)
      (net 265 "/Debug and JTAG/USBC_VBUS") (pinfunction "VBUS") (pintype "passive"))
    (pad "A12" smd roundrect (at 3.2 -3.5 180) (size 0.6 1.15) (layers "F.Cu" "F.Paste" "F.Mask") (roundrect_rratio 0.25)
      (net 1 "GND") (pinfunction "GND") (pintype "passive"))
    (pad "B1" smd roundrect (at 3.2 -3.5 180) (size 0.6 1.15) (layers "F.Cu" "F.Paste" "F.Mask") (roundrect_rratio 0.25)
      (net 1 "GND") (pinfunction "GND") (pintype "passive"))
    (pad "B4" smd roundrect (at 2.398 -3.5 180) (size 0.6 1.15) (layers "F.Cu" "F.Paste" "F.Mask") (roundrect_rratio 0.25)
      (net 265 "/Debug and JTAG/USBC_VBUS") (pinfunction "VBUS") (pintype "passive"))
    (pad "B5" smd roundrect (at 1.749 -3.5 180) (size 0.3 1.15) (layers "F.Cu" "F.Paste" "F.Mask") (roundrect_rratio 0.25)
      (net 300 "/Power Supply/USB-C socket/USBC_TVS_CC2") (pinfunction "CC_{2}") (pintype "bidirectional"))
    (pad "B6" smd roundrect (at 0.748 -3.5 180) (size 0.3 1.15) (layers "F.Cu" "F.Paste" "F.Mask") (roundrect_rratio 0.25)
      (net 299 "/Power Supply/USB-C socket/USBC_TVS_P") (pinfunction "D_{B}+") (pintype "bidirectional"))
    (pad "B7" smd roundrect (at -0.75 -3.5 180) (size 0.3 1.15) (layers "F.Cu" "F.Paste" "F.Mask") (roundrect_rratio 0.25)
      (net 298 "/Power Supply/USB-C socket/USBC_TVS_N") (pinfunction "D_{B}-") (pintype "bidirectional"))
    (pad "B8" smd roundrect (at -1.75 -3.5 180) (size 0.3 1.15) (layers "F.Cu" "F.Paste" "F.Mask") (roundrect_rratio 0.25)
      (net 368 "unconnected-(J10-SBU_{2}-PadB8)") (pinfunction "SBU_{2}") (pintype "bidirectional+no_connect"))
    (pad "B9" smd roundrect (at -2.4 -3.5 180) (size 0.6 1.15) (layers "F.Cu" "F.Paste" "F.Mask") (roundrect_rratio 0.25)
      (net 265 "/Debug and JTAG/USBC_VBUS") (pinfunction "VBUS") (pintype "passive"))
    (pad "B12" smd roundrect (at -3.202 -3.5 180) (size 0.6 1.15) (layers "F.Cu" "F.Paste" "F.Mask") (roundrect_rratio 0.25)
      (net 1 "GND") (pinfunction "GND") (pintype "passive"))
    (pad "SH" thru_hole oval (at -4.321 -2.926 180) (size 1.05 2.1) (drill oval 0.6 1.7) (layers "*.Cu" "*.Mask")
      (net 319 "SH_UP") (pinfunction "SH") (pintype "passive"))
    (pad "SH" thru_hole oval (at -4.321 1.255 180) (size 1 2) (drill oval 0.6 1.4) (layers "*.Cu" "*.Mask")
      (net 319 "SH_UP") (pinfunction "SH") (pintype "passive"))
    (pad "SH" thru_hole oval (at 4.32 -2.926 180) (size 1.05 2.1) (drill oval 0.6 1.7) (layers "*.Cu" "*.Mask")
      (net 319 "SH_UP") (pinfunction "SH") (pintype "passive"))
    (pad "SH" thru_hole oval (at 4.32 1.255 180) (size 1 2) (drill oval 0.6 1.4) (layers "*.Cu" "*.Mask")
      (net 319 "SH_UP") (pinfunction "SH") (pintype "passive"))
  )

  (footprint "kria-k26-devboard-footprints:R_0402_1005Metric" (layer "F.Cu")
    (at 151.9 65.5 -90)
    (descr "Resistor SMD 0402")
    (tags "resistor SMD 0402")
    (property "Author" "Antmicro")
    (property "License" "Apache-2.0")
    (property "MPN" "CR0402-FX-1003GLF")
    (property "Manufacturer" "Bourns")
    (property "Sheetfile" "usbc-socket.kicad_sch")
    (property "Sheetname" "USB-C socket")
    (property "Tolerance" "1%")
    (property "Val" "100k")
    (property "ki_description" "100k resistor in 0402 package with 1% tolerance")
    (attr smd)
    (fp_text reference "R149" (at 0.38 -1.23 -90) (layer "F.SilkS")
        (effects (font (size 0.7 0.7) (thickness 0.15)) (justify left bottom))
    )
    (fp_text value "R_100k_0402" (at 0 1.4 -90) (layer "F.Fab") hide
        (effects (font (size 0.7 0.7) (thickness 0.15)) (justify left bottom))
    )
    (fp_text user "License: Apache-2.0" (at -0.95 5.169 -90) (layer "F.Fab") hide
        (effects (font (size 0.7 0.7) (thickness 0.15)) (justify left bottom))
    )
    (fp_text user "Author: Antmicro" (at -0.95 4.169 -90) (layer "F.Fab") hide
        (effects (font (size 0.7 0.7) (thickness 0.15)) (justify left bottom))
    )
    (fp_text user "${REFERENCE}" (at -0.95 3.168 -90) (layer "F.Fab") hide
        (effects (font (size 0.7 0.7) (thickness 0.15)) (justify left bottom))
    )
    (fp_rect (start -0.93 -0.47) (end 0.93 0.47)
      (stroke (width 0.05) (type solid)) (fill none) (layer "F.CrtYd"))
    (fp_rect (start -0.5 -0.25) (end 0.5 0.25)
      (stroke (width 0.15) (type solid)) (fill none) (layer "F.Fab"))
    (pad "1" smd roundrect (at -0.485 0 270) (size 0.59 0.64) (layers "F.Cu" "F.Paste" "F.Mask") (roundrect_rratio 0.25)
      (net 265 "/Debug and JTAG/USBC_VBUS") (pintype "passive"))
    (pad "2" smd roundrect (at 0.485 0 270) (size 0.59 0.64) (layers "F.Cu" "F.Paste" "F.Mask") (roundrect_rratio 0.25)
      (net 433 "Net-(Q16-G)") (pintype "passive"))
  )

  (footprint "kria-k26-devboard-footprints:C_0402_1005Metric" (layer "F.Cu")
    (at 186.775 61.75)
    (descr "Capacitor SMD 0402")
    (tags "capacitor SMD 0402")
    (property "Author" "Antmicro")
    (property "Dielectric" "")
    (property "License" "Apache-2.0")
    (property "MPN" "GRM155R71H104KE14D")
    (property "Manufacturer" "Murata")
    (property "Sheetfile" "dc-input.kicad_sch")
    (property "Sheetname" "DC Input")
    (property "Val" "100n/50V")
    (property "Voltage" "")
    (property "ki_description" " ")
    (attr smd)
    (fp_text reference "C232" (at 0.955 0.36) (layer "F.SilkS")
        (effects (font (size 0.7 0.7) (thickness 0.15)) (justify left bottom))
    )
    (fp_text value "C_100n_50V_0402" (at 0 1.4) (layer "F.Fab") hide
        (effects (font (size 0.7 0.7) (thickness 0.15)) (justify left bottom))
    )
    (fp_text user "${REFERENCE}" (at -0.932 3.168) (layer "F.Fab") hide
        (effects (font (size 0.7 0.7) (thickness 0.15)) (justify left bottom))
    )
    (fp_text user "License: Apache-2.0" (at -0.932 5.17) (layer "F.Fab") hide
        (effects (font (size 0.7 0.7) (thickness 0.15)) (justify left bottom))
    )
    (fp_text user "Author: Antmicro" (at -0.932 4.17) (layer "F.Fab") hide
        (effects (font (size 0.7 0.7) (thickness 0.15)) (justify left bottom))
    )
    (fp_rect (start -0.94 -0.47) (end 0.94 0.47)
      (stroke (width 0.05) (type solid)) (fill none) (layer "F.CrtYd"))
    (fp_rect (start -0.499 -0.249) (end 0.499 0.249)
      (stroke (width 0.15) (type solid)) (fill none) (layer "F.Fab"))
    (pad "1" smd roundrect (at -0.484 0) (size 0.59 0.64) (layers "F.Cu" "F.Paste" "F.Mask") (roundrect_rratio 0.25)
      (net 22 "/Power Supply/DC Input/DC_IN") (pintype "passive"))
    (pad "2" smd roundrect (at 0.484 0) (size 0.59 0.64) (layers "F.Cu" "F.Paste" "F.Mask") (roundrect_rratio 0.25)
      (net 1 "GND") (pintype "passive"))
  )

  (footprint "kria-k26-devboard-footprints:BarrelJack_Pin2mm_MJ-179PH" (layer "F.Cu")
    (at 180 65.695 90)
    (property "Author" "Antmicro")
    (property "License" "Apache-2.0")
    (property "MPN" "MJ-179PH")
    (property "Manufacturer" "Multicomp Pro")
    (property "Sheetfile" "dc-input.kicad_sch")
    (property "Sheetname" "DC Input")
    (property "ki_description" "DC Power Connector, Jack, 4 A, 1.95 mm, PCB Mount, Through Hole")
    (property "ki_keywords" "HORIZONTAL, THT, JACK, CONNECTOR, POWER")
    (attr through_hole)
    (fp_text reference "J11" (at 11.715 -5.04 90) (layer "F.SilkS")
        (effects (font (size 0.7 0.7) (thickness 0.15)) (justify left bottom))
    )
    (fp_text value "BarrelJack_Pin2mm_MJ-179PH" (at 0 15.4 90) (layer "F.Fab") hide
        (effects (font (size 0.7 0.7) (thickness 0.15)) (justify left bottom))
    )
    (fp_text user "${REFERENCE}" (at -5.1 16.4 90) (layer "F.Fab") hide
        (effects (font (size 0.7 0.7) (thickness 0.15)) (justify left bottom))
    )
    (fp_text user "Author: Antmicro" (at -5.1 17.601 90) (layer "F.Fab") hide
        (effects (font (size 0.7 0.7) (thickness 0.15)) (justify left bottom))
    )
    (fp_text user "License: Apache-2.0" (at -5.1 18.802 90) (layer "F.Fab") hide
        (effects (font (size 0.7 0.7) (thickness 0.15)) (justify left bottom))
    )
    (fp_line (start -0.1 -4.8) (end 0.8255 -4.8)
      (stroke (width 0.15) (type solid)) (layer "F.SilkS"))
    (fp_line (start -0.1 -2.4) (end -0.1 -4.8)
      (stroke (width 0.15) (type solid)) (layer "F.SilkS"))
    (fp_line (start -0.1 4.8) (end -0.1 2.4)
      (stroke (width 0.15) (type solid)) (layer "F.SilkS"))
    (fp_line (start 10.1 4.8) (end 10.1 -4.8)
      (stroke (width 0.15) (type solid)) (layer "F.SilkS"))
    (fp_line (start 14 -4.8) (end 5.1 -4.8)
      (stroke (width 0.15) (type solid)) (layer "F.SilkS"))
    (fp_line (start 14 4.8) (end -0.1 4.8)
      (stroke (width 0.15) (type solid)) (layer "F.SilkS"))
    (fp_line (start 14 4.8) (end 14 -4.8)
      (stroke (width 0.15) (type solid)) (layer "F.SilkS"))
    (fp_line (start -1.3 -2.5) (end -1.3 2.5)
      (stroke (width 0.05) (type solid)) (layer "F.CrtYd"))
    (fp_line (start -1.3 2.5) (end -0.4 2.5)
      (stroke (width 0.05) (type solid)) (layer "F.CrtYd"))
    (fp_line (start -0.4 -5.1) (end -0.4 -2.5)
      (stroke (width 0.05) (type solid)) (layer "F.CrtYd"))
    (fp_line (start -0.4 -2.5) (end -1.3 -2.5)
      (stroke (width 0.05) (type solid)) (layer "F.CrtYd"))
    (fp_line (start -0.4 2.5) (end -0.4 5.1)
      (stroke (width 0.05) (type solid)) (layer "F.CrtYd"))
    (fp_line (start -0.4 5.1) (end 14.3 5.1)
      (stroke (width 0.05) (type solid)) (layer "F.CrtYd"))
    (fp_line (start 0.7 -6.1) (end 0.7 -5.1)
      (stroke (width 0.05) (type solid)) (layer "F.CrtYd"))
    (fp_line (start 0.7 -5.1) (end -0.4 -5.1)
      (stroke (width 0.05) (type solid)) (layer "F.CrtYd"))
    (fp_line (start 5.2 -6.1) (end 0.7 -6.1)
      (stroke (width 0.05) (type solid)) (layer "F.CrtYd"))
    (fp_line (start 5.2 -5.1) (end 5.2 -6.1)
      (stroke (width 0.05) (type solid)) (layer "F.CrtYd"))
    (fp_line (start 14.3 -5.1) (end 5.2 -5.1)
      (stroke (width 0.05) (type solid)) (layer "F.CrtYd"))
    (fp_line (start 14.3 5.1) (end 14.3 -5.1)
      (stroke (width 0.05) (type solid)) (layer "F.CrtYd"))
    (fp_line (start -0.4 3.6) (end 0.5 4.5)
      (stroke (width 0.15) (type solid)) (layer "F.Fab"))
    (fp_rect (start -0.4 4.5) (end 13.7 -5.111)
      (stroke (width 0.15) (type solid)) (fill none) (layer "F.Fab"))
    (pad "1" thru_hole oval (at 0 0 90) (size 2 4.5) (drill oval 1 3.5) (layers "*.Cu" "*.Mask")
      (net 22 "/Power Supply/DC Input/DC_IN") (pinfunction "1") (pintype "passive"))
    (pad "2" thru_hole oval (at 2.948 -4.879) (size 1.99 4) (drill oval 1 3) (layers "*.Cu" "*.Mask")
      (net 437 "unconnected-(J11-Pad2)") (pinfunction "2") (pintype "passive+no_connect"))
    (pad "3" thru_hole oval (at 5.999 0 270) (size 2 4) (drill oval 1 3) (layers "*.Cu" "*.Mask")
      (net 1 "GND") (pinfunction "3") (pintype "passive"))
  )

  (footprint "kria-k26-devboard-footprints:antmicro-logo" (layer "F.Cu")
    (at 91.1 78.779847)
    (property "Author" "Antmicro")
    (property "License" "Apache-2.0")
    (property "MPN" "")
    (property "Manufacturer" "")
    (property "Sheetfile" "kria-k26-devboard.kicad_sch")
    (property "Sheetname" "")
    (attr exclude_from_pos_files)
    (fp_text reference "N1" (at -7.7 -10.3) (layer "F.SilkS") hide
        (effects (font (size 1.524 1.524) (thickness 0.3)))
    )
    (fp_text value "antmicro_logo" (at -5.3 10.1) (layer "F.SilkS") hide
        (effects (font (size 1.524 1.524) (thickness 0.3)))
    )
    (fp_text user "License: Apache-2.0" (at -56.999 20.6) (layer "F.Fab") hide
        (effects (font (size 0.7 0.7) (thickness 0.15)) (justify left bottom))
    )
    (fp_text user "${REFERENCE}" (at -56.999 18.6) (layer "F.Fab") hide
        (effects (font (size 0.7 0.7) (thickness 0.15)) (justify left bottom))
    )
    (fp_text user "Author: Antmicro" (at -56.999 19.6) (layer "F.Fab") hide
        (effects (font (size 0.7 0.7) (thickness 0.15)) (justify left bottom))
    )
    (fp_poly
      (pts
        (xy 6.912132 1.55682)
        (xy 6.345204 1.55682)
        (xy 6.345204 -1.797504)
        (xy 6.912132 -1.797504)
        (xy 6.912132 1.55682)
      )

      (stroke (width 0.00279) (type solid)) (fill solid) (layer "F.Cu"))
    (fp_poly
      (pts
        (xy 11.340704 -1.841043)
        (xy 11.383146 -1.835075)
        (xy 11.399626 -1.825218)
        (xy 11.400312 -1.821945)
        (xy 11.393617 -1.787258)
        (xy 11.375745 -1.719809)
        (xy 11.35001 -1.631803)
        (xy 11.338272 -1.593625)
        (xy 11.306574 -1.497032)
        (xy 11.282387 -1.438676)
        (xy 11.261494 -1.411028)
        (xy 11.239676 -1.40656)
        (xy 11.234259 -1.407963)
        (xy 11.087402 -1.439293)
        (xy 10.923404 -1.449612)
        (xy 10.760846 -1.43919)
        (xy 10.618313 -1.408295)
        (xy 10.591259 -1.398688)
        (xy 10.526298 -1.373477)
        (xy 10.526298 1.55682)
        (xy 9.95937 1.55682)
        (xy 9.95937 -1.627357)
        (xy 10.130629 -1.688724)
        (xy 10.279454 -1.738722)
        (xy 10.415589 -1.775887)
        (xy 10.552002 -1.802432)
        (xy 10.701659 -1.820566)
        (xy 10.877526 -1.832501)
        (xy 11.004644 -1.837729)
        (xy 11.156748 -1.842159)
        (xy 11.267003 -1.843334)
        (xy 11.340704 -1.841043)
      )

      (stroke (width 0.00279) (type solid)) (fill solid) (layer "F.Cu"))
    (fp_poly
      (pts
        (xy 0.286882 -2.696334)
        (xy 0.291195 -2.633826)
        (xy 0.294644 -2.538397)
        (xy 0.296982 -2.41721)
        (xy 0.297958 -2.277426)
        (xy 0.297972 -2.258133)
        (xy 0.297972 -1.797504)
        (xy 0.8649 -1.797504)
        (xy 0.8649 -1.419552)
        (xy 0.297972 -1.419552)
        (xy 0.297972 0.887973)
        (xy 0.35171 0.989594)
        (xy 0.420809 1.086396)
        (xy 0.509669 1.146307)
        (xy 0.625356 1.172892)
        (xy 0.717312 1.174035)
        (xy 0.864999 1.167057)
        (xy 0.864949 1.348733)
        (xy 0.860772 1.460716)
        (xy 0.84846 1.528604)
        (xy 0.835373 1.548939)
        (xy 0.800261 1.557487)
        (xy 0.729644 1.565503)
        (xy 0.635257 1.571858)
        (xy 0.569625 1.57448)
        (xy 0.440081 1.575664)
        (xy 0.342385 1.569249)
        (xy 0.261533 1.553675)
        (xy 0.208325 1.536992)
        (xy 0.064544 1.469148)
        (xy -0.049904 1.37486)
        (xy -0.144592 1.245474)
        (xy -0.174468 1.191014)
        (xy -0.257145 1.030172)
        (xy -0.26386 -0.19469)
        (xy -0.270574 -1.419552)
        (xy -0.646908 -1.419552)
        (xy -0.646908 -1.797504)
        (xy -0.268956 -1.797504)
        (xy -0.268956 -2.551783)
        (xy -0.001508 -2.635272)
        (xy 0.104164 -2.667861)
        (xy 0.192964 -2.694497)
        (xy 0.255428 -2.712391)
        (xy 0.281956 -2.718762)
        (xy 0.286882 -2.696334)
      )

      (stroke (width 0.00279) (type solid)) (fill solid) (layer "F.Cu"))
    (fp_poly
      (pts
        (xy -2.136607 -1.83175)
        (xy -2.010904 -1.828463)
        (xy -1.914265 -1.822037)
        (xy -1.837617 -1.811764)
        (xy -1.771885 -1.796939)
        (xy -1.74634 -1.789492)
        (xy -1.532158 -1.70751)
        (xy -1.359129 -1.605683)
        (xy -1.224749 -1.482223)
        (xy -1.136379 -1.354088)
        (xy -1.108163 -1.301039)
        (xy -1.084174 -1.250965)
        (xy -1.064068 -1.19968)
        (xy -1.047504 -1.142994)
        (xy -1.034138 -1.076717)
        (xy -1.023628 -0.996662)
        (xy -1.015631 -0.89864)
        (xy -1.009804 -0.778462)
        (xy -1.005806 -0.63194)
        (xy -1.003292 -0.454884)
        (xy -1.001922 -0.243105)
        (xy -1.001351 0.007584)
        (xy -1.001238 0.298006)
        (xy -1.001238 1.55682)
        (xy -1.568166 1.55682)
        (xy -1.568166 0.309141)
        (xy -1.568286 0.015459)
        (xy -1.56889 -0.234942)
        (xy -1.570346 -0.44602)
        (xy -1.573022 -0.621739)
        (xy -1.577286 -0.766058)
        (xy -1.583506 -0.882939)
        (xy -1.592049 -0.976344)
        (xy -1.603283 -1.050233)
        (xy -1.617577 -1.108567)
        (xy -1.635297 -1.155309)
        (xy -1.656812 -1.194418)
        (xy -1.682489 -1.229857)
        (xy -1.712696 -1.265585)
        (xy -1.714581 -1.267734)
        (xy -1.812287 -1.355903)
        (xy -1.931432 -1.417802)
        (xy -2.082042 -1.458151)
        (xy -2.138368 -1.46726)
        (xy -2.29674 -1.477433)
        (xy -2.472019 -1.46882)
        (xy -2.642327 -1.443409)
        (xy -2.766455 -1.410218)
        (xy -2.855565 -1.37937)
        (xy -2.861649 0.088725)
        (xy -2.867734 1.55682)
        (xy -3.434304 1.55682)
        (xy -3.434304 -1.626184)
        (xy -3.215801 -1.697862)
        (xy -3.065439 -1.745385)
        (xy -2.937666 -1.780369)
        (xy -2.819819 -1.804679)
        (xy -2.699238 -1.820176)
        (xy -2.563261 -1.828726)
        (xy -2.399228 -1.832192)
        (xy -2.300448 -1.832603)
        (xy -2.136607 -1.83175)
      )

      (stroke (width 0.00279) (type solid)) (fill solid) (layer "F.Cu"))
    (fp_poly
      (pts
        (xy 4.729063 -1.8271)
        (xy 4.959571 -1.776882)
        (xy 5.157893 -1.693771)
        (xy 5.323148 -1.578206)
        (xy 5.454451 -1.43062)
        (xy 5.517493 -1.325064)
        (xy 5.542461 -1.274165)
        (xy 5.563676 -1.22495)
        (xy 5.581442 -1.173239)
        (xy 5.596064 -1.114853)
        (xy 5.607848 -1.045613)
        (xy 5.617099 -0.96134)
        (xy 5.624121 -0.857855)
        (xy 5.629219 -0.730978)
        (xy 5.632699 -0.576531)
        (xy 5.634866 -0.390333)
        (xy 5.636025 -0.168207)
        (xy 5.63648 0.094028)
        (xy 5.636544 0.306017)
        (xy 5.636544 1.55682)
        (xy 5.071143 1.55682)
        (xy 5.064474 0.251704)
        (xy 5.057805 -1.053411)
        (xy 4.988868 -1.177834)
        (xy 4.895109 -1.301546)
        (xy 4.773134 -1.393175)
        (xy 4.629913 -1.452165)
        (xy 4.472416 -1.477959)
        (xy 4.307613 -1.470001)
        (xy 4.142475 -1.427734)
        (xy 3.98397 -1.350603)
        (xy 3.870799 -1.267078)
        (xy 3.770406 -1.179651)
        (xy 3.770406 1.55682)
        (xy 3.203478 1.55682)
        (xy 3.203478 0.278067)
        (xy 3.203064 -0.042779)
        (xy 3.201801 -0.31793)
        (xy 3.19966 -0.548927)
        (xy 3.196609 -0.737311)
        (xy 3.192619 -0.884624)
        (xy 3.187659 -0.992408)
        (xy 3.181699 -1.062204)
        (xy 3.176515 -1.09068)
        (xy 3.113168 -1.224355)
        (xy 3.012925 -1.331319)
        (xy 2.878719 -1.410269)
        (xy 2.713483 -1.459907)
        (xy 2.52015 -1.478929)
        (xy 2.324287 -1.468768)
        (xy 2.217475 -1.455784)
        (xy 2.140831 -1.44347)
        (xy 2.077483 -1.428123)
        (xy 2.010555 -1.406041)
        (xy 1.969229 -1.39085)
        (xy 1.904268 -1.366577)
        (xy 1.904268 1.55682)
        (xy 1.360962 1.55682)
        (xy 1.360962 -1.629932)
        (xy 1.585996 -1.702017)
        (xy 1.839432 -1.773628)
        (xy 2.076192 -1.818337)
        (xy 2.316338 -1.838944)
        (xy 2.565684 -1.838752)
        (xy 2.765772 -1.826957)
        (xy 2.929729 -1.804535)
        (xy 3.068058 -1.768421)
        (xy 3.191262 -1.715547)
        (xy 3.309844 -1.64285)
        (xy 3.35863 -1.60731)
        (xy 3.513772 -1.489884)
        (xy 3.612561 -1.570037)
        (xy 3.803824 -1.696423)
        (xy 4.018585 -1.783662)
        (xy 4.258747 -1.832362)
        (xy 4.467255 -1.843989)
        (xy 4.729063 -1.8271)
      )

      (stroke (width 0.00279) (type solid)) (fill solid) (layer "F.Cu"))
    (fp_poly
      (pts
        (xy 13.011 -1.828598)
        (xy 13.222157 -1.780519)
        (xy 13.409082 -1.697802)
        (xy 13.577941 -1.578087)
        (xy 13.656079 -1.505081)
        (xy 13.8057 -1.322147)
        (xy 13.924227 -1.106958)
        (xy 14.012192 -0.85815)
        (xy 14.070128 -0.574357)
        (xy 14.090393 -0.390545)
        (xy 14.101846 -0.06018)
        (xy 14.082517 0.248736)
        (xy 14.033408 0.533287)
        (xy 13.955524 0.790553)
        (xy 13.849866 1.017617)
        (xy 13.717438 1.211561)
        (xy 13.559243 1.369467)
        (xy 13.461074 1.440241)
        (xy 13.306254 1.517112)
        (xy 13.121999 1.574401)
        (xy 12.922961 1.609506)
        (xy 12.723792 1.619827)
        (xy 12.542357 1.603344)
        (xy 12.30932 1.539496)
        (xy 12.102782 1.436939)
        (xy 11.923619 1.296654)
        (xy 11.772705 1.119624)
        (xy 11.650914 0.906828)
        (xy 11.559121 0.659249)
        (xy 11.509091 0.443636)
        (xy 11.467044 0.123703)
        (xy 11.458222 -0.133265)
        (xy 12.022913 -0.133265)
        (xy 12.033208 0.130412)
        (xy 12.06476 0.384026)
        (xy 12.117594 0.617116)
        (xy 12.189245 0.813805)
        (xy 12.281708 0.968837)
        (xy 12.398869 1.090076)
        (xy 12.534807 1.175098)
        (xy 12.683598 1.221477)
        (xy 12.839322 1.226788)
        (xy 12.996055 1.188608)
        (xy 13.048162 1.165468)
        (xy 13.180842 1.078195)
        (xy 13.290857 0.958674)
        (xy 13.37932 0.804507)
        (xy 13.447344 0.613298)
        (xy 13.496041 0.382646)
        (xy 13.524253 0.1395)
        (xy 13.536499 -0.156891)
        (xy 13.524426 -0.432929)
        (xy 13.488984 -0.684487)
        (xy 13.431119 -0.907435)
        (xy 13.351781 -1.097642)
        (xy 13.251917 -1.250979)
        (xy 13.189895 -1.316899)
        (xy 13.054995 -1.412386)
        (xy 12.90868 -1.465731)
        (xy 12.757488 -1.478493)
        (xy 12.607953 -1.452231)
        (xy 12.466612 -1.388504)
        (xy 12.340002 -1.288871)
        (xy 12.234658 -1.15489)
        (xy 12.193793 -1.079317)
        (xy 12.119314 -0.880028)
        (xy 12.065991 -0.648948)
        (xy 12.033849 -0.396539)
        (xy 12.022913 -0.133265)
        (xy 11.458222 -0.133265)
        (xy 11.456366 -0.187331)
        (xy 11.476106 -0.484529)
        (xy 11.525315 -0.762953)
        (xy 11.603043 -1.017667)
        (xy 11.70834 -1.243733)
        (xy 11.840256 -1.436213)
        (xy 11.879302 -1.480693)
        (xy 12.04917 -1.632047)
        (xy 12.241107 -1.742502)
        (xy 12.456488 -1.812618)
        (xy 12.696687 -1.842957)
        (xy 12.769446 -1.844399)
        (xy 13.011 -1.828598)
      )

      (stroke (width 0.00279) (type solid)) (fill solid) (layer "F.Cu"))
    (fp_poly
      (pts
        (xy 8.814213 -1.840483)
        (xy 8.969759 -1.825412)
        (xy 9.056281 -1.809134)
        (xy 9.145452 -1.783461)
        (xy 9.241206 -1.748594)
        (xy 9.331151 -1.709938)
        (xy 9.402898 -1.672901)
        (xy 9.444054 -1.642889)
        (xy 9.447346 -1.638505)
        (xy 9.444801 -1.609133)
        (xy 9.427786 -1.551422)
        (xy 9.401635 -1.478945)
        (xy 9.371683 -1.405273)
        (xy 9.343265 -1.343977)
        (xy 9.321716 -1.308629)
        (xy 9.316165 -1.304791)
        (xy 9.28701 -1.3133)
        (xy 9.228967 -1.336582)
        (xy 9.170199 -1.362544)
        (xy 8.989584 -1.425274)
        (xy 8.810705 -1.449653)
        (xy 8.641862 -1.435423)
        (xy 8.493873 -1.383637)
        (xy 8.370199 -1.295153)
        (xy 8.256869 -1.165361)
        (xy 8.157444 -0.999709)
        (xy 8.075486 -0.803644)
        (xy 8.04073 -0.690661)
        (xy 8.0133 -0.551431)
        (xy 7.995672 -0.37999)
        (xy 7.987846 -0.190341)
        (xy 7.989822 0.003512)
        (xy 8.001598 0.187565)
        (xy 8.023174 0.347814)
        (xy 8.040794 0.426604)
        (xy 8.120911 0.661281)
        (xy 8.221774 0.853813)
        (xy 8.343673 1.00464)
        (xy 8.4869 1.114204)
        (xy 8.498013 1.120496)
        (xy 8.570319 1.157192)
        (xy 8.633963 1.178299)
        (xy 8.70729 1.187849)
        (xy 8.808641 1.18987)
        (xy 8.813703 1.189851)
        (xy 8.920044 1.185178)
        (xy 9.013384 1.169314)
        (xy 9.108059 1.137943)
        (xy 9.218407 1.086747)
        (xy 9.300948 1.043176)
        (xy 9.311241 1.049795)
        (xy 9.329071 1.080783)
        (xy 9.356659 1.141006)
        (xy 9.396222 1.235333)
        (xy 9.449978 1.368632)
        (xy 9.455034 1.381317)
        (xy 9.441745 1.40673)
        (xy 9.393674 1.442381)
        (xy 9.32065 1.48296)
        (xy 9.232503 1.523157)
        (xy 9.139062 1.557662)
        (xy 9.114694 1.565169)
        (xy 8.987614 1.592214)
        (xy 8.834546 1.609553)
        (xy 8.675805 1.616006)
        (xy 8.531704 1.610388)
        (xy 8.471184 1.602631)
        (xy 8.382682 1.580174)
        (xy 8.27615 1.542853)
        (xy 8.175909 1.499329)
        (xy 7.979839 1.377324)
        (xy 7.810569 1.217033)
        (xy 7.668836 1.019577)
        (xy 7.555379 0.786076)
        (xy 7.470937 0.517652)
        (xy 7.442822 0.386949)
        (xy 7.422315 0.232254)
        (xy 7.411523 0.048978)
        (xy 7.410053 -0.149598)
        (xy 7.417508 -0.350189)
        (xy 7.433495 -0.539511)
        (xy 7.457618 -0.704283)
        (xy 7.477921 -0.793551)
        (xy 7.569718 -1.055031)
        (xy 7.690906 -1.282895)
        (xy 7.839972 -1.475439)
        (xy 8.015408 -1.630955)
        (xy 8.215702 -1.747738)
        (xy 8.375078 -1.807062)
        (xy 8.499369 -1.831256)
        (xy 8.651582 -1.842414)
        (xy 8.814213 -1.840483)
      )

      (stroke (width 0.00279) (type solid)) (fill solid) (layer "F.Cu"))
    (fp_poly
      (pts
        (xy -5.050123 -1.828751)
        (xy -4.900576 -1.800755)
        (xy -4.730837 -1.748715)
        (xy -4.593875 -1.684132)
        (xy -4.475494 -1.599519)
        (xy -4.417289 -1.545833)
        (xy -4.33145 -1.438632)
        (xy -4.25438 -1.301382)
        (xy -4.194656 -1.151275)
        (xy -4.167075 -1.044179)
        (xy -4.161601 -0.991002)
        (xy -4.156686 -0.894515)
        (xy -4.152404 -0.758651)
        (xy -4.14883 -0.587342)
        (xy -4.146038 -0.38452)
        (xy -4.144102 -0.154118)
        (xy -4.143096 0.099932)
        (xy -4.142964 0.236107)
        (xy -4.142964 1.389255)
        (xy -4.253676 1.438228)
        (xy -4.451908 1.509446)
        (xy -4.681546 1.56447)
        (xy -4.929024 1.601579)
        (xy -5.180775 1.61905)
        (xy -5.423232 1.615164)
        (xy -5.551117 1.602857)
        (xy -5.801683 1.552934)
        (xy -6.015853 1.473578)
        (xy -6.193196 1.365257)
        (xy -6.33328 1.228443)
        (xy -6.435674 1.063605)
        (xy -6.499947 0.871213)
        (xy -6.525669 0.651739)
        (xy -6.524424 0.541559)
        (xy -6.521414 0.520731)
        (xy -5.980195 0.520731)
        (xy -5.975801 0.716157)
        (xy -5.933333 0.885059)
        (xy -5.853697 1.026031)
        (xy -5.737804 1.137664)
        (xy -5.58656 1.218552)
        (xy -5.514208 1.242597)
        (xy -5.421778 1.258401)
        (xy -5.297997 1.265595)
        (xy -5.157857 1.264744)
        (xy -5.016352 1.25641)
        (xy -4.888475 1.241159)
        (xy -4.789219 1.219554)
        (xy -4.774853 1.214784)
        (xy -4.662648 1.174427)
        (xy -4.662648 -0.312718)
        (xy -4.798474 -0.29633)
        (xy -4.885159 -0.282693)
        (xy -4.997384 -0.260692)
        (xy -5.115103 -0.234352)
        (xy -5.152116 -0.225299)
        (xy -5.394278 -0.150849)
        (xy -5.593128 -0.059371)
        (xy -5.749805 0.050162)
        (xy -5.865449 0.178776)
        (xy -5.941198 0.327497)
        (xy -5.978194 0.497353)
        (xy -5.980195 0.520731)
        (xy -6.521414 0.520731)
        (xy -6.493668 0.328754)
        (xy -6.422351 0.139568)
        (xy -6.30958 -0.028039)
        (xy -6.245225 -0.096814)
        (xy -6.103026 -0.209801)
        (xy -5.920199 -0.31379)
        (xy -5.702882 -0.406508)
        (xy -5.457208 -0.48568)
        (xy -5.189315 -0.549035)
        (xy -4.905337 -0.594299)
        (xy -4.901094 -0.594815)
        (xy -4.656202 -0.624496)
        (xy -4.67036 -0.825112)
        (xy -4.697756 -1.014305)
        (xy -4.7521 -1.166118)
        (xy -4.835845 -1.283573)
        (xy -4.951447 -1.369689)
        (xy -5.101362 -1.427488)
        (xy -5.173118 -1.443664)
        (xy -5.368453 -1.460676)
        (xy -5.585568 -1.444404)
        (xy -5.814301 -1.396375)
        (xy -6.044491 -1.318113)
        (xy -6.064756 -1.309714)
        (xy -6.137401 -1.280895)
        (xy -6.190621 -1.263081)
        (xy -6.21177 -1.260016)
        (xy -6.223817 -1.284953)
        (xy -6.246487 -1.340557)
        (xy -6.274545 -1.412991)
        (xy -6.30276 -1.488418)
        (xy -6.325898 -1.553)
        (xy -6.338724 -1.592902)
        (xy -6.33981 -1.598556)
        (xy -6.320033 -1.613975)
        (xy -6.268692 -1.64124)
        (xy -6.210986 -1.6681)
        (xy -5.998934 -1.744812)
        (xy -5.763807 -1.80055)
        (xy -5.51862 -1.833998)
        (xy -5.276387 -1.843837)
        (xy -5.050123 -1.828751)
      )

      (stroke (width 0.00279) (type solid)) (fill solid) (layer "F.Cu"))
    (fp_poly
      (pts
        (xy -11.634962 -4.909269)
        (xy -11.537229 -4.886866)
        (xy -11.535595 -4.886192)
        (xy -11.504855 -4.870152)
        (xy -11.436833 -4.832523)
        (xy -11.335138 -4.775379)
        (xy -11.203377 -4.700793)
        (xy -11.045161 -4.610843)
        (xy -10.864096 -4.507601)
        (xy -10.663791 -4.393143)
        (xy -10.447855 -4.269542)
        (xy -10.219896 -4.138875)
        (xy -9.983523 -4.003215)
        (xy -9.742343 -3.864638)
        (xy -9.499965 -3.725217)
        (xy -9.259997 -3.587029)
        (xy -9.026048 -3.452146)
        (xy -8.801727 -3.322644)
        (xy -8.590641 -3.200598)
        (xy -8.396399 -3.088082)
        (xy -8.222609 -2.98717)
        (xy -8.07288 -2.899939)
        (xy -7.950819 -2.828462)
        (xy -7.860036 -2.774814)
        (xy -7.804139 -2.741069)
        (xy -7.797751 -2.737074)
        (xy -7.697553 -2.654792)
        (xy -7.620586 -2.556391)
        (xy -7.556343 -2.447109)
        (xy -7.549972 -0.195459)
        (xy -7.549017 0.235367)
        (xy -7.548701 0.6241)
        (xy -7.549022 0.970152)
        (xy -7.549975 1.272938)
        (xy -7.551555 1.53187)
        (xy -7.553759 1.746362)
        (xy -7.556581 1.915829)
        (xy -7.560017 2.039683)
        (xy -7.564064 2.117338)
        (xy -7.567619 2.145384)
        (xy -7.577264 2.180947)
        (xy -7.587545 2.213383)
        (xy -7.600916 2.244325)
        (xy -7.619829 2.275406)
        (xy -7.646736 2.30826)
        (xy -7.684091 2.344521)
        (xy -7.734346 2.385822)
        (xy -7.799953 2.433797)
        (xy -7.883366 2.49008)
        (xy -7.987037 2.556303)
        (xy -8.113418 2.634101)
        (xy -8.264963 2.725108)
        (xy -8.444124 2.830956)
        (xy -8.653354 2.953279)
        (xy -8.895105 3.093711)
        (xy -9.17183 3.253885)
        (xy -9.485981 3.435436)
        (xy -9.625797 3.516214)
        (xy -11.524839 4.613405)
        (xy -11.702004 4.622509)
        (xy -11.879169 4.631612)
        (xy -12.576018 4.230845)
        (xy -13.002735 3.985469)
        (xy -13.390442 3.762529)
        (xy -13.741039 3.560827)
        (xy -14.056425 3.379165)
        (xy -14.338499 3.216347)
        (xy -14.589159 3.071175)
        (xy -14.810305 2.942451)
        (xy -15.003836 2.828979)
        (xy -15.171651 2.729561)
        (xy -15.315648 2.643)
        (xy -15.437727 2.568099)
        (xy -15.539787 2.503659)
        (xy -15.623728 2.448485)
        (xy -15.691447 2.401378)
        (xy -15.744844 2.361141)
        (xy -15.785818 2.326577)
        (xy -15.816268 2.296489)
        (xy -15.838093 2.269678)
        (xy -15.853192 2.244949)
        (xy -15.863464 2.221104)
        (xy -15.870808 2.196945)
        (xy -15.877123 2.171275)
        (xy -15.883619 2.145435)
        (xy -15.888143 2.103987)
        (xy -15.892058 2.015869)
        (xy -15.895361 1.881652)
        (xy -15.898047 1.701907)
        (xy -15.900112 1.477205)
        (xy -15.901551 1.208115)
        (xy -15.902361 0.89521)
        (xy -15.902536 0.539059)
        (xy -15.902073 0.140233)
        (xy -15.901402 -0.143964)
        (xy -14.442156 -0.143964)
        (xy -14.442124 0.163081)
        (xy -14.441853 0.426492)
        (xy -14.441076 0.649878)
        (xy -14.439527 0.836849)
        (xy -14.436941 0.991014)
        (xy -14.433052 1.115983)
        (xy -14.427595 1.215365)
        (xy -14.420304 1.292771)
        (xy -14.410912 1.351809)
        (xy -14.399155 1.39609)
        (xy -14.384767 1.429223)
        (xy -14.367482 1.454817)
        (xy -14.347035 1.476482)
        (xy -14.323159 1.497828)
        (xy -14.321185 1.49955)
        (xy -14.289536 1.521118)
        (xy -14.221441 1.563277)
        (xy -14.121348 1.623467)
        (xy -13.993705 1.699126)
        (xy -13.842963 1.787694)
        (xy -13.67357 1.88661)
        (xy -13.489974 1.993314)
        (xy -13.296625 2.105246)
        (xy -13.097972 2.219844)
        (xy -12.898464 2.334548)
        (xy -12.702549 2.446797)
        (xy -12.514678 2.554031)
        (xy -12.339297 2.653689)
        (xy -12.180857 2.74321)
        (xy -12.043807 2.820035)
        (xy -11.932595 2.881601)
        (xy -11.85167 2.92535)
        (xy -11.805481 2.948719)
        (xy -11.798239 2.951643)
        (xy -11.739669 2.967611)
        (xy -11.698729 2.968556)
        (xy -11.650207 2.952973)
        (xy -11.621431 2.941108)
        (xy -11.582082 2.921398)
        (xy -11.507211 2.880786)
        (xy -11.401295 2.821862)
        (xy -11.26881 2.747214)
        (xy -11.114234 2.659433)
        (xy -10.942044 2.561108)
        (xy -10.756716 2.454828)
        (xy -10.562727 2.343182)
        (xy -10.364553 2.228759)
        (xy -10.166673 2.11415)
        (xy -9.973562 2.001942)
        (xy -9.789697 1.894726)
        (xy -9.619556 1.795091)
        (xy -9.467615 1.705626)
        (xy -9.338351 1.628921)
        (xy -9.236241 1.567564)
        (xy -9.165761 1.524145)
        (xy -9.131389 1.501254)
        (xy -9.130067 1.500156)
        (xy -9.105914 1.478431)
        (xy -9.08521 1.456719)
        (xy -9.06769 1.431407)
        (xy -9.053089 1.398882)
        (xy -9.04114 1.355531)
        (xy -9.031578 1.297741)
        (xy -9.024136 1.221898)
        (xy -9.01855 1.12439)
        (xy -9.014552 1.001603)
        (xy -9.011878 0.849924)
        (xy -9.010261 0.665741)
        (xy -9.009436 0.445438)
        (xy -9.009136 0.185404)
        (xy -9.009096 -0.117974)
        (xy -9.009096 -0.143964)
        (xy -9.0091 -0.452362)
        (xy -9.009321 -0.717103)
        (xy -9.010073 -0.941774)
        (xy -9.01167 -1.129961)
        (xy -9.014425 -1.285251)
        (xy -9.018653 -1.411232)
        (xy -9.024668 -1.511489)
        (xy -9.032783 -1.58961)
        (xy -9.043312 -1.649182)
        (xy -9.056569 -1.69379)
        (xy -9.072868 -1.727023)
        (xy -9.092523 -1.752467)
        (xy -9.115847 -1.773708)
        (xy -9.143156 -1.794333)
        (xy -9.154227 -1.80245)
        (xy -9.188912 -1.824767)
        (xy -9.260658 -1.868304)
        (xy -9.365548 -1.930764)
        (xy -9.499667 -2.009853)
        (xy -9.659099 -2.103275)
        (xy -9.839929 -2.208734)
        (xy -10.038241 -2.323934)
        (xy -10.250119 -2.44658)
        (xy -10.42874 -2.549657)
        (xy -10.683967 -2.696551)
        (xy -10.901677 -2.821355)
        (xy -11.085146 -2.925812)
        (xy -11.237649 -3.011663)
        (xy -11.362461 -3.080652)
        (xy -11.462857 -3.134521)
        (xy -11.542113 -3.175015)
        (xy -11.603503 -3.203875)
        (xy -11.650303 -3.222844)
        (xy -11.685788 -3.233665)
        (xy -11.713233 -3.238082)
        (xy -11.723096 -3.238446)
        (xy -11.747788 -3.236214)
        (xy -11.779117 -3.228375)
        (xy -11.820299 -3.213209)
        (xy -11.87455 -3.189)
        (xy -11.945086 -3.154031)
        (xy -12.035122 -3.106582)
        (xy -12.147874 -3.044939)
        (xy -12.286558 -2.967382)
        (xy -12.45439 -2.872194)
        (xy -12.654587 -2.757658)
        (xy -12.890362 -2.622057)
        (xy -13.055415 -2.526885)
        (xy -13.277555 -2.398503)
        (xy -13.488307 -2.276303)
        (xy -13.683963 -2.162462)
        (xy -13.860818 -2.059154)
        (xy -14.015167 -1.968555)
        (xy -14.143302 -1.892839)
        (xy -14.241518 -1.834183)
        (xy -14.30611 -1.79476)
        (xy -14.333212 -1.776887)
        (xy -14.354964 -1.757361)
        (xy -14.373609 -1.736701)
        (xy -14.389386 -1.711319)
        (xy -14.402536 -1.677626)
        (xy -14.413297 -1.632035)
        (xy -14.421909 -1.570958)
        (xy -14.428611 -1.490807)
        (xy -14.433642 -1.387994)
        (xy -14.437243 -1.258931)
        (xy -14.439651 -1.100029)
        (xy -14.441108 -0.907702)
        (xy -14.441851 -0.678361)
        (xy -14.44212 -0.408418)
        (xy -14.442156 -0.143964)
        (xy -15.901402 -0.143964)
        (xy -15.90128 -0.195459)
        (xy -15.900261 -0.578211)
        (xy -15.899381 -0.916603)
        (xy -15.898458 -1.213517)
        (xy -15.89731 -1.471836)
        (xy -15.895755 -1.694444)
        (xy -15.893611 -1.884222)
        (xy -15.890696 -2.044053)
        (xy -15.886827 -2.176821)
        (xy -15.881824 -2.285408)
        (xy -15.875504 -2.372697)
        (xy -15.867686 -2.441569)
        (xy -15.858186 -2.49491)
        (xy -15.846824 -2.535599)
        (xy -15.833418 -2.566522)
        (xy -15.817785 -2.59056)
        (xy -15.799743 -2.610596)
        (xy -15.779112 -2.629513)
        (xy -15.755708 -2.650193)
        (xy -15.745777 -2.659371)
        (xy -15.715671 -2.680398)
        (xy -15.647598 -2.723193)
        (xy -15.544554 -2.785985)
        (xy -15.409536 -2.867005)
        (xy -15.245541 -2.964486)
        (xy -15.055566 -3.076657)
        (xy -14.842607 -3.20175)
        (xy -14.609663 -3.337996)
        (xy -14.359728 -3.483626)
        (xy -14.0958 -3.636872)
        (xy -13.820877 -3.795963)
        (xy -13.791539 -3.812909)
        (xy -13.471051 -3.997959)
        (xy -13.18881 -4.160791)
        (xy -12.942164 -4.302841)
        (xy -12.728464 -4.425542)
        (xy -12.545058 -4.530328)
        (xy -12.389295 -4.618633)
        (xy -12.258526 -4.691893)
        (xy -12.150098 -4.751541)
        (xy -12.061361 -4.799011)
        (xy -11.989665 -4.835738)
        (xy -11.932359 -4.863157)
        (xy -11.886792 -4.8827)
        (xy -11.850312 -4.895803)
        (xy -11.820271 -4.9039)
        (xy -11.794016 -4.908426)
        (xy -11.768896 -4.910813)
        (xy -11.761531 -4.911305)
        (xy -11.634962 -4.909269)
      )

      (stroke (width 0.00279) (type solid)) (fill solid) (layer "F.Cu"))
    (fp_poly
      (pts
        (xy -11.598428 -2.080424)
        (xy -11.57723 -2.072066)
        (xy -11.468751 -2.001658)
        (xy -11.389638 -1.901364)
        (xy -11.34533 -1.781817)
        (xy -11.341267 -1.653648)
        (xy -11.347026 -1.622167)
        (xy -11.393935 -1.501154)
        (xy -11.47506 -1.410426)
        (xy -11.556887 -1.360523)
        (xy -11.65476 -1.313304)
        (xy -11.65476 -0.758136)
        (xy -11.242486 -0.758136)
        (xy -11.072717 -0.926772)
        (xy -10.902947 -1.095409)
        (xy -10.91549 -1.216935)
        (xy -10.915635 -1.219488)
        (xy -10.755191 -1.219488)
        (xy -10.728778 -1.164434)
        (xy -10.673757 -1.138779)
        (xy -10.607221 -1.144244)
        (xy -10.558024 -1.173208)
        (xy -10.524273 -1.228567)
        (xy -10.536119 -1.285278)
        (xy -10.568148 -1.325064)
        (xy -10.613088 -1.363188)
        (xy -10.650323 -1.366995)
        (xy -10.700942 -1.338104)
        (xy -10.704624 -1.335536)
        (xy -10.746388 -1.283194)
        (xy -10.755191 -1.219488)
        (xy -10.915635 -1.219488)
        (xy -10.919936 -1.294799)
        (xy -10.9095 -1.347615)
        (xy -10.878693 -1.396634)
        (xy -10.864682 -1.413748)
        (xy -10.778844 -1.486331)
        (xy -10.684406 -1.519496)
        (xy -10.589344 -1.517602)
        (xy -10.501633 -1.485007)
        (xy -10.429249 -1.426066)
        (xy -10.380166 -1.34514)
        (xy -10.36236 -1.246585)
        (xy -10.379014 -1.148379)
        (xy -10.432246 -1.055367)
        (xy -10.517668 -0.995483)
        (xy -10.631547 -0.971164)
        (xy -10.650843 -0.970734)
        (xy -10.700173 -0.969021)
        (xy -10.741166 -0.960188)
        (xy -10.782998 -0.93869)
        (xy -10.834845 -0.898984)
        (xy -10.905884 -0.835526)
        (xy -10.96366 -0.781758)
        (xy -11.165642 -0.592782)
        (xy -11.65476 -0.592782)
        (xy -11.65476 -0.21483)
        (xy -10.758337 -0.21483)
        (xy -10.723338 -0.282511)
        (xy -10.659408 -0.359534)
        (xy -10.571221 -0.40564)
        (xy -10.47149 -0.419331)
        (xy -10.372929 -0.399105)
        (xy -10.288248 -0.343464)
        (xy -10.280045 -0.334805)
        (xy -10.218985 -0.239159)
        (xy -10.198673 -0.141594)
        (xy -10.213428 -0.048914)
        (xy -10.257567 0.032077)
        (xy -10.325406 0.094573)
        (xy -10.411263 0.13177)
        (xy -10.509456 0.136864)
        (xy -10.614302 0.103049)
        (xy -10.63563 0.090981)
        (xy -10.690298 0.048218)
        (xy -10.724151 0.004288)
        (xy -10.726968 -0.003419)
        (xy -10.733524 -0.019303)
        (xy -10.747921 -0.031049)
        (xy -10.776503 -0.03928)
        (xy -10.825609 -0.044615)
        (xy -10.901582 -0.047677)
        (xy -11.010765 -0.049088)
        (xy -11.159498 -0.049469)
        (xy -11.196886 -0.049476)
        (xy -11.65476 -0.049476)
        (xy -11.65476 0.304854)
        (xy -11.169466 0.304854)
        (xy -10.777215 0.699153)
        (xy -10.666776 0.689665)
        (xy -10.54838 0.697916)
        (xy -10.45636 0.743895)
        (xy -10.393666 0.825779)
        (xy -10.377361 0.868512)
        (xy -10.361371 0.981493)
        (xy -10.388493 1.07909)
        (xy -10.447693 1.156536)
        (xy -10.539198 1.220541)
        (xy -10.636418 1.243765)
        (xy -10.730888 1.23049)
        (xy -10.81414 1.185001)
        (xy -10.877707 1.111581)
        (xy -10.913123 1.014512)
        (xy -10.914674 0.943593)
        (xy -10.75263 0.943593)
        (xy -10.744939 1.002359)
        (xy -10.722338 1.036421)
        (xy -10.668584 1.077858)
        (xy -10.616765 1.074443)
        (xy -10.568148 1.037136)
        (xy -10.527141 0.979502)
        (xy -10.530991 0.9279)
        (xy -10.5662 0.885356)
        (xy -10.625941 0.854578)
        (xy -10.683408 0.860296)
        (xy -10.728879 0.893103)
        (xy -10.75263 0.943593)
        (xy -10.914674 0.943593)
        (xy -10.91519 0.920035)
        (xy -10.901974 0.808447)
        (xy -11.242486 0.470208)
        (xy -11.65476 0.470208)
        (xy -11.65476 1.029961)
        (xy -11.557366 1.073879)
        (xy -11.455133 1.142987)
        (xy -11.384628 1.237535)
        (xy -11.346116 1.348001)
        (xy -11.33986 1.464867)
        (xy -11.366124 1.578613)
        (xy -11.42517 1.679718)
        (xy -11.517263 1.758662)
        (xy -11.538089 1.770152)
        (xy -11.661781 1.808862)
        (xy -11.793522 1.808868)
        (xy -11.91585 1.770223)
        (xy -11.918197 1.768995)
        (xy -12.015055 1.693955)
        (xy -12.078707 1.595232)
        (xy -12.109487 1.482413)
        (xy -12.108656 1.426899)
        (xy -11.947673 1.426899)
        (xy -11.938086 1.497165)
        (xy -11.90202 1.553977)
        (xy -11.87171 1.583435)
        (xy -11.784326 1.639137)
        (xy -11.698287 1.647711)
        (xy -11.61162 1.609158)
        (xy -11.579542 1.583435)
        (xy -11.526679 1.525013)
        (xy -11.505614 1.464095)
        (xy -11.503579 1.426899)
        (xy -11.524839 1.341071)
        (xy -11.580199 1.266709)
        (xy -11.65703 1.216575)
        (xy -11.725626 1.20249)
        (xy -11.81055 1.223976)
        (xy -11.88413 1.279925)
        (xy -11.933736 1.357574)
        (xy -11.947673 1.426899)
        (xy -12.108656 1.426899)
        (xy -12.107731 1.365086)
        (xy -12.073774 1.252838)
        (xy -12.007952 1.155256)
        (xy -11.9106 1.081929)
        (xy -11.893886 1.073879)
        (xy -11.796492 1.029961)
        (xy -11.796492 0.470208)
        (xy -12.208766 0.470208)
        (xy -12.549278 0.808447)
        (xy -12.536062 0.920035)
        (xy -12.541999 1.033334)
        (xy -12.583046 1.126506)
        (xy -12.650738 1.195267)
        (xy -12.736606 1.235334)
        (xy -12.832185 1.242424)
        (xy -12.929008 1.212252)
        (xy -13.003559 1.156536)
        (xy -13.069237 1.066034)
        (xy -13.090194 0.96674)
        (xy -13.085366 0.937646)
        (xy -12.92434 0.937646)
        (xy -12.919831 0.989652)
        (xy -12.883104 1.037136)
        (xy -12.825593 1.07811)
        (xy -12.774031 1.074247)
        (xy -12.730422 1.038088)
        (xy -12.700833 0.977326)
        (xy -12.708615 0.915658)
        (xy -12.749494 0.869261)
        (xy -12.778117 0.857531)
        (xy -12.847796 0.860939)
        (xy -12.884056 0.884454)
        (xy -12.92434 0.937646)
        (xy -13.085366 0.937646)
        (xy -13.073891 0.868512)
        (xy -13.02385 0.772676)
        (xy -12.943292 0.712009)
        (xy -12.83517 0.688335)
        (xy -12.784476 0.689665)
        (xy -12.674037 0.699153)
        (xy -12.281786 0.304854)
        (xy -11.796492 0.304854)
        (xy -11.796492 -0.049476)
        (xy -12.255529 -0.049476)
        (xy -12.413558 -0.049274)
        (xy -12.530739 -0.04823)
        (xy -12.613468 -0.045683)
        (xy -12.668141 -0.040976)
        (xy -12.701154 -0.033451)
        (xy -12.718903 -0.022447)
        (xy -12.727784 -0.007307)
        (xy -12.730078 -0.000602)
        (xy -12.768179 0.053795)
        (xy -12.836662 0.101408)
        (xy -12.918753 0.132562)
        (xy -12.97286 0.139412)
        (xy -13.081927 0.119662)
        (xy -13.16716 0.066135)
        (xy -13.224798 -0.01218)
        (xy -13.251082 -0.106295)
        (xy -13.248267 -0.138461)
        (xy -13.092435 -0.138461)
        (xy -13.085594 -0.104362)
        (xy -13.06173 -0.074712)
        (xy -12.999893 -0.032025)
        (xy -12.936774 -0.035011)
        (xy -12.896602 -0.062974)
        (xy -12.862603 -0.123872)
        (xy -12.869847 -0.163375)
        (xy -10.58825 -0.163375)
        (xy -10.579305 -0.097122)
        (xy -10.55465 -0.062974)
        (xy -10.494098 -0.028987)
        (xy -10.430729 -0.040964)
        (xy -10.389522 -0.074712)
        (xy -10.360749 -0.113869)
        (xy -10.362101 -0.149471)
        (xy -10.380745 -0.186917)
        (xy -10.430735 -0.241425)
        (xy -10.490836 -0.256827)
        (xy -10.549013 -0.230385)
        (xy -10.553393 -0.226211)
        (xy -10.58825 -0.163375)
        (xy -12.869847 -0.163375)
        (xy -12.874232 -0.187285)
        (xy -12.904968 -0.225051)
        (xy -12.965739 -0.256682)
        (xy -13.023234 -0.242178)
        (xy -13.070485 -0.18675)
        (xy -13.092435 -0.138461)
        (xy -13.248267 -0.138461)
        (xy -13.24225 -0.20722)
        (xy -13.194545 -0.305966)
        (xy -13.171207 -0.334805)
        (xy -13.086844 -0.396657)
        (xy -12.988403 -0.420452)
        (xy -12.887861 -0.407544)
        (xy -12.797197 -0.359286)
        (xy -12.733093 -0.285314)
        (xy -12.691457 -0.21483)
        (xy -11.796492 -0.21483)
        (xy -11.796492 -0.592782)
        (xy -12.28561 -0.592782)
        (xy -12.487592 -0.781758)
        (xy -12.574784 -0.862522)
        (xy -12.637071 -0.916226)
        (xy -12.683768 -0.948383)
        (xy -12.724188 -0.964507)
        (xy -12.767644 -0.970114)
        (xy -12.806775 -0.970734)
        (xy -12.922899 -0.987671)
        (xy -13.00786 -1.039568)
        (xy -13.063979 -1.128054)
        (xy -13.074609 -1.158837)
        (xy -13.084885 -1.244074)
        (xy -12.930348 -1.244074)
        (xy -12.910031 -1.190176)
        (xy -12.860199 -1.152565)
        (xy -12.797538 -1.137632)
        (xy -12.738728 -1.15177)
        (xy -12.722474 -1.164434)
        (xy -12.695969 -1.22018)
        (xy -12.705149 -1.283867)
        (xy -12.746628 -1.335536)
        (xy -12.791873 -1.362923)
        (xy -12.817494 -1.372308)
        (xy -12.851732 -1.3546)
        (xy -12.892344 -1.313705)
        (xy -12.923186 -1.267968)
        (xy -12.930348 -1.244074)
        (xy -13.084885 -1.244074)
        (xy -13.087974 -1.269701)
        (xy -13.063381 -1.365651)
        (xy -13.008888 -1.442479)
        (xy -12.932552 -1.495976)
        (xy -12.842431 -1.521934)
        (xy -12.746584 -1.516145)
        (xy -12.653067 -1.474399)
        (xy -12.58657 -1.413748)
        (xy -12.548594 -1.36173)
        (xy -12.532631 -1.312282)
        (xy -12.533195 -1.24415)
        (xy -12.535762 -1.216935)
        (xy -12.548305 -1.095409)
        (xy -12.378536 -0.926772)
        (xy -12.208766 -0.758136)
        (xy -11.796492 -0.758136)
        (xy -11.796492 -1.315972)
        (xy -11.890413 -1.35741)
        (xy -12.000362 -1.428554)
        (xy -12.074751 -1.530309)
        (xy -12.103547 -1.608413)
        (xy -12.114691 -1.719427)
        (xy -11.953136 -1.719427)
        (xy -11.944244 -1.665249)
        (xy -11.927218 -1.625373)
        (xy -11.866718 -1.543897)
        (xy -11.786289 -1.49957)
        (xy -11.696376 -1.495069)
        (xy -11.607427 -1.533073)
        (xy -11.597127 -1.540764)
        (xy -11.527435 -1.615972)
        (xy -11.503765 -1.69764)
        (xy -11.522499 -1.783736)
        (xy -11.579788 -1.872176)
        (xy -11.655413 -1.92277)
        (xy -11.739655 -1.935681)
        (xy -11.822795 -1.911076)
        (xy -11.895117 -1.849121)
        (xy -11.937073 -1.77666)
        (xy -11.953136 -1.719427)
        (xy -12.114691 -1.719427)
        (xy -12.116284 -1.735287)
        (xy -12.089238 -1.852462)
        (xy -12.0293 -1.953869)
        (xy -11.943361 -2.033438)
        (xy -11.838308 -2.0851)
        (xy -11.721034 -2.102786)
        (xy -11.598428 -2.080424)
      )

      (stroke (width 0.00279) (type solid)) (fill solid) (layer "F.Cu"))
    (fp_poly
      (pts
        (xy 6.912132 1.55682)
        (xy 6.345204 1.55682)
        (xy 6.345204 -1.797504)
        (xy 6.912132 -1.797504)
        (xy 6.912132 1.55682)
      )

      (stroke (width 0.00279) (type solid)) (fill solid) (layer "F.Mask"))
    (fp_poly
      (pts
        (xy 11.340704 -1.841043)
        (xy 11.383146 -1.835075)
        (xy 11.399626 -1.825218)
        (xy 11.400312 -1.821945)
        (xy 11.393617 -1.787258)
        (xy 11.375745 -1.719809)
        (xy 11.35001 -1.631803)
        (xy 11.338272 -1.593625)
        (xy 11.306574 -1.497032)
        (xy 11.282387 -1.438676)
        (xy 11.261494 -1.411028)
        (xy 11.239676 -1.40656)
        (xy 11.234259 -1.407963)
        (xy 11.087402 -1.439293)
        (xy 10.923404 -1.449612)
        (xy 10.760846 -1.43919)
        (xy 10.618313 -1.408295)
        (xy 10.591259 -1.398688)
        (xy 10.526298 -1.373477)
        (xy 10.526298 1.55682)
        (xy 9.95937 1.55682)
        (xy 9.95937 -1.627357)
        (xy 10.130629 -1.688724)
        (xy 10.279454 -1.738722)
        (xy 10.415589 -1.775887)
        (xy 10.552002 -1.802432)
        (xy 10.701659 -1.820566)
        (xy 10.877526 -1.832501)
        (xy 11.004644 -1.837729)
        (xy 11.156748 -1.842159)
        (xy 11.267003 -1.843334)
        (xy 11.340704 -1.841043)
      )

      (stroke (width 0.00279) (type solid)) (fill solid) (layer "F.Mask"))
    (fp_poly
      (pts
        (xy 0.286882 -2.696334)
        (xy 0.291195 -2.633826)
        (xy 0.294644 -2.538397)
        (xy 0.296982 -2.41721)
        (xy 0.297958 -2.277426)
        (xy 0.297972 -2.258133)
        (xy 0.297972 -1.797504)
        (xy 0.8649 -1.797504)
        (xy 0.8649 -1.419552)
        (xy 0.297972 -1.419552)
        (xy 0.297972 0.887973)
        (xy 0.35171 0.989594)
        (xy 0.420809 1.086396)
        (xy 0.509669 1.146307)
        (xy 0.625356 1.172892)
        (xy 0.717312 1.174035)
        (xy 0.864999 1.167057)
        (xy 0.864949 1.348733)
        (xy 0.860772 1.460716)
        (xy 0.84846 1.528604)
        (xy 0.835373 1.548939)
        (xy 0.800261 1.557487)
        (xy 0.729644 1.565503)
        (xy 0.635257 1.571858)
        (xy 0.569625 1.57448)
        (xy 0.440081 1.575664)
        (xy 0.342385 1.569249)
        (xy 0.261533 1.553675)
        (xy 0.208325 1.536992)
        (xy 0.064544 1.469148)
        (xy -0.049904 1.37486)
        (xy -0.144592 1.245474)
        (xy -0.174468 1.191014)
        (xy -0.257145 1.030172)
        (xy -0.26386 -0.19469)
        (xy -0.270574 -1.419552)
        (xy -0.646908 -1.419552)
        (xy -0.646908 -1.797504)
        (xy -0.268956 -1.797504)
        (xy -0.268956 -2.551783)
        (xy -0.001508 -2.635272)
        (xy 0.104164 -2.667861)
        (xy 0.192964 -2.694497)
        (xy 0.255428 -2.712391)
        (xy 0.281956 -2.718762)
        (xy 0.286882 -2.696334)
      )

      (stroke (width 0.00279) (type solid)) (fill solid) (layer "F.Mask"))
    (fp_poly
      (pts
        (xy -2.136607 -1.83175)
        (xy -2.010904 -1.828463)
        (xy -1.914265 -1.822037)
        (xy -1.837617 -1.811764)
        (xy -1.771885 -1.796939)
        (xy -1.74634 -1.789492)
        (xy -1.532158 -1.70751)
        (xy -1.359129 -1.605683)
        (xy -1.224749 -1.482223)
        (xy -1.136379 -1.354088)
        (xy -1.108163 -1.301039)
        (xy -1.084174 -1.250965)
        (xy -1.064068 -1.19968)
        (xy -1.047504 -1.142994)
        (xy -1.034138 -1.076717)
        (xy -1.023628 -0.996662)
        (xy -1.015631 -0.89864)
        (xy -1.009804 -0.778462)
        (xy -1.005806 -0.63194)
        (xy -1.003292 -0.454884)
        (xy -1.001922 -0.243105)
        (xy -1.001351 0.007584)
        (xy -1.001238 0.298006)
        (xy -1.001238 1.55682)
        (xy -1.568166 1.55682)
        (xy -1.568166 0.309141)
        (xy -1.568286 0.015459)
        (xy -1.56889 -0.234942)
        (xy -1.570346 -0.44602)
        (xy -1.573022 -0.621739)
        (xy -1.577286 -0.766058)
        (xy -1.583506 -0.882939)
        (xy -1.592049 -0.976344)
        (xy -1.603283 -1.050233)
        (xy -1.617577 -1.108567)
        (xy -1.635297 -1.155309)
        (xy -1.656812 -1.194418)
        (xy -1.682489 -1.229857)
        (xy -1.712696 -1.265585)
        (xy -1.714581 -1.267734)
        (xy -1.812287 -1.355903)
        (xy -1.931432 -1.417802)
        (xy -2.082042 -1.458151)
        (xy -2.138368 -1.46726)
        (xy -2.29674 -1.477433)
        (xy -2.472019 -1.46882)
        (xy -2.642327 -1.443409)
        (xy -2.766455 -1.410218)
        (xy -2.855565 -1.37937)
        (xy -2.861649 0.088725)
        (xy -2.867734 1.55682)
        (xy -3.434304 1.55682)
        (xy -3.434304 -1.626184)
        (xy -3.215801 -1.697862)
        (xy -3.065439 -1.745385)
        (xy -2.937666 -1.780369)
        (xy -2.819819 -1.804679)
        (xy -2.699238 -1.820176)
        (xy -2.563261 -1.828726)
        (xy -2.399228 -1.832192)
        (xy -2.300448 -1.832603)
        (xy -2.136607 -1.83175)
      )

      (stroke (width 0.00279) (type solid)) (fill solid) (layer "F.Mask"))
    (fp_poly
      (pts
        (xy 4.729063 -1.8271)
        (xy 4.959571 -1.776882)
        (xy 5.157893 -1.693771)
        (xy 5.323148 -1.578206)
        (xy 5.454451 -1.43062)
        (xy 5.517493 -1.325064)
        (xy 5.542461 -1.274165)
        (xy 5.563676 -1.22495)
        (xy 5.581442 -1.173239)
        (xy 5.596064 -1.114853)
        (xy 5.607848 -1.045613)
        (xy 5.617099 -0.96134)
        (xy 5.624121 -0.857855)
        (xy 5.629219 -0.730978)
        (xy 5.632699 -0.576531)
        (xy 5.634866 -0.390333)
        (xy 5.636025 -0.168207)
        (xy 5.63648 0.094028)
        (xy 5.636544 0.306017)
        (xy 5.636544 1.55682)
        (xy 5.071143 1.55682)
        (xy 5.064474 0.251704)
        (xy 5.057805 -1.053411)
        (xy 4.988868 -1.177834)
        (xy 4.895109 -1.301546)
        (xy 4.773134 -1.393175)
        (xy 4.629913 -1.452165)
        (xy 4.472416 -1.477959)
        (xy 4.307613 -1.470001)
        (xy 4.142475 -1.427734)
        (xy 3.98397 -1.350603)
        (xy 3.870799 -1.267078)
        (xy 3.770406 -1.179651)
        (xy 3.770406 1.55682)
        (xy 3.203478 1.55682)
        (xy 3.203478 0.278067)
        (xy 3.203064 -0.042779)
        (xy 3.201801 -0.31793)
        (xy 3.19966 -0.548927)
        (xy 3.196609 -0.737311)
        (xy 3.192619 -0.884624)
        (xy 3.187659 -0.992408)
        (xy 3.181699 -1.062204)
        (xy 3.176515 -1.09068)
        (xy 3.113168 -1.224355)
        (xy 3.012925 -1.331319)
        (xy 2.878719 -1.410269)
        (xy 2.713483 -1.459907)
        (xy 2.52015 -1.478929)
        (xy 2.324287 -1.468768)
        (xy 2.217475 -1.455784)
        (xy 2.140831 -1.44347)
        (xy 2.077483 -1.428123)
        (xy 2.010555 -1.406041)
        (xy 1.969229 -1.39085)
        (xy 1.904268 -1.366577)
        (xy 1.904268 1.55682)
        (xy 1.360962 1.55682)
        (xy 1.360962 -1.629932)
        (xy 1.585996 -1.702017)
        (xy 1.839432 -1.773628)
        (xy 2.076192 -1.818337)
        (xy 2.316338 -1.838944)
        (xy 2.565684 -1.838752)
        (xy 2.765772 -1.826957)
        (xy 2.929729 -1.804535)
        (xy 3.068058 -1.768421)
        (xy 3.191262 -1.715547)
        (xy 3.309844 -1.64285)
        (xy 3.35863 -1.60731)
        (xy 3.513772 -1.489884)
        (xy 3.612561 -1.570037)
        (xy 3.803824 -1.696423)
        (xy 4.018585 -1.783662)
        (xy 4.258747 -1.832362)
        (xy 4.467255 -1.843989)
        (xy 4.729063 -1.8271)
      )

      (stroke (width 0.00279) (type solid)) (fill solid) (layer "F.Mask"))
    (fp_poly
      (pts
        (xy 13.011 -1.828598)
        (xy 13.222157 -1.780519)
        (xy 13.409082 -1.697802)
        (xy 13.577941 -1.578087)
        (xy 13.656079 -1.505081)
        (xy 13.8057 -1.322147)
        (xy 13.924227 -1.106958)
        (xy 14.012192 -0.85815)
        (xy 14.070128 -0.574357)
        (xy 14.090393 -0.390545)
        (xy 14.101846 -0.06018)
        (xy 14.082517 0.248736)
        (xy 14.033408 0.533287)
        (xy 13.955524 0.790553)
        (xy 13.849866 1.017617)
        (xy 13.717438 1.211561)
        (xy 13.559243 1.369467)
        (xy 13.461074 1.440241)
        (xy 13.306254 1.517112)
        (xy 13.121999 1.574401)
        (xy 12.922961 1.609506)
        (xy 12.723792 1.619827)
        (xy 12.542357 1.603344)
        (xy 12.30932 1.539496)
        (xy 12.102782 1.436939)
        (xy 11.923619 1.296654)
        (xy 11.772705 1.119624)
        (xy 11.650914 0.906828)
        (xy 11.559121 0.659249)
        (xy 11.509091 0.443636)
        (xy 11.467044 0.123703)
        (xy 11.458222 -0.133265)
        (xy 12.022913 -0.133265)
        (xy 12.033208 0.130412)
        (xy 12.06476 0.384026)
        (xy 12.117594 0.617116)
        (xy 12.189245 0.813805)
        (xy 12.281708 0.968837)
        (xy 12.398869 1.090076)
        (xy 12.534807 1.175098)
        (xy 12.683598 1.221477)
        (xy 12.839322 1.226788)
        (xy 12.996055 1.188608)
        (xy 13.048162 1.165468)
        (xy 13.180842 1.078195)
        (xy 13.290857 0.958674)
        (xy 13.37932 0.804507)
        (xy 13.447344 0.613298)
        (xy 13.496041 0.382646)
        (xy 13.524253 0.1395)
        (xy 13.536499 -0.156891)
        (xy 13.524426 -0.432929)
        (xy 13.488984 -0.684487)
        (xy 13.431119 -0.907435)
        (xy 13.351781 -1.097642)
        (xy 13.251917 -1.250979)
        (xy 13.189895 -1.316899)
        (xy 13.054995 -1.412386)
        (xy 12.90868 -1.465731)
        (xy 12.757488 -1.478493)
        (xy 12.607953 -1.452231)
        (xy 12.466612 -1.388504)
        (xy 12.340002 -1.288871)
        (xy 12.234658 -1.15489)
        (xy 12.193793 -1.079317)
        (xy 12.119314 -0.880028)
        (xy 12.065991 -0.648948)
        (xy 12.033849 -0.396539)
        (xy 12.022913 -0.133265)
        (xy 11.458222 -0.133265)
        (xy 11.456366 -0.187331)
        (xy 11.476106 -0.484529)
        (xy 11.525315 -0.762953)
        (xy 11.603043 -1.017667)
        (xy 11.70834 -1.243733)
        (xy 11.840256 -1.436213)
        (xy 11.879302 -1.480693)
        (xy 12.04917 -1.632047)
        (xy 12.241107 -1.742502)
        (xy 12.456488 -1.812618)
        (xy 12.696687 -1.842957)
        (xy 12.769446 -1.844399)
        (xy 13.011 -1.828598)
      )

      (stroke (width 0.00279) (type solid)) (fill solid) (layer "F.Mask"))
    (fp_poly
      (pts
        (xy 8.814213 -1.840483)
        (xy 8.969759 -1.825412)
        (xy 9.056281 -1.809134)
        (xy 9.145452 -1.783461)
        (xy 9.241206 -1.748594)
        (xy 9.331151 -1.709938)
        (xy 9.402898 -1.672901)
        (xy 9.444054 -1.642889)
        (xy 9.447346 -1.638505)
        (xy 9.444801 -1.609133)
        (xy 9.427786 -1.551422)
        (xy 9.401635 -1.478945)
        (xy 9.371683 -1.405273)
        (xy 9.343265 -1.343977)
        (xy 9.321716 -1.308629)
        (xy 9.316165 -1.304791)
        (xy 9.28701 -1.3133)
        (xy 9.228967 -1.336582)
        (xy 9.170199 -1.362544)
        (xy 8.989584 -1.425274)
        (xy 8.810705 -1.449653)
        (xy 8.641862 -1.435423)
        (xy 8.493873 -1.383637)
        (xy 8.370199 -1.295153)
        (xy 8.256869 -1.165361)
        (xy 8.157444 -0.999709)
        (xy 8.075486 -0.803644)
        (xy 8.04073 -0.690661)
        (xy 8.0133 -0.551431)
        (xy 7.995672 -0.37999)
        (xy 7.987846 -0.190341)
        (xy 7.989822 0.003512)
        (xy 8.001598 0.187565)
        (xy 8.023174 0.347814)
        (xy 8.040794 0.426604)
        (xy 8.120911 0.661281)
        (xy 8.221774 0.853813)
        (xy 8.343673 1.00464)
        (xy 8.4869 1.114204)
        (xy 8.498013 1.120496)
        (xy 8.570319 1.157192)
        (xy 8.633963 1.178299)
        (xy 8.70729 1.187849)
        (xy 8.808641 1.18987)
        (xy 8.813703 1.189851)
        (xy 8.920044 1.185178)
        (xy 9.013384 1.169314)
        (xy 9.108059 1.137943)
        (xy 9.218407 1.086747)
        (xy 9.300948 1.043176)
        (xy 9.311241 1.049795)
        (xy 9.329071 1.080783)
        (xy 9.356659 1.141006)
        (xy 9.396222 1.235333)
        (xy 9.449978 1.368632)
        (xy 9.455034 1.381317)
        (xy 9.441745 1.40673)
        (xy 9.393674 1.442381)
        (xy 9.32065 1.48296)
        (xy 9.232503 1.523157)
        (xy 9.139062 1.557662)
        (xy 9.114694 1.565169)
        (xy 8.987614 1.592214)
        (xy 8.834546 1.609553)
        (xy 8.675805 1.616006)
        (xy 8.531704 1.610388)
        (xy 8.471184 1.602631)
        (xy 8.382682 1.580174)
        (xy 8.27615 1.542853)
        (xy 8.175909 1.499329)
        (xy 7.979839 1.377324)
        (xy 7.810569 1.217033)
        (xy 7.668836 1.019577)
        (xy 7.555379 0.786076)
        (xy 7.470937 0.517652)
        (xy 7.442822 0.386949)
        (xy 7.422315 0.232254)
        (xy 7.411523 0.048978)
        (xy 7.410053 -0.149598)
        (xy 7.417508 -0.350189)
        (xy 7.433495 -0.539511)
        (xy 7.457618 -0.704283)
        (xy 7.477921 -0.793551)
        (xy 7.569718 -1.055031)
        (xy 7.690906 -1.282895)
        (xy 7.839972 -1.475439)
        (xy 8.015408 -1.630955)
        (xy 8.215702 -1.747738)
        (xy 8.375078 -1.807062)
        (xy 8.499369 -1.831256)
        (xy 8.651582 -1.842414)
        (xy 8.814213 -1.840483)
      )

      (stroke (width 0.00279) (type solid)) (fill solid) (layer "F.Mask"))
    (fp_poly
      (pts
        (xy -5.050123 -1.828751)
        (xy -4.900576 -1.800755)
        (xy -4.730837 -1.748715)
        (xy -4.593875 -1.684132)
        (xy -4.475494 -1.599519)
        (xy -4.417289 -1.545833)
        (xy -4.33145 -1.438632)
        (xy -4.25438 -1.301382)
        (xy -4.194656 -1.151275)
        (xy -4.167075 -1.044179)
        (xy -4.161601 -0.991002)
        (xy -4.156686 -0.894515)
        (xy -4.152404 -0.758651)
        (xy -4.14883 -0.587342)
        (xy -4.146038 -0.38452)
        (xy -4.144102 -0.154118)
        (xy -4.143096 0.099932)
        (xy -4.142964 0.236107)
        (xy -4.142964 1.389255)
        (xy -4.253676 1.438228)
        (xy -4.451908 1.509446)
        (xy -4.681546 1.56447)
        (xy -4.929024 1.601579)
        (xy -5.180775 1.61905)
        (xy -5.423232 1.615164)
        (xy -5.551117 1.602857)
        (xy -5.801683 1.552934)
        (xy -6.015853 1.473578)
        (xy -6.193196 1.365257)
        (xy -6.33328 1.228443)
        (xy -6.435674 1.063605)
        (xy -6.499947 0.871213)
        (xy -6.525669 0.651739)
        (xy -6.524424 0.541559)
        (xy -6.521414 0.520731)
        (xy -5.980195 0.520731)
        (xy -5.975801 0.716157)
        (xy -5.933333 0.885059)
        (xy -5.853697 1.026031)
        (xy -5.737804 1.137664)
        (xy -5.58656 1.218552)
        (xy -5.514208 1.242597)
        (xy -5.421778 1.258401)
        (xy -5.297997 1.265595)
        (xy -5.157857 1.264744)
        (xy -5.016352 1.25641)
        (xy -4.888475 1.241159)
        (xy -4.789219 1.219554)
        (xy -4.774853 1.214784)
        (xy -4.662648 1.174427)
        (xy -4.662648 -0.312718)
        (xy -4.798474 -0.29633)
        (xy -4.885159 -0.282693)
        (xy -4.997384 -0.260692)
        (xy -5.115103 -0.234352)
        (xy -5.152116 -0.225299)
        (xy -5.394278 -0.150849)
        (xy -5.593128 -0.059371)
        (xy -5.749805 0.050162)
        (xy -5.865449 0.178776)
        (xy -5.941198 0.327497)
        (xy -5.978194 0.497353)
        (xy -5.980195 0.520731)
        (xy -6.521414 0.520731)
        (xy -6.493668 0.328754)
        (xy -6.422351 0.139568)
        (xy -6.30958 -0.028039)
        (xy -6.245225 -0.096814)
        (xy -6.103026 -0.209801)
        (xy -5.920199 -0.31379)
        (xy -5.702882 -0.406508)
        (xy -5.457208 -0.48568)
        (xy -5.189315 -0.549035)
        (xy -4.905337 -0.594299)
        (xy -4.901094 -0.594815)
        (xy -4.656202 -0.624496)
        (xy -4.67036 -0.825112)
        (xy -4.697756 -1.014305)
        (xy -4.7521 -1.166118)
        (xy -4.835845 -1.283573)
        (xy -4.951447 -1.369689)
        (xy -5.101362 -1.427488)
        (xy -5.173118 -1.443664)
        (xy -5.368453 -1.460676)
        (xy -5.585568 -1.444404)
        (xy -5.814301 -1.396375)
        (xy -6.044491 -1.318113)
        (xy -6.064756 -1.309714)
        (xy -6.137401 -1.280895)
        (xy -6.190621 -1.263081)
        (xy -6.21177 -1.260016)
        (xy -6.223817 -1.284953)
        (xy -6.246487 -1.340557)
        (xy -6.274545 -1.412991)
        (xy -6.30276 -1.488418)
        (xy -6.325898 -1.553)
        (xy -6.338724 -1.592902)
        (xy -6.33981 -1.598556)
        (xy -6.320033 -1.613975)
        (xy -6.268692 -1.64124)
        (xy -6.210986 -1.6681)
        (xy -5.998934 -1.744812)
        (xy -5.763807 -1.80055)
        (xy -5.51862 -1.833998)
        (xy -5.276387 -1.843837)
        (xy -5.050123 -1.828751)
      )

      (stroke (width 0.00279) (type solid)) (fill solid) (layer "F.Mask"))
    (fp_poly
      (pts
        (xy -11.634962 -4.909269)
        (xy -11.537229 -4.886866)
        (xy -11.535595 -4.886192)
        (xy -11.504855 -4.870152)
        (xy -11.436833 -4.832523)
        (xy -11.335138 -4.775379)
        (xy -11.203377 -4.700793)
        (xy -11.045161 -4.610843)
        (xy -10.864096 -4.507601)
        (xy -10.663791 -4.393143)
        (xy -10.447855 -4.269542)
        (xy -10.219896 -4.138875)
        (xy -9.983523 -4.003215)
        (xy -9.742343 -3.864638)
        (xy -9.499965 -3.725217)
        (xy -9.259997 -3.587029)
        (xy -9.026048 -3.452146)
        (xy -8.801727 -3.322644)
        (xy -8.590641 -3.200598)
        (xy -8.396399 -3.088082)
        (xy -8.222609 -2.98717)
        (xy -8.07288 -2.899939)
        (xy -7.950819 -2.828462)
        (xy -7.860036 -2.774814)
        (xy -7.804139 -2.741069)
        (xy -7.797751 -2.737074)
        (xy -7.697553 -2.654792)
        (xy -7.620586 -2.556391)
        (xy -7.556343 -2.447109)
        (xy -7.549972 -0.195459)
        (xy -7.549017 0.235367)
        (xy -7.548701 0.6241)
        (xy -7.549022 0.970152)
        (xy -7.549975 1.272938)
        (xy -7.551555 1.53187)
        (xy -7.553759 1.746362)
        (xy -7.556581 1.915829)
        (xy -7.560017 2.039683)
        (xy -7.564064 2.117338)
        (xy -7.567619 2.145384)
        (xy -7.577264 2.180947)
        (xy -7.587545 2.213383)
        (xy -7.600916 2.244325)
        (xy -7.619829 2.275406)
        (xy -7.646736 2.30826)
        (xy -7.684091 2.344521)
        (xy -7.734346 2.385822)
        (xy -7.799953 2.433797)
        (xy -7.883366 2.49008)
        (xy -7.987037 2.556303)
        (xy -8.113418 2.634101)
        (xy -8.264963 2.725108)
        (xy -8.444124 2.830956)
        (xy -8.653354 2.953279)
        (xy -8.895105 3.093711)
        (xy -9.17183 3.253885)
        (xy -9.485981 3.435436)
        (xy -9.625797 3.516214)
        (xy -11.524839 4.613405)
        (xy -11.702004 4.622509)
        (xy -11.879169 4.631612)
        (xy -12.576018 4.230845)
        (xy -13.002735 3.985469)
        (xy -13.390442 3.762529)
        (xy -13.741039 3.560827)
        (xy -14.056425 3.379165)
        (xy -14.338499 3.216347)
        (xy -14.589159 3.071175)
        (xy -14.810305 2.942451)
        (xy -15.003836 2.828979)
        (xy -15.171651 2.729561)
        (xy -15.315648 2.643)
        (xy -15.437727 2.568099)
        (xy -15.539787 2.503659)
        (xy -15.623728 2.448485)
        (xy -15.691447 2.401378)
        (xy -15.744844 2.361141)
        (xy -15.785818 2.326577)
        (xy -15.816268 2.296489)
        (xy -15.838093 2.269678)
        (xy -15.853192 2.244949)
        (xy -15.863464 2.221104)
        (xy -15.870808 2.196945)
        (xy -15.877123 2.171275)
        (xy -15.883619 2.145435)
        (xy -15.888143 2.103987)
        (xy -15.892058 2.015869)
        (xy -15.895361 1.881652)
        (xy -15.898047 1.701907)
        (xy -15.900112 1.477205)
        (xy -15.901551 1.208115)
        (xy -15.902361 0.89521)
        (xy -15.902536 0.539059)
        (xy -15.902073 0.140233)
        (xy -15.901402 -0.143964)
        (xy -14.442156 -0.143964)
        (xy -14.442124 0.163081)
        (xy -14.441853 0.426492)
        (xy -14.441076 0.649878)
        (xy -14.439527 0.836849)
        (xy -14.436941 0.991014)
        (xy -14.433052 1.115983)
        (xy -14.427595 1.215365)
        (xy -14.420304 1.292771)
        (xy -14.410912 1.351809)
        (xy -14.399155 1.39609)
        (xy -14.384767 1.429223)
        (xy -14.367482 1.454817)
        (xy -14.347035 1.476482)
        (xy -14.323159 1.497828)
        (xy -14.321185 1.49955)
        (xy -14.289536 1.521118)
        (xy -14.221441 1.563277)
        (xy -14.121348 1.623467)
        (xy -13.993705 1.699126)
        (xy -13.842963 1.787694)
        (xy -13.67357 1.88661)
        (xy -13.489974 1.993314)
        (xy -13.296625 2.105246)
        (xy -13.097972 2.219844)
        (xy -12.898464 2.334548)
        (xy -12.702549 2.446797)
        (xy -12.514678 2.554031)
        (xy -12.339297 2.653689)
        (xy -12.180857 2.74321)
        (xy -12.043807 2.820035)
        (xy -11.932595 2.881601)
        (xy -11.85167 2.92535)
        (xy -11.805481 2.948719)
        (xy -11.798239 2.951643)
        (xy -11.739669 2.967611)
        (xy -11.698729 2.968556)
        (xy -11.650207 2.952973)
        (xy -11.621431 2.941108)
        (xy -11.582082 2.921398)
        (xy -11.507211 2.880786)
        (xy -11.401295 2.821862)
        (xy -11.26881 2.747214)
        (xy -11.114234 2.659433)
        (xy -10.942044 2.561108)
        (xy -10.756716 2.454828)
        (xy -10.562727 2.343182)
        (xy -10.364553 2.228759)
        (xy -10.166673 2.11415)
        (xy -9.973562 2.001942)
        (xy -9.789697 1.894726)
        (xy -9.619556 1.795091)
        (xy -9.467615 1.705626)
        (xy -9.338351 1.628921)
        (xy -9.236241 1.567564)
        (xy -9.165761 1.524145)
        (xy -9.131389 1.501254)
        (xy -9.130067 1.500156)
        (xy -9.105914 1.478431)
        (xy -9.08521 1.456719)
        (xy -9.06769 1.431407)
        (xy -9.053089 1.398882)
        (xy -9.04114 1.355531)
        (xy -9.031578 1.297741)
        (xy -9.024136 1.221898)
        (xy -9.01855 1.12439)
        (xy -9.014552 1.001603)
        (xy -9.011878 0.849924)
        (xy -9.010261 0.665741)
        (xy -9.009436 0.445438)
        (xy -9.009136 0.185404)
        (xy -9.009096 -0.117974)
        (xy -9.009096 -0.143964)
        (xy -9.0091 -0.452362)
        (xy -9.009321 -0.717103)
        (xy -9.010073 -0.941774)
        (xy -9.01167 -1.129961)
        (xy -9.014425 -1.285251)
        (xy -9.018653 -1.411232)
        (xy -9.024668 -1.511489)
        (xy -9.032783 -1.58961)
        (xy -9.043312 -1.649182)
        (xy -9.056569 -1.69379)
        (xy -9.072868 -1.727023)
        (xy -9.092523 -1.752467)
        (xy -9.115847 -1.773708)
        (xy -9.143156 -1.794333)
        (xy -9.154227 -1.80245)
        (xy -9.188912 -1.824767)
        (xy -9.260658 -1.868304)
        (xy -9.365548 -1.930764)
        (xy -9.499667 -2.009853)
        (xy -9.659099 -2.103275)
        (xy -9.839929 -2.208734)
        (xy -10.038241 -2.323934)
        (xy -10.250119 -2.44658)
        (xy -10.42874 -2.549657)
        (xy -10.683967 -2.696551)
        (xy -10.901677 -2.821355)
        (xy -11.085146 -2.925812)
        (xy -11.237649 -3.011663)
        (xy -11.362461 -3.080652)
        (xy -11.462857 -3.134521)
        (xy -11.542113 -3.175015)
        (xy -11.603503 -3.203875)
        (xy -11.650303 -3.222844)
        (xy -11.685788 -3.233665)
        (xy -11.713233 -3.238082)
        (xy -11.723096 -3.238446)
        (xy -11.747788 -3.236214)
        (xy -11.779117 -3.228375)
        (xy -11.820299 -3.213209)
        (xy -11.87455 -3.189)
        (xy -11.945086 -3.154031)
        (xy -12.035122 -3.106582)
        (xy -12.147874 -3.044939)
        (xy -12.286558 -2.967382)
        (xy -12.45439 -2.872194)
        (xy -12.654587 -2.757658)
        (xy -12.890362 -2.622057)
        (xy -13.055415 -2.526885)
        (xy -13.277555 -2.398503)
        (xy -13.488307 -2.276303)
        (xy -13.683963 -2.162462)
        (xy -13.860818 -2.059154)
        (xy -14.015167 -1.968555)
        (xy -14.143302 -1.892839)
        (xy -14.241518 -1.834183)
        (xy -14.30611 -1.79476)
        (xy -14.333212 -1.776887)
        (xy -14.354964 -1.757361)
        (xy -14.373609 -1.736701)
        (xy -14.389386 -1.711319)
        (xy -14.402536 -1.677626)
        (xy -14.413297 -1.632035)
        (xy -14.421909 -1.570958)
        (xy -14.428611 -1.490807)
        (xy -14.433642 -1.387994)
        (xy -14.437243 -1.258931)
        (xy -14.439651 -1.100029)
        (xy -14.441108 -0.907702)
        (xy -14.441851 -0.678361)
        (xy -14.44212 -0.408418)
        (xy -14.442156 -0.143964)
        (xy -15.901402 -0.143964)
        (xy -15.90128 -0.195459)
        (xy -15.900261 -0.578211)
        (xy -15.899381 -0.916603)
        (xy -15.898458 -1.213517)
        (xy -15.89731 -1.471836)
        (xy -15.895755 -1.694444)
        (xy -15.893611 -1.884222)
        (xy -15.890696 -2.044053)
        (xy -15.886827 -2.176821)
        (xy -15.881824 -2.285408)
        (xy -15.875504 -2.372697)
        (xy -15.867686 -2.441569)
        (xy -15.858186 -2.49491)
        (xy -15.846824 -2.535599)
        (xy -15.833418 -2.566522)
        (xy -15.817785 -2.59056)
        (xy -15.799743 -2.610596)
        (xy -15.779112 -2.629513)
        (xy -15.755708 -2.650193)
        (xy -15.745777 -2.659371)
        (xy -15.715671 -2.680398)
        (xy -15.647598 -2.723193)
        (xy -15.544554 -2.785985)
        (xy -15.409536 -2.867005)
        (xy -15.245541 -2.964486)
        (xy -15.055566 -3.076657)
        (xy -14.842607 -3.20175)
        (xy -14.609663 -3.337996)
        (xy -14.359728 -3.483626)
        (xy -14.0958 -3.636872)
        (xy -13.820877 -3.795963)
        (xy -13.791539 -3.812909)
        (xy -13.471051 -3.997959)
        (xy -13.18881 -4.160791)
        (xy -12.942164 -4.302841)
        (xy -12.728464 -4.425542)
        (xy -12.545058 -4.530328)
        (xy -12.389295 -4.618633)
        (xy -12.258526 -4.691893)
        (xy -12.150098 -4.751541)
        (xy -12.061361 -4.799011)
        (xy -11.989665 -4.835738)
        (xy -11.932359 -4.863157)
        (xy -11.886792 -4.8827)
        (xy -11.850312 -4.895803)
        (xy -11.820271 -4.9039)
        (xy -11.794016 -4.908426)
        (xy -11.768896 -4.910813)
        (xy -11.761531 -4.911305)
        (xy -11.634962 -4.909269)
      )

      (stroke (width 0.00279) (type solid)) (fill solid) (layer "F.Mask"))
    (fp_poly
      (pts
        (xy -11.598428 -2.080424)
        (xy -11.57723 -2.072066)
        (xy -11.468751 -2.001658)
        (xy -11.389638 -1.901364)
        (xy -11.34533 -1.781817)
        (xy -11.341267 -1.653648)
        (xy -11.347026 -1.622167)
        (xy -11.393935 -1.501154)
        (xy -11.47506 -1.410426)
        (xy -11.556887 -1.360523)
        (xy -11.65476 -1.313304)
        (xy -11.65476 -0.758136)
        (xy -11.242486 -0.758136)
        (xy -11.072717 -0.926772)
        (xy -10.902947 -1.095409)
        (xy -10.91549 -1.216935)
        (xy -10.915635 -1.219488)
        (xy -10.755191 -1.219488)
        (xy -10.728778 -1.164434)
        (xy -10.673757 -1.138779)
        (xy -10.607221 -1.144244)
        (xy -10.558024 -1.173208)
        (xy -10.524273 -1.228567)
        (xy -10.536119 -1.285278)
        (xy -10.568148 -1.325064)
        (xy -10.613088 -1.363188)
        (xy -10.650323 -1.366995)
        (xy -10.700942 -1.338104)
        (xy -10.704624 -1.335536)
        (xy -10.746388 -1.283194)
        (xy -10.755191 -1.219488)
        (xy -10.915635 -1.219488)
        (xy -10.919936 -1.294799)
        (xy -10.9095 -1.347615)
        (xy -10.878693 -1.396634)
        (xy -10.864682 -1.413748)
        (xy -10.778844 -1.486331)
        (xy -10.684406 -1.519496)
        (xy -10.589344 -1.517602)
        (xy -10.501633 -1.485007)
        (xy -10.429249 -1.426066)
        (xy -10.380166 -1.34514)
        (xy -10.36236 -1.246585)
        (xy -10.379014 -1.148379)
        (xy -10.432246 -1.055367)
        (xy -10.517668 -0.995483)
        (xy -10.631547 -0.971164)
        (xy -10.650843 -0.970734)
        (xy -10.700173 -0.969021)
        (xy -10.741166 -0.960188)
        (xy -10.782998 -0.93869)
        (xy -10.834845 -0.898984)
        (xy -10.905884 -0.835526)
        (xy -10.96366 -0.781758)
        (xy -11.165642 -0.592782)
        (xy -11.65476 -0.592782)
        (xy -11.65476 -0.21483)
        (xy -10.758337 -0.21483)
        (xy -10.723338 -0.282511)
        (xy -10.659408 -0.359534)
        (xy -10.571221 -0.40564)
        (xy -10.47149 -0.419331)
        (xy -10.372929 -0.399105)
        (xy -10.288248 -0.343464)
        (xy -10.280045 -0.334805)
        (xy -10.218985 -0.239159)
        (xy -10.198673 -0.141594)
        (xy -10.213428 -0.048914)
        (xy -10.257567 0.032077)
        (xy -10.325406 0.094573)
        (xy -10.411263 0.13177)
        (xy -10.509456 0.136864)
        (xy -10.614302 0.103049)
        (xy -10.63563 0.090981)
        (xy -10.690298 0.048218)
        (xy -10.724151 0.004288)
        (xy -10.726968 -0.003419)
        (xy -10.733524 -0.019303)
        (xy -10.747921 -0.031049)
        (xy -10.776503 -0.03928)
        (xy -10.825609 -0.044615)
        (xy -10.901582 -0.047677)
        (xy -11.010765 -0.049088)
        (xy -11.159498 -0.049469)
        (xy -11.196886 -0.049476)
        (xy -11.65476 -0.049476)
        (xy -11.65476 0.304854)
        (xy -11.169466 0.304854)
        (xy -10.777215 0.699153)
        (xy -10.666776 0.689665)
        (xy -10.54838 0.697916)
        (xy -10.45636 0.743895)
        (xy -10.393666 0.825779)
        (xy -10.377361 0.868512)
        (xy -10.361371 0.981493)
        (xy -10.388493 1.07909)
        (xy -10.447693 1.156536)
        (xy -10.539198 1.220541)
        (xy -10.636418 1.243765)
        (xy -10.730888 1.23049)
        (xy -10.81414 1.185001)
        (xy -10.877707 1.111581)
        (xy -10.913123 1.014512)
        (xy -10.914674 0.943593)
        (xy -10.75263 0.943593)
        (xy -10.744939 1.002359)
        (xy -10.722338 1.036421)
        (xy -10.668584 1.077858)
        (xy -10.616765 1.074443)
        (xy -10.568148 1.037136)
        (xy -10.527141 0.979502)
        (xy -10.530991 0.9279)
        (xy -10.5662 0.885356)
        (xy -10.625941 0.854578)
        (xy -10.683408 0.860296)
        (xy -10.728879 0.893103)
        (xy -10.75263 0.943593)
        (xy -10.914674 0.943593)
        (xy -10.91519 0.920035)
        (xy -10.901974 0.808447)
        (xy -11.242486 0.470208)
        (xy -11.65476 0.470208)
        (xy -11.65476 1.029961)
        (xy -11.557366 1.073879)
        (xy -11.455133 1.142987)
        (xy -11.384628 1.237535)
        (xy -11.346116 1.348001)
        (xy -11.33986 1.464867)
        (xy -11.366124 1.578613)
        (xy -11.42517 1.679718)
        (xy -11.517263 1.758662)
        (xy -11.538089 1.770152)
        (xy -11.661781 1.808862)
        (xy -11.793522 1.808868)
        (xy -11.91585 1.770223)
        (xy -11.918197 1.768995)
        (xy -12.015055 1.693955)
        (xy -12.078707 1.595232)
        (xy -12.109487 1.482413)
        (xy -12.108656 1.426899)
        (xy -11.947673 1.426899)
        (xy -11.938086 1.497165)
        (xy -11.90202 1.553977)
        (xy -11.87171 1.583435)
        (xy -11.784326 1.639137)
        (xy -11.698287 1.647711)
        (xy -11.61162 1.609158)
        (xy -11.579542 1.583435)
        (xy -11.526679 1.525013)
        (xy -11.505614 1.464095)
        (xy -11.503579 1.426899)
        (xy -11.524839 1.341071)
        (xy -11.580199 1.266709)
        (xy -11.65703 1.216575)
        (xy -11.725626 1.20249)
        (xy -11.81055 1.223976)
        (xy -11.88413 1.279925)
        (xy -11.933736 1.357574)
        (xy -11.947673 1.426899)
        (xy -12.108656 1.426899)
        (xy -12.107731 1.365086)
        (xy -12.073774 1.252838)
        (xy -12.007952 1.155256)
        (xy -11.9106 1.081929)
        (xy -11.893886 1.073879)
        (xy -11.796492 1.029961)
        (xy -11.796492 0.470208)
        (xy -12.208766 0.470208)
        (xy -12.549278 0.808447)
        (xy -12.536062 0.920035)
        (xy -12.541999 1.033334)
        (xy -12.583046 1.126506)
        (xy -12.650738 1.195267)
        (xy -12.736606 1.235334)
        (xy -12.832185 1.242424)
        (xy -12.929008 1.212252)
        (xy -13.003559 1.156536)
        (xy -13.069237 1.066034)
        (xy -13.090194 0.96674)
        (xy -13.085366 0.937646)
        (xy -12.92434 0.937646)
        (xy -12.919831 0.989652)
        (xy -12.883104 1.037136)
        (xy -12.825593 1.07811)
        (xy -12.774031 1.074247)
        (xy -12.730422 1.038088)
        (xy -12.700833 0.977326)
        (xy -12.708615 0.915658)
        (xy -12.749494 0.869261)
        (xy -12.778117 0.857531)
        (xy -12.847796 0.860939)
        (xy -12.884056 0.884454)
        (xy -12.92434 0.937646)
        (xy -13.085366 0.937646)
        (xy -13.073891 0.868512)
        (xy -13.02385 0.772676)
        (xy -12.943292 0.712009)
        (xy -12.83517 0.688335)
        (xy -12.784476 0.689665)
        (xy -12.674037 0.699153)
        (xy -12.281786 0.304854)
        (xy -11.796492 0.304854)
        (xy -11.796492 -0.049476)
        (xy -12.255529 -0.049476)
        (xy -12.413558 -0.049274)
        (xy -12.530739 -0.04823)
        (xy -12.613468 -0.045683)
        (xy -12.668141 -0.040976)
        (xy -12.701154 -0.033451)
        (xy -12.718903 -0.022447)
        (xy -12.727784 -0.007307)
        (xy -12.730078 -0.000602)
        (xy -12.768179 0.053795)
        (xy -12.836662 0.101408)
        (xy -12.918753 0.132562)
        (xy -12.97286 0.139412)
        (xy -13.081927 0.119662)
        (xy -13.16716 0.066135)
        (xy -13.224798 -0.01218)
        (xy -13.251082 -0.106295)
        (xy -13.248267 -0.138461)
        (xy -13.092435 -0.138461)
        (xy -13.085594 -0.104362)
        (xy -13.06173 -0.074712)
        (xy -12.999893 -0.032025)
        (xy -12.936774 -0.035011)
        (xy -12.896602 -0.062974)
        (xy -12.862603 -0.123872)
        (xy -12.869847 -0.163375)
        (xy -10.58825 -0.163375)
        (xy -10.579305 -0.097122)
        (xy -10.55465 -0.062974)
        (xy -10.494098 -0.028987)
        (xy -10.430729 -0.040964)
        (xy -10.389522 -0.074712)
        (xy -10.360749 -0.113869)
        (xy -10.362101 -0.149471)
        (xy -10.380745 -0.186917)
        (xy -10.430735 -0.241425)
        (xy -10.490836 -0.256827)
        (xy -10.549013 -0.230385)
        (xy -10.553393 -0.226211)
        (xy -10.58825 -0.163375)
        (xy -12.869847 -0.163375)
        (xy -12.874232 -0.187285)
        (xy -12.904968 -0.225051)
        (xy -12.965739 -0.256682)
        (xy -13.023234 -0.242178)
        (xy -13.070485 -0.18675)
        (xy -13.092435 -0.138461)
        (xy -13.248267 -0.138461)
        (xy -13.24225 -0.20722)
        (xy -13.194545 -0.305966)
        (xy -13.171207 -0.334805)
        (xy -13.086844 -0.396657)
        (xy -12.988403 -0.420452)
        (xy -12.887861 -0.407544)
        (xy -12.797197 -0.359286)
        (xy -12.733093 -0.285314)
        (xy -12.691457 -0.21483)
        (xy -11.796492 -0.21483)
        (xy -11.796492 -0.592782)
        (xy -12.28561 -0.592782)
        (xy -12.487592 -0.781758)
        (xy -12.574784 -0.862522)
        (xy -12.637071 -0.916226)
        (xy -12.683768 -0.948383)
        (xy -12.724188 -0.964507)
        (xy -12.767644 -0.970114)
        (xy -12.806775 -0.970734)
        (xy -12.922899 -0.987671)
        (xy -13.00786 -1.039568)
        (xy -13.063979 -1.128054)
        (xy -13.074609 -1.158837)
        (xy -13.084885 -1.244074)
        (xy -12.930348 -1.244074)
        (xy -12.910031 -1.190176)
        (xy -12.860199 -1.152565)
        (xy -12.797538 -1.137632)
        (xy -12.738728 -1.15177)
        (xy -12.722474 -1.164434)
        (xy -12.695969 -1.22018)
        (xy -12.705149 -1.283867)
        (xy -12.746628 -1.335536)
        (xy -12.791873 -1.362923)
        (xy -12.817494 -1.372308)
        (xy -12.851732 -1.3546)
        (xy -12.892344 -1.313705)
        (xy -12.923186 -1.267968)
        (xy -12.930348 -1.244074)
        (xy -13.084885 -1.244074)
        (xy -13.087974 -1.269701)
        (xy -13.063381 -1.365651)
        (xy -13.008888 -1.442479)
        (xy -12.932552 -1.495976)
        (xy -12.842431 -1.521934)
        (xy -12.746584 -1.516145)
        (xy -12.653067 -1.474399)
        (xy -12.58657 -1.413748)
        (xy -12.548594 -1.36173)
        (xy -12.532631 -1.312282)
        (xy -12.533195 -1.24415)
        (xy -12.535762 -1.216935)
        (xy -12.548305 -1.095409)
        (xy -12.378536 -0.926772)
        (xy -12.208766 -0.758136)
        (xy -11.796492 -0.758136)
        (xy -11.796492 -1.315972)
        (xy -11.890413 -1.35741)
        (xy -12.000362 -1.428554)
        (xy -12.074751 -1.530309)
        (xy -12.103547 -1.608413)
        (xy -12.114691 -1.719427)
        (xy -11.953136 -1.719427)
        (xy -11.944244 -1.665249)
        (xy -11.927218 -1.625373)
        (xy -11.866718 -1.543897)
        (xy -11.786289 -1.49957)
        (xy -11.696376 -1.495069)
        (xy -11.607427 -1.533073)
        (xy -11.597127 -1.540764)
        (xy -11.527435 -1.615972)
        (xy -11.503765 -1.69764)
        (xy -11.522499 -1.783736)
        (xy -11.579788 -1.872176)
        (xy -11.655413 -1.92277)
        (xy -11.739655 -1.935681)
        (xy -11.822795 -1.911076)
        (xy -11.895117 -1.849121)
        (xy -11.937073 -1.77666)
        (xy -11.953136 -1.719427)
        (xy -12.114691 -1.719427)
        (xy -12.116284 -1.735287)
        (xy -12.089238 -1.852462)
        (xy -12.0293 -1.953869)
        (xy -11.943361 -2.033438)
        (xy -11.838308 -2.0851)
        (xy -11.721034 -2.102786)
        (xy -11.598428 -2.080424)
      )

      (stroke (width 0.00279) (type solid)) (fill solid) (layer "F.Mask"))
  )

  (footprint "kria-k26-devboard-footprints:C_0402_1005Metric" (layer "F.Cu")
    (at 84.38 71.317 90)
    (descr "Capacitor SMD 0402")
    (tags "capacitor SMD 0402")
    (property "Author" "Antmicro")
    (property "Dielectric" "X5R")
    (property "License" "Apache-2.0")
    (property "MPN" "GRM155R61H104KE14D")
    (property "Manufacturer" "Murata")
    (property "Sheetfile" "dp.kicad_sch")
    (property "Sheetname" "Display Port")
    (property "Val" "100n")
    (property "Voltage" "50V")
    (property "ki_description" " ")
    (attr smd)
    (fp_text reference "C6" (at -2.403 0.37 90) (layer "F.SilkS")
        (effects (font (size 0.7 0.7) (thickness 0.15)) (justify left bottom))
    )
    (fp_text value "C_100n_0402" (at 0 1.4 90) (layer "F.Fab") hide
        (effects (font (size 0.7 0.7) (thickness 0.15)) (justify left bottom))
    )
    (fp_text user "${REFERENCE}" (at -0.932 3.168 90) (layer "F.Fab") hide
        (effects (font (size 0.7 0.7) (thickness 0.15)) (justify left bottom))
    )
    (fp_text user "Author: Antmicro" (at -0.932 4.17 90) (layer "F.Fab") hide
        (effects (font (size 0.7 0.7) (thickness 0.15)) (justify left bottom))
    )
    (fp_text user "License: Apache-2.0" (at -0.932 5.17 90) (layer "F.Fab") hide
        (effects (font (size 0.7 0.7) (thickness 0.15)) (justify left bottom))
    )
    (fp_rect (start -0.94 -0.47) (end 0.94 0.47)
      (stroke (width 0.05) (type solid)) (fill none) (layer "F.CrtYd"))
    (fp_rect (start -0.499 -0.249) (end 0.499 0.249)
      (stroke (width 0.15) (type solid)) (fill none) (layer "F.Fab"))
    (pad "1" smd roundrect (at -0.484 0 90) (size 0.59 0.64) (layers "F.Cu" "F.Paste" "F.Mask") (roundrect_rratio 0.25)
      (net 92 "/Display Port/GTR_DP1_M2C_P") (pintype "passive"))
    (pad "2" smd roundrect (at 0.484 0 90) (size 0.59 0.64) (layers "F.Cu" "F.Paste" "F.Mask") (roundrect_rratio 0.25)
      (net 93 "/Display Port/GTR_DP1_M2C_C_P") (pintype "passive"))
  )

  (footprint "kria-k26-devboard-footprints:C_0402_1005Metric" (layer "F.Cu")
    (at 85.36 71.317 90)
    (descr "Capacitor SMD 0402")
    (tags "capacitor SMD 0402")
    (property "Author" "Antmicro")
    (property "Dielectric" "X5R")
    (property "License" "Apache-2.0")
    (property "MPN" "GRM155R61H104KE14D")
    (property "Manufacturer" "Murata")
    (property "Sheetfile" "dp.kicad_sch")
    (property "Sheetname" "Display Port")
    (property "Val" "100n")
    (property "Voltage" "50V")
    (property "ki_description" " ")
    (attr smd)
    (fp_text reference "C7" (at -2.403 0.37 90) (layer "F.SilkS")
        (effects (font (size 0.7 0.7) (thickness 0.15)) (justify left bottom))
    )
    (fp_text value "C_100n_0402" (at 0 1.4 90) (layer "F.Fab") hide
        (effects (font (size 0.7 0.7) (thickness 0.15)) (justify left bottom))
    )
    (fp_text user "Author: Antmicro" (at -0.932 4.17 90) (layer "F.Fab") hide
        (effects (font (size 0.7 0.7) (thickness 0.15)) (justify left bottom))
    )
    (fp_text user "License: Apache-2.0" (at -0.932 5.17 90) (layer "F.Fab") hide
        (effects (font (size 0.7 0.7) (thickness 0.15)) (justify left bottom))
    )
    (fp_text user "${REFERENCE}" (at -0.932 3.168 90) (layer "F.Fab") hide
        (effects (font (size 0.7 0.7) (thickness 0.15)) (justify left bottom))
    )
    (fp_rect (start -0.94 -0.47) (end 0.94 0.47)
      (stroke (width 0.05) (type solid)) (fill none) (layer "F.CrtYd"))
    (fp_rect (start -0.499 -0.249) (end 0.499 0.249)
      (stroke (width 0.15) (type solid)) (fill none) (layer "F.Fab"))
    (pad "1" smd roundrect (at -0.484 0 90) (size 0.59 0.64) (layers "F.Cu" "F.Paste" "F.Mask") (roundrect_rratio 0.25)
      (net 94 "/Display Port/GTR_DP1_M2C_N") (pintype "passive"))
    (pad "2" smd roundrect (at 0.484 0 90) (size 0.59 0.64) (layers "F.Cu" "F.Paste" "F.Mask") (roundrect_rratio 0.25)
      (net 95 "/Display Port/GTR_DP1_M2C_C_N") (pintype "passive"))
  )

  (footprint "kria-k26-devboard-footprints:D_SOD-323F" (layer "F.Cu")
    (at 95.85 68.99 -90)
    (property "Author" "Antmicro")
    (property "License" "Apache-2.0")
    (property "MPN" "PMEG3010CEJ")
    (property "Manufacturer" "Nexperia")
    (property "Sheetfile" "dp.kicad_sch")
    (property "Sheetname" "Display Port")
    (property "ki_description" "1 A very low V F MEGA Schottky barrier rectifiers")
    (property "ki_keywords" "1 A very low V F MEGA Schottky barrier rectifiers")
    (attr smd)
    (fp_text reference "D1" (at 0.79 -5.2 -90) (layer "F.SilkS")
        (effects (font (size 0.7 0.7) (thickness 0.15)) (justify left bottom))
    )
    (fp_text value "PMEG3010CE_SOD323" (at -1.7 1.9 -90) (layer "F.Fab") hide
        (effects (font (size 0.7 0.7) (thickness 0.15)) (justify left bottom))
    )
    (fp_text user "Author: Antmicro" (at -1.8 4.46 -90) (layer "F.Fab") hide
        (effects (font (size 0.7 0.7) (thickness 0.15)) (justify left bottom))
    )
    (fp_text user "${REFERENCE}" (at -1.8 3.2 -90) (layer "F.Fab") hide
        (effects (font (size 0.7 0.7) (thickness 0.15)) (justify left bottom))
    )
    (fp_text user "License: Apache-2.0" (at -1.8 5.8 -90) (layer "F.Fab") hide
        (effects (font (size 0.7 0.7) (thickness 0.15)) (justify left bottom))
    )
    (fp_line (start -0.975 -0.75) (end -0.975 -0.45)
      (stroke (width 0.15) (type solid)) (layer "F.SilkS"))
    (fp_line (start -0.975 0.748) (end -0.975 0.45)
      (stroke (width 0.15) (type solid)) (layer "F.SilkS"))
    (fp_line (start -0.625 -0.75) (end -0.975 -0.75)
      (stroke (width 0.15) (type solid)) (layer "F.SilkS"))
    (fp_line (start -0.625 0.748) (end -0.975 0.748)
      (stroke (width 0.15) (type solid)) (layer "F.SilkS"))
    (fp_line (start -0.5 -0.426) (end -0.5 0.424)
      (stroke (width 0.15) (type solid)) (layer "F.SilkS"))
    (fp_line (start 0.623 -0.75) (end 0.973 -0.75)
      (stroke (width 0.15) (type solid)) (layer "F.SilkS"))
    (fp_line (start 0.973 -0.75) (end 0.973 -0.45)
      (stroke (width 0.15) (type solid)) (layer "F.SilkS"))
    (fp_line (start 0.973 0.45) (end 0.973 0.748)
      (stroke (width 0.15) (type solid)) (layer "F.SilkS"))
    (fp_line (start 0.973 0.748) (end 0.623 0.748)
      (stroke (width 0.15) (type solid)) (layer "F.SilkS"))
    (fp_rect (start -1.6 -0.827) (end 1.599 0.825)
      (stroke (width 0.05) (type solid)) (fill none) (layer "F.CrtYd"))
    (fp_line (start -0.85 -0.625) (end 0.848 -0.625)
      (stroke (width 0.15) (type solid)) (layer "F.Fab"))
    (fp_line (start -0.85 0.623) (end -0.85 -0.625)
      (stroke (width 0.15) (type solid)) (layer "F.Fab"))
    (fp_line (start -0.85 0.623) (end 0.848 0.623)
      (stroke (width 0.15) (type solid)) (layer "F.Fab"))
    (fp_line (start 0.848 -0.625) (end 0.848 0.623)
      (stroke (width 0.15) (type solid)) (layer "F.Fab"))
    (pad "A" smd roundrect (at 1.05 0 270) (size 0.8 0.6) (layers "F.Cu" "F.Paste" "F.Mask") (roundrect_rratio 0.15)
      (net 15 "PS_3V3") (pinfunction "A") (pintype "passive"))
    (pad "K" smd roundrect (at -1.051 0 270) (size 0.8 0.6) (layers "F.Cu" "F.Paste" "F.Mask") (roundrect_rratio 0.15)
      (net 334 "Net-(J1-DP_PWR)") (pinfunction "K") (pintype "passive"))
  )

  (footprint "kria-k26-devboard-footprints:R_0402_1005Metric" (layer "F.Cu")
    (at 89.75 68.42 -90)
    (descr "Resistor SMD 0402")
    (tags "resistor SMD 0402")
    (property "Author" "Antmicro")
    (property "License" "Apache-2.0")
    (property "MPN" "CR0402-FX-1004GLF")
    (property "Manufacturer" "Bourns")
    (property "Sheetfile" "dp.kicad_sch")
    (property "Sheetname" "Display Port")
    (property "Tolerance" "1%")
    (property "Val" "1M")
    (property "ki_description" "1M resistor in 0402 package with 1% tolerance")
    (attr smd)
    (fp_text reference "R9" (at 1.05 0.56 -90) (layer "F.SilkS")
        (effects (font (size 0.7 0.7) (thickness 0.15)) (justify left bottom))
    )
    (fp_text value "R_1M_0402" (at 0 1.4 -90) (layer "F.Fab") hide
        (effects (font (size 0.7 0.7) (thickness 0.15)) (justify left bottom))
    )
    (fp_text user "License: Apache-2.0" (at -0.95 5.169 -90) (layer "F.Fab") hide
        (effects (font (size 0.7 0.7) (thickness 0.15)) (justify left bottom))
    )
    (fp_text user "${REFERENCE}" (at -0.95 3.168 -90) (layer "F.Fab") hide
        (effects (font (size 0.7 0.7) (thickness 0.15)) (justify left bottom))
    )
    (fp_text user "Author: Antmicro" (at -0.95 4.169 -90) (layer "F.Fab") hide
        (effects (font (size 0.7 0.7) (thickness 0.15)) (justify left bottom))
    )
    (fp_rect (start -0.93 -0.47) (end 0.93 0.47)
      (stroke (width 0.05) (type solid)) (fill none) (layer "F.CrtYd"))
    (fp_rect (start -0.5 -0.25) (end 0.5 0.25)
      (stroke (width 0.15) (type solid)) (fill none) (layer "F.Fab"))
    (pad "1" smd roundrect (at -0.485 0 270) (size 0.59 0.64) (layers "F.Cu" "F.Paste" "F.Mask") (roundrect_rratio 0.25)
      (net 348 "Net-(J1-CFG1)") (pintype "passive"))
    (pad "2" smd roundrect (at 0.485 0 270) (size 0.59 0.64) (layers "F.Cu" "F.Paste" "F.Mask") (roundrect_rratio 0.25)
      (net 1 "GND") (pintype "passive"))
  )

  (footprint "kria-k26-devboard-footprints:R_0402_1005Metric" (layer "F.Cu")
    (at 94.4 68.41 -90)
    (descr "Resistor SMD 0402")
    (tags "resistor SMD 0402")
    (property "Author" "Antmicro")
    (property "Current" "1A")
    (property "License" "Apache-2.0")
    (property "MPN" "ERJ2GE0R00X")
    (property "Manufacturer" "Panasonic")
    (property "Sheetfile" "dp.kicad_sch")
    (property "Sheetname" "Display Port")
    (property "Tolerance" "")
    (property "Val" "0R")
    (property "ki_description" "0R resistor in 0402 package with unspecified tolerance")
    (attr smd)
    (fp_text reference "R10" (at 1.13 -5.29 -90) (layer "F.SilkS")
        (effects (font (size 0.7 0.7) (thickness 0.15)) (justify left bottom))
    )
    (fp_text value "R_0R_0402" (at 0 1.4 -90) (layer "F.Fab") hide
        (effects (font (size 0.7 0.7) (thickness 0.15)) (justify left bottom))
    )
    (fp_text user "Author: Antmicro" (at -0.95 4.169 -90) (layer "F.Fab") hide
        (effects (font (size 0.7 0.7) (thickness 0.15)) (justify left bottom))
    )
    (fp_text user "${REFERENCE}" (at -0.95 3.168 -90) (layer "F.Fab") hide
        (effects (font (size 0.7 0.7) (thickness 0.15)) (justify left bottom))
    )
    (fp_text user "License: Apache-2.0" (at -0.95 5.169 -90) (layer "F.Fab") hide
        (effects (font (size 0.7 0.7) (thickness 0.15)) (justify left bottom))
    )
    (fp_rect (start -0.93 -0.47) (end 0.93 0.47)
      (stroke (width 0.05) (type solid)) (fill none) (layer "F.CrtYd"))
    (fp_rect (start -0.5 -0.25) (end 0.5 0.25)
      (stroke (width 0.15) (type solid)) (fill none) (layer "F.Fab"))
    (pad "1" smd roundrect (at -0.485 0 270) (size 0.59 0.64) (layers "F.Cu" "F.Paste" "F.Mask") (roundrect_rratio 0.25)
      (net 804 "Net-(J1-RTN)") (pintype "passive"))
    (pad "2" smd roundrect (at 0.485 0 270) (size 0.59 0.64) (layers "F.Cu" "F.Paste" "F.Mask") (roundrect_rratio 0.25)
      (net 1 "GND") (pintype "passive"))
  )

  (footprint "kria-k26-devboard-footprints:R_0402_1005Metric" (layer "F.Cu")
    (at 93.43 68.39 -90)
    (descr "Resistor SMD 0402")
    (tags "resistor SMD 0402")
    (property "Author" "Antmicro")
    (property "License" "Apache-2.0")
    (property "MPN" "CR0402-FX-1003GLF")
    (property "Manufacturer" "Bourns")
    (property "Sheetfile" "dp.kicad_sch")
    (property "Sheetname" "Display Port")
    (property "Tolerance" "1%")
    (property "Val" "100k")
    (property "ki_description" "100k resistor in 0402 package with 1% tolerance")
    (attr smd)
    (fp_text reference "R11" (at 1.13 -5.29 -90) (layer "F.SilkS")
        (effects (font (size 0.7 0.7) (thickness 0.15)) (justify left bottom))
    )
    (fp_text value "R_100k_0402" (at 0 1.4 -90) (layer "F.Fab") hide
        (effects (font (size 0.7 0.7) (thickness 0.15)) (justify left bottom))
    )
    (fp_text user "Author: Antmicro" (at -0.95 4.169 -90) (layer "F.Fab") hide
        (effects (font (size 0.7 0.7) (thickness 0.15)) (justify left bottom))
    )
    (fp_text user "License: Apache-2.0" (at -0.95 5.169 -90) (layer "F.Fab") hide
        (effects (font (size 0.7 0.7) (thickness 0.15)) (justify left bottom))
    )
    (fp_text user "${REFERENCE}" (at -0.95 3.168 -90) (layer "F.Fab") hide
        (effects (font (size 0.7 0.7) (thickness 0.15)) (justify left bottom))
    )
    (fp_rect (start -0.93 -0.47) (end 0.93 0.47)
      (stroke (width 0.05) (type solid)) (fill none) (layer "F.CrtYd"))
    (fp_rect (start -0.5 -0.25) (end 0.5 0.25)
      (stroke (width 0.15) (type solid)) (fill none) (layer "F.Fab"))
    (pad "1" smd roundrect (at -0.485 0 270) (size 0.59 0.64) (layers "F.Cu" "F.Paste" "F.Mask") (roundrect_rratio 0.25)
      (net 105 "/Display Port/DP_HPD") (pintype "passive"))
    (pad "2" smd roundrect (at 0.485 0 270) (size 0.59 0.64) (layers "F.Cu" "F.Paste" "F.Mask") (roundrect_rratio 0.25)
      (net 1 "GND") (pintype "passive"))
  )

  (footprint "kria-k26-devboard-footprints:R_0402_1005Metric" (layer "F.Cu")
    (at 90.72 68.42 90)
    (descr "Resistor SMD 0402")
    (tags "resistor SMD 0402")
    (property "Author" "Antmicro")
    (property "License" "Apache-2.0")
    (property "MPN" "CR0402-FX-1004GLF")
    (property "Manufacturer" "Bourns")
    (property "Sheetfile" "dp.kicad_sch")
    (property "Sheetname" "Display Port")
    (property "Tolerance" "1%")
    (property "Val" "1M")
    (property "ki_description" "1M resistor in 0402 package with 1% tolerance")
    (attr smd)
    (fp_text reference "R12" (at -1.05 -2.41 90) (layer "F.SilkS")
        (effects (font (size 0.7 0.7) (thickness 0.15)) (justify left bottom))
    )
    (fp_text value "R_1M_0402" (at 0 1.4 90) (layer "F.Fab") hide
        (effects (font (size 0.7 0.7) (thickness 0.15)) (justify left bottom))
    )
    (fp_text user "License: Apache-2.0" (at -0.95 5.169 90) (layer "F.Fab") hide
        (effects (font (size 0.7 0.7) (thickness 0.15)) (justify left bottom))
    )
    (fp_text user "${REFERENCE}" (at -0.95 3.168 90) (layer "F.Fab") hide
        (effects (font (size 0.7 0.7) (thickness 0.15)) (justify left bottom))
    )
    (fp_text user "Author: Antmicro" (at -0.95 4.169 90) (layer "F.Fab") hide
        (effects (font (size 0.7 0.7) (thickness 0.15)) (justify left bottom))
    )
    (fp_rect (start -0.93 -0.47) (end 0.93 0.47)
      (stroke (width 0.05) (type solid)) (fill none) (layer "F.CrtYd"))
    (fp_rect (start -0.5 -0.25) (end 0.5 0.25)
      (stroke (width 0.15) (type solid)) (fill none) (layer "F.Fab"))
    (pad "1" smd roundrect (at -0.485 0 90) (size 0.59 0.64) (layers "F.Cu" "F.Paste" "F.Mask") (roundrect_rratio 0.25)
      (net 1 "GND") (pintype "passive"))
    (pad "2" smd roundrect (at 0.485 0 90) (size 0.59 0.64) (layers "F.Cu" "F.Paste" "F.Mask") (roundrect_rratio 0.25)
      (net 349 "Net-(J1-CFG2)") (pintype "passive"))
  )

  (footprint "kria-k26-devboard-footprints:USB-A_Receptacle_Amphenol_GSB3112311HR" (layer "F.Cu")
    (at 113.9 65.73 180)
    (descr "Ethernet Amphenol")
    (tags "Ethernet Amphenol")
    (property "Author" "Antmicro")
    (property "License" "Apache-2.0")
    (property "MPN" "GSB3112311HR")
    (property "Manufacturer" "Amphenol")
    (property "Sheetfile" "usb.kicad_sch")
    (property "Sheetname" "USB")
    (property "ki_description" "USB-A (USB TYPE-A) USB 3.2 Gen 1 (USB 3.1 Gen 1, Superspeed (USB 3.0)) Receptacle Connector 5 Position Through Hole, Right Angle")
    (property "ki_keywords" "USB, CONNECTOR, THT, HORIZONTAL")
    (attr through_hole)
    (fp_text reference "U29" (at 7.86 -6.95) (layer "F.SilkS")
        (effects (font (size 0.7 0.7) (thickness 0.15)) (justify right bottom))
    )
    (fp_text value "USB-A_Amphenol_GSB3112311HR" (at 0 14.8) (layer "F.Fab") hide
        (effects (font (size 0.7 0.7) (thickness 0.15)) (justify right bottom))
    )
    (fp_text user "${REFERENCE}" (at -4.6 16.3) (layer "F.Fab") hide
        (effects (font (size 0.7 0.7) (thickness 0.15)) (justify right bottom))
    )
    (fp_text user "License: Apache-2.0" (at -4.6 18.7) (layer "F.Fab") hide
        (effects (font (size 0.7 0.7) (thickness 0.15)) (justify right bottom))
    )
    (fp_text user "Author: Antmicro" (at -4.6 17.501) (layer "F.Fab") hide
        (effects (font (size 0.7 0.7) (thickness 0.15)) (justify right bottom))
    )
    (fp_rect (start -4.6 13.711) (end 11.7 -6.6)
      (stroke (width 0.05) (type solid)) (fill none) (layer "F.CrtYd"))
    (pad "1" thru_hole circle (at 0 0 270) (size 1.1 1.1) (drill 0.7) (layers "*.Cu" "*.Mask")
      (net 86 "/USB/USB3_VBUS") (pinfunction "VBUS") (pintype "passive"))
    (pad "2" thru_hole circle (at 2.499 0 270) (size 1.1 1.1) (drill 0.7) (layers "*.Cu" "*.Mask")
      (net 290 "/USB/USB3_TVS_N") (pinfunction "D-") (pintype "bidirectional"))
    (pad "3" thru_hole circle (at 4.498 0 270) (size 1.1 1.1) (drill 0.7) (layers "*.Cu" "*.Mask")
      (net 291 "/USB/USB3_TVS_P") (pinfunction "D+") (pintype "bidirectional"))
    (pad "4" thru_hole circle (at 6.999 0 270) (size 1.1 1.1) (drill 0.7) (layers "*.Cu" "*.Mask")
      (net 1 "GND") (pinfunction "GND") (pintype "power_in"))
    (pad "5" thru_hole circle (at 7.499 -1.499 270) (size 1.1 1.1) (drill 0.7) (layers "*.Cu" "*.Mask")
      (net 79 "/USB/USB3_RX_N") (pinfunction "SSRX-") (pintype "bidirectional"))
    (pad "6" thru_hole circle (at 5.499 -1.499 270) (size 1.1 1.1) (drill 0.7) (layers "*.Cu" "*.Mask")
      (net 80 "/USB/USB3_RX_P") (pinfunction "SSRX+") (pintype "bidirectional"))
    (pad "7" thru_hole circle (at 3.499 -1.499 270) (size 1.1 1.1) (drill 0.7) (layers "*.Cu" "*.Mask")
      (net 1 "GND") (pinfunction "GND_DRAIN") (pintype "power_in"))
    (pad "8" thru_hole circle (at 1.499 -1.499 270) (size 1.1 1.1) (drill 0.7) (layers "*.Cu" "*.Mask")
      (net 282 "/USB/USB3_TX_C_N") (pinfunction "SSTX-") (pintype "bidirectional"))
    (pad "9" thru_hole circle (at -0.5 -1.499 270) (size 1.1 1.1) (drill 0.7) (layers "*.Cu" "*.Mask")
      (net 283 "/USB/USB3_TX_C_P") (pinfunction "SSTX+") (pintype "bidirectional"))
    (pad "10" thru_hole circle (at 0 -3.2 270) (size 1.1 1.1) (drill 0.7) (layers "*.Cu" "*.Mask")
      (net 87 "/USB/USB4_VBUS") (pinfunction "VBUS") (pintype "power_in"))
    (pad "11" thru_hole circle (at 2.499 -3.2 270) (size 1.1 1.1) (drill 0.7) (layers "*.Cu" "*.Mask")
      (net 292 "/USB/USB4_TVS_N") (pinfunction "D-") (pintype "bidirectional"))
    (pad "12" thru_hole circle (at 4.498 -3.2 270) (size 1.1 1.1) (drill 0.7) (layers "*.Cu" "*.Mask")
      (net 293 "/USB/USB4_TVS_P") (pinfunction "D+") (pintype "bidirectional"))
    (pad "13" thru_hole circle (at 6.999 -3.2 270) (size 1.1 1.1) (drill 0.7) (layers "*.Cu" "*.Mask")
      (net 1 "GND") (pinfunction "GND") (pintype "power_in"))
    (pad "14" thru_hole circle (at 7.499 -4.7 270) (size 1.1 1.1) (drill 0.7) (layers "*.Cu" "*.Mask")
      (net 73 "/USB/USB4_RX_N") (pinfunction "SSRX-") (pintype "bidirectional"))
    (pad "15" thru_hole circle (at 5.499 -4.7 270) (size 1.1 1.1) (drill 0.7) (layers "*.Cu" "*.Mask")
      (net 74 "/USB/USB4_RX_P") (pinfunction "SSRX+") (pintype "bidirectional"))
    (pad "16" thru_hole circle (at 3.499 -4.7 270) (size 1.1 1.1) (drill 0.7) (layers "*.Cu" "*.Mask")
      (net 1 "GND") (pinfunction "GND_DRAIN") (pintype "power_in"))
    (pad "17" thru_hole circle (at 1.499 -4.7 270) (size 1.1 1.1) (drill 0.7) (layers "*.Cu" "*.Mask")
      (net 284 "/USB/USB4_TX_C_N") (pinfunction "SSTX-") (pintype "bidirectional"))
    (pad "18" thru_hole circle (at -0.5 -4.7 270) (size 1.1 1.1) (drill 0.7) (layers "*.Cu" "*.Mask")
      (net 285 "/USB/USB4_TX_C_P") (pinfunction "SSTX+") (pintype "bidirectional"))
    (pad "SH" thru_hole circle (at -3.072 -3.68 270) (size 2.9 2.9) (drill 2.3) (layers "*.Cu" "*.Mask")
      (net 319 "SH_UP") (pinfunction "SHIELD") (pintype "passive"))
    (pad "SH" thru_hole circle (at -3.072 2 270) (size 2.9 2.9) (drill 2.3) (layers "*.Cu" "*.Mask")
      (net 319 "SH_UP") (pinfunction "SHIELD") (pintype "passive"))
    (pad "SH" thru_hole circle (at 10.07 -3.68 270) (size 2.9 2.9) (drill 2.3) (layers "*.Cu" "*.Mask")
      (net 319 "SH_UP") (pinfunction "SHIELD") (pintype "passive"))
    (pad "SH" thru_hole circle (at 10.169 2 270) (size 2.9 2.9) (drill 2.3) (layers "*.Cu" "*.Mask")
      (net 319 "SH_UP") (pinfunction "SHIELD") (pintype "passive"))
  )

  (footprint "kria-k26-devboard-footprints:C_1206_3216Metric" (layer "F.Cu")
    (at 187.385 116.45)
    (descr "Capacitor SMD 1206")
    (tags "capacitor SMD 1206")
    (property "Author" "Antmicro")
    (property "Dielectric" "")
    (property "License" "Apache-2.0")
    (property "MPN" "C3216X5R1C476M160AB")
    (property "Manufacturer" "TDK")
    (property "Sheetfile" "PoE.kicad_sch")
    (property "Sheetname" "PoE")
    (property "Val" "47u/16V")
    (property "Voltage" "")
    (property "ki_description" " ")
    (attr smd)
    (fp_text reference "C180" (at 0.915 -1.93) (layer "F.SilkS")
        (effects (font (size 0.7 0.7) (thickness 0.15)) (justify left bottom))
    )
    (fp_text value "C_47u_16V_1206" (at 0 2.1) (layer "F.Fab") hide
        (effects (font (size 0.7 0.7) (thickness 0.15)) (justify left bottom))
    )
    (fp_text user "License: Apache-2.0" (at -2.8 6.6) (layer "F.Fab") hide
        (effects (font (size 0.7 0.7) (thickness 0.15)) (justify left bottom))
    )
    (fp_text user "${REFERENCE}" (at -2.8 4.6) (layer "F.Fab") hide
        (effects (font (size 0.7 0.7) (thickness 0.15)) (justify left bottom))
    )
    (fp_text user "Author: Antmicro" (at -2.8 5.6) (layer "F.Fab") hide
        (effects (font (size 0.7 0.7) (thickness 0.15)) (justify left bottom))
    )
    (fp_line (start -2.625 -0.3) (end -2.625 0.3)
      (stroke (width 0.15) (type solid)) (layer "F.SilkS"))
    (fp_line (start 0.5 -0.9) (end -0.5 -0.9)
      (stroke (width 0.15) (type solid)) (layer "F.SilkS"))
    (fp_line (start 0.5 0.9) (end -0.5 0.9)
      (stroke (width 0.15) (type solid)) (layer "F.SilkS"))
    (fp_line (start 2.625 -0.3) (end 2.625 0.3)
      (stroke (width 0.15) (type solid)) (layer "F.SilkS"))
    (fp_rect (start -2.8 -1.15) (end 2.8 1.15)
      (stroke (width 0.05) (type solid)) (fill none) (layer "F.CrtYd"))
    (fp_rect (start -1.6 -0.8) (end 1.6 0.8)
      (stroke (width 0.15) (type solid)) (fill none) (layer "F.Fab"))
    (pad "1" smd rect (at -1.8 0) (size 1.5 1.8) (layers "F.Cu" "F.Paste" "F.Mask")
      (net 13 "/Power Supply/PoE/POE_12V") (pintype "passive"))
    (pad "2" smd rect (at 1.8 0) (size 1.5 1.8) (layers "F.Cu" "F.Paste" "F.Mask")
      (net 1 "GND") (pintype "passive"))
  )

  (footprint "kria-k26-devboard-footprints:R_0402_1005Metric" (layer "F.Cu")
    (at 177.625 130.6)
    (descr "Resistor SMD 0402")
    (tags "resistor SMD 0402")
    (property "Author" "Antmicro")
    (property "License" "Apache-2.0")
    (property "MPN" "CR0402-FX-1002GLF")
    (property "Manufacturer" "Bourns")
    (property "Sheetfile" "dc-dc-conventers.kicad_sch")
    (property "Sheetname" "DC/DC conventers")
    (property "Tolerance" "1%")
    (property "Val" "10k")
    (property "ki_description" "10k resistor in 0402 package with 1% tolerance")
    (attr smd)
    (fp_text reference "R145" (at -0.085 -0.43) (layer "F.SilkS")
        (effects (font (size 0.7 0.7) (thickness 0.15)) (justify left bottom))
    )
    (fp_text value "R_10k_0402" (at 0 1.4) (layer "F.Fab") hide
        (effects (font (size 0.7 0.7) (thickness 0.15)) (justify left bottom))
    )
    (fp_text user "License: Apache-2.0" (at -0.95 5.169) (layer "F.Fab") hide
        (effects (font (size 0.7 0.7) (thickness 0.15)) (justify left bottom))
    )
    (fp_text user "Author: Antmicro" (at -0.95 4.169) (layer "F.Fab") hide
        (effects (font (size 0.7 0.7) (thickness 0.15)) (justify left bottom))
    )
    (fp_text user "${REFERENCE}" (at -0.95 3.168) (layer "F.Fab") hide
        (effects (font (size 0.7 0.7) (thickness 0.15)) (justify left bottom))
    )
    (fp_rect (start -0.93 -0.47) (end 0.93 0.47)
      (stroke (width 0.05) (type solid)) (fill none) (layer "F.CrtYd"))
    (fp_rect (start -0.5 -0.25) (end 0.5 0.25)
      (stroke (width 0.15) (type solid)) (fill none) (layer "F.Fab"))
    (pad "1" smd roundrect (at -0.485 0) (size 0.59 0.64) (layers "F.Cu" "F.Paste" "F.Mask") (roundrect_rratio 0.25)
      (net 693 "Net-(U54-FB)") (pintype "passive"))
    (pad "2" smd roundrect (at 0.485 0) (size 0.59 0.64) (layers "F.Cu" "F.Paste" "F.Mask") (roundrect_rratio 0.25)
      (net 1 "GND") (pintype "passive"))
  )

  (footprint "kria-k26-devboard-footprints:C_0603_1608Metric" (layer "F.Cu")
    (at 182.28 135.925 -90)
    (descr "Capacitor SMD 0603")
    (tags "capacitor 0603")
    (property "Author" "Antmicro")
    (property "Dielectric" "")
    (property "License" "Apache-2.0")
    (property "MPN" "GRM188R60J226MEA0D")
    (property "Manufacturer" "Murata")
    (property "Sheetfile" "dc-dc-conventers.kicad_sch")
    (property "Sheetname" "DC/DC conventers")
    (property "Val" "22u")
    (property "Voltage" "")
    (property "ki_description" " ")
    (attr smd)
    (fp_text reference "C225" (at -1.165 -0.88 -90) (layer "F.SilkS")
        (effects (font (size 0.7 0.7) (thickness 0.15)) (justify left bottom))
    )
    (fp_text value "C_22u_0603" (at 0 1.6 -90) (layer "F.Fab") hide
        (effects (font (size 0.7 0.7) (thickness 0.15)) (justify left bottom))
    )
    (fp_text user "Author: Antmicro" (at -1.682 4.894 -90) (layer "F.Fab") hide
        (effects (font (size 0.7 0.7) (thickness 0.15)) (justify left bottom))
    )
    (fp_text user "${REFERENCE}" (at -1.682 3.895 -90) (layer "F.Fab") hide
        (effects (font (size 0.7 0.7) (thickness 0.15)) (justify left bottom))
    )
    (fp_text user "License: Apache-2.0" (at -1.682 5.895 -90) (layer "F.Fab") hide
        (effects (font (size 0.7 0.7) (thickness 0.15)) (justify left bottom))
    )
    (fp_line (start -0.3 -0.3) (end 0.3 -0.3)
      (stroke (width 0.15) (type solid)) (layer "F.SilkS"))
    (fp_line (start -0.3 0.3) (end 0.3 0.3)
      (stroke (width 0.15) (type solid)) (layer "F.SilkS"))
    (fp_rect (start -1.24 -0.7) (end 1.24 0.7)
      (stroke (width 0.05) (type solid)) (fill none) (layer "F.CrtYd"))
    (fp_rect (start -0.8 -0.4) (end 0.8 0.4)
      (stroke (width 0.15) (type solid)) (fill none) (layer "F.Fab"))
    (pad "1" smd roundrect (at -0.7 0 270) (size 0.6 0.8) (layers "F.Cu" "F.Paste" "F.Mask") (roundrect_rratio 0.2)
      (net 1 "GND") (pintype "passive"))
    (pad "2" smd roundrect (at 0.7 0 270) (size 0.6 0.8) (layers "F.Cu" "F.Paste" "F.Mask") (roundrect_rratio 0.2)
      (net 770 "/Power Supply/DC/DC conventers/PL_3V3_OUT") (pintype "passive"))
  )

  (footprint "kria-k26-devboard-footprints:C_1206_3216Metric" (layer "F.Cu")
    (at 187.399999 118.8)
    (descr "Capacitor SMD 1206")
    (tags "capacitor SMD 1206")
    (property "Author" "Antmicro")
    (property "Dielectric" "")
    (property "License" "Apache-2.0")
    (property "MPN" "C3216X5R1C476M160AB")
    (property "Manufacturer" "TDK")
    (property "Sheetfile" "PoE.kicad_sch")
    (property "Sheetname" "PoE")
    (property "Val" "47u/16V")
    (property "Voltage" "")
    (property "ki_description" " ")
    (attr smd)
    (fp_text reference "C181" (at 0.910001 -3.4) (layer "F.SilkS")
        (effects (font (size 0.7 0.7) (thickness 0.15)) (justify left bottom))
    )
    (fp_text value "C_47u_16V_1206" (at 0 2.1) (layer "F.Fab") hide
        (effects (font (size 0.7 0.7) (thickness 0.15)) (justify left bottom))
    )
    (fp_text user "${REFERENCE}" (at -2.8 4.6) (layer "F.Fab") hide
        (effects (font (size 0.7 0.7) (thickness 0.15)) (justify left bottom))
    )
    (fp_text user "License: Apache-2.0" (at -2.8 6.6) (layer "F.Fab") hide
        (effects (font (size 0.7 0.7) (thickness 0.15)) (justify left bottom))
    )
    (fp_text user "Author: Antmicro" (at -2.8 5.6) (layer "F.Fab") hide
        (effects (font (size 0.7 0.7) (thickness 0.15)) (justify left bottom))
    )
    (fp_line (start -2.625 -0.3) (end -2.625 0.3)
      (stroke (width 0.15) (type solid)) (layer "F.SilkS"))
    (fp_line (start 0.5 -0.9) (end -0.5 -0.9)
      (stroke (width 0.15) (type solid)) (layer "F.SilkS"))
    (fp_line (start 0.5 0.9) (end -0.5 0.9)
      (stroke (width 0.15) (type solid)) (layer "F.SilkS"))
    (fp_line (start 2.625 -0.3) (end 2.625 0.3)
      (stroke (width 0.15) (type solid)) (layer "F.SilkS"))
    (fp_rect (start -2.8 -1.15) (end 2.8 1.15)
      (stroke (width 0.05) (type solid)) (fill none) (layer "F.CrtYd"))
    (fp_rect (start -1.6 -0.8) (end 1.6 0.8)
      (stroke (width 0.15) (type solid)) (fill none) (layer "F.Fab"))
    (pad "1" smd rect (at -1.8 0) (size 1.5 1.8) (layers "F.Cu" "F.Paste" "F.Mask")
      (net 13 "/Power Supply/PoE/POE_12V") (pintype "passive"))
    (pad "2" smd rect (at 1.8 0) (size 1.5 1.8) (layers "F.Cu" "F.Paste" "F.Mask")
      (net 1 "GND") (pintype "passive"))
  )

  (footprint "kria-k26-devboard-footprints:C_0603_1608Metric" (layer "F.Cu")
    (at 180.86 135.92 -90)
    (descr "Capacitor SMD 0603")
    (tags "capacitor 0603")
    (property "Author" "Antmicro")
    (property "Dielectric" "")
    (property "License" "Apache-2.0")
    (property "MPN" "GRM188R60J226MEA0D")
    (property "Manufacturer" "Murata")
    (property "Sheetfile" "dc-dc-conventers.kicad_sch")
    (property "Sheetname" "DC/DC conventers")
    (property "Val" "22u")
    (property "Voltage" "")
    (property "ki_description" " ")
    (attr smd)
    (fp_text reference "C223" (at -1.175 -1.24 -90) (layer "F.SilkS")
        (effects (font (size 0.7 0.7) (thickness 0.15)) (justify left bottom))
    )
    (fp_text value "C_22u_0603" (at 0 1.6 -90) (layer "F.Fab") hide
        (effects (font (size 0.7 0.7) (thickness 0.15)) (justify left bottom))
    )
    (fp_text user "Author: Antmicro" (at -1.682 4.894 -90) (layer "F.Fab") hide
        (effects (font (size 0.7 0.7) (thickness 0.15)) (justify left bottom))
    )
    (fp_text user "License: Apache-2.0" (at -1.682 5.895 -90) (layer "F.Fab") hide
        (effects (font (size 0.7 0.7) (thickness 0.15)) (justify left bottom))
    )
    (fp_text user "${REFERENCE}" (at -1.682 3.895 -90) (layer "F.Fab") hide
        (effects (font (size 0.7 0.7) (thickness 0.15)) (justify left bottom))
    )
    (fp_line (start -0.3 -0.3) (end 0.3 -0.3)
      (stroke (width 0.15) (type solid)) (layer "F.SilkS"))
    (fp_line (start -0.3 0.3) (end 0.3 0.3)
      (stroke (width 0.15) (type solid)) (layer "F.SilkS"))
    (fp_rect (start -1.24 -0.7) (end 1.24 0.7)
      (stroke (width 0.05) (type solid)) (fill none) (layer "F.CrtYd"))
    (fp_rect (start -0.8 -0.4) (end 0.8 0.4)
      (stroke (width 0.15) (type solid)) (fill none) (layer "F.Fab"))
    (pad "1" smd roundrect (at -0.7 0 270) (size 0.6 0.8) (layers "F.Cu" "F.Paste" "F.Mask") (roundrect_rratio 0.2)
      (net 1 "GND") (pintype "passive"))
    (pad "2" smd roundrect (at 0.7 0 270) (size 0.6 0.8) (layers "F.Cu" "F.Paste" "F.Mask") (roundrect_rratio 0.2)
      (net 770 "/Power Supply/DC/DC conventers/PL_3V3_OUT") (pintype "passive"))
  )

  (footprint "kria-k26-devboard-footprints:C_0603_1608Metric" (layer "F.Cu")
    (at 180.775 133.175 -90)
    (descr "Capacitor SMD 0603")
    (tags "capacitor 0603")
    (property "Author" "Antmicro")
    (property "Dielectric" "")
    (property "License" "Apache-2.0")
    (property "MPN" "C1608X5R1E106M080AC")
    (property "Manufacturer" "TDK")
    (property "Sheetfile" "dc-dc-conventers.kicad_sch")
    (property "Sheetname" "DC/DC conventers")
    (property "Val" "10u/25V")
    (property "Voltage" "")
    (property "ki_description" " ")
    (attr smd)
    (fp_text reference "C219" (at -1.025 -0.625 -90) (layer "F.SilkS")
        (effects (font (size 0.7 0.7) (thickness 0.15)) (justify left bottom))
    )
    (fp_text value "C_10u_25V_0603" (at 0 1.6 -90) (layer "F.Fab") hide
        (effects (font (size 0.7 0.7) (thickness 0.15)) (justify left bottom))
    )
    (fp_text user "License: Apache-2.0" (at -1.682 5.895 -90) (layer "F.Fab") hide
        (effects (font (size 0.7 0.7) (thickness 0.15)) (justify left bottom))
    )
    (fp_text user "${REFERENCE}" (at -1.682 3.895 -90) (layer "F.Fab") hide
        (effects (font (size 0.7 0.7) (thickness 0.15)) (justify left bottom))
    )
    (fp_text user "Author: Antmicro" (at -1.682 4.894 -90) (layer "F.Fab") hide
        (effects (font (size 0.7 0.7) (thickness 0.15)) (justify left bottom))
    )
    (fp_line (start -0.3 -0.3) (end 0.3 -0.3)
      (stroke (width 0.15) (type solid)) (layer "F.SilkS"))
    (fp_line (start -0.3 0.3) (end 0.3 0.3)
      (stroke (width 0.15) (type solid)) (layer "F.SilkS"))
    (fp_rect (start -1.24 -0.7) (end 1.24 0.7)
      (stroke (width 0.05) (type solid)) (fill none) (layer "F.CrtYd"))
    (fp_rect (start -0.8 -0.4) (end 0.8 0.4)
      (stroke (width 0.15) (type solid)) (fill none) (layer "F.Fab"))
    (pad "1" smd roundrect (at -0.7 0 270) (size 0.6 0.8) (layers "F.Cu" "F.Paste" "F.Mask") (roundrect_rratio 0.2)
      (net 14 "/Power Supply/DC/DC conventers/DC_MAIN_BUS") (pintype "passive"))
    (pad "2" smd roundrect (at 0.7 0 270) (size 0.6 0.8) (layers "F.Cu" "F.Paste" "F.Mask") (roundrect_rratio 0.2)
      (net 1 "GND") (pintype "passive"))
  )

  (footprint "kria-k26-devboard-footprints:L_0806_2016Metric" (layer "F.Cu")
    (at 178.39 136.01)
    (property "Author" "Antmicro")
    (property "IMax" "")
    (property "ISat" "")
    (property "License" "Apache-2.0")
    (property "MPN" "SRP2010-1R0M")
    (property "Manufacturer" "Bourns")
    (property "Sheetfile" "dc-dc-conventers.kicad_sch")
    (property "Sheetname" "DC/DC conventers")
    (property "Size" "2.0x1.6")
    (property "Val" "1u/2.6A")
    (attr smd)
    (fp_text reference "L8" (at 0.63 -4.78 180) (layer "F.SilkS")
        (effects (font (size 0.7 0.7) (thickness 0.15)) (justify left bottom))
    )
    (fp_text value "L_1u_2.6A_0806" (at 0 2) (layer "F.Fab") hide
        (effects (font (size 0.7 0.7) (thickness 0.15)) (justify left bottom))
    )
    (fp_text user "Author: Antmicro" (at -1.9 4.4) (layer "F.Fab") hide
        (effects (font (size 0.7 0.7) (thickness 0.15)) (justify left bottom))
    )
    (fp_text user "${REFERENCE}" (at -1.9 3.1) (layer "F.Fab") hide
        (effects (font (size 0.7 0.7) (thickness 0.15)) (justify left bottom))
    )
    (fp_text user "License: Apache-2.0" (at -1.9 5.75) (layer "F.Fab") hide
        (effects (font (size 0.7 0.7) (thickness 0.15)) (justify left bottom))
    )
    (fp_line (start -0.301 0.9) (end 0.299 0.9)
      (stroke (width 0.15) (type solid)) (layer "F.SilkS"))
    (fp_line (start -0.3 -0.9) (end 0.298 -0.9)
      (stroke (width 0.15) (type solid)) (layer "F.SilkS"))
    (fp_rect (start -1.75 -1.05) (end 1.75 1.05)
      (stroke (width 0.05) (type solid)) (fill none) (layer "F.CrtYd"))
    (fp_rect (start -0.951 -0.882) (end 0.949 0.875)
      (stroke (width 0.15) (type solid)) (fill none) (layer "F.Fab"))
    (pad "1" smd roundrect (at -1.1 -0.001) (size 1 1.8) (layers "F.Cu" "F.Paste" "F.Mask") (roundrect_rratio 0.15)
      (net 315 "/Power Supply/DC/DC conventers/SW_PL_3V3") (pintype "passive"))
    (pad "2" smd roundrect (at 1.1 -0.001) (size 1 1.8) (layers "F.Cu" "F.Paste" "F.Mask") (roundrect_rratio 0.15)
      (net 770 "/Power Supply/DC/DC conventers/PL_3V3_OUT") (pintype "passive"))
  )

  (footprint "kria-k26-devboard-footprints:PinHeader_2x7_P2mm_Drill1mm_Shrouded" (layer "F.Cu")
    (at 76.8 130.975 90)
    (property "Author" "Antmicro")
    (property "License" "Apache-2.0")
    (property "MPN" "0878311420")
    (property "Manufacturer" "Molex")
    (property "Sheetfile" "debug.kicad_sch")
    (property "Sheetname" "Debug and JTAG")
    (property "ki_description" "Pin Header, Wire-to-Board, 2 mm, 2 Rows, 14 Contacts, Surface Mount Straight, Milli-Grid 87832")
    (property "ki_keywords" "PINSTRIP, HEADER ")
    (attr through_hole)
    (fp_text reference "J9" (at -14.525 5.26 90) (layer "F.SilkS")
        (effects (font (size 0.7 0.7) (thickness 0.15)) (justify left bottom))
    )
    (fp_text value "PinHeader_2x7_P2mm_Drill1mm_Shrouded" (at -14.7 5.4 90) (layer "F.Fab") hide
        (effects (font (size 0.7 0.7) (thickness 0.15)) (justify left bottom))
    )
    (fp_text user "License: Apache-2.0" (at -14.7 7.9 90) (layer "F.Fab")
        (effects (font (size 0.7 0.7) (thickness 0.15)) (justify left bottom))
    )
    (fp_text user "${REFERENCE}" (at -14.7 6.7 90) (layer "F.Fab")
        (effects (font (size 0.7 0.7) (thickness 0.15)) (justify left bottom))
    )
    (fp_text user "Author: Antmicro" (at -14.7 9.2 90) (layer "F.Fab")
        (effects (font (size 0.7 0.7) (thickness 0.15)) (justify left bottom))
    )
    (fp_line (start -14.41 -2.24) (end -14.41 -1.74)
      (stroke (width 0.15) (type solid)) (layer "F.SilkS"))
    (fp_line (start -14.41 -2.24) (end -13.91 -2.24)
      (stroke (width 0.15) (type solid)) (layer "F.SilkS"))
    (fp_line (start -14.41 4.24) (end -14.41 3.74)
      (stroke (width 0.15) (type solid)) (layer "F.SilkS"))
    (fp_line (start -14.41 4.24) (end -13.91 4.24)
      (stroke (width 0.15) (type solid)) (layer "F.SilkS"))
    (fp_line (start 2.41 -2.24) (end 1.91 -2.24)
      (stroke (width 0.15) (type solid)) (layer "F.SilkS"))
    (fp_line (start 2.41 -2.24) (end 2.41 -1.74)
      (stroke (width 0.15) (type solid)) (layer "F.SilkS"))
    (fp_line (start 2.41 4.24) (end 1.91 4.24)
      (stroke (width 0.15) (type solid)) (layer "F.SilkS"))
    (fp_line (start 2.41 4.24) (end 2.41 3.74)
      (stroke (width 0.15) (type solid)) (layer "F.SilkS"))
    (fp_line (start -14.51 -2.34) (end -14.51 4.34)
      (stroke (width 0.05) (type solid)) (layer "F.CrtYd"))
    (fp_line (start 2.51 -2.34) (end -14.51 -2.34)
      (stroke (width 0.05) (type solid)) (layer "F.CrtYd"))
    (fp_line (start 2.51 -2.34) (end 2.51 4.34)
      (stroke (width 0.05) (type solid)) (layer "F.CrtYd"))
    (fp_line (start 2.51 4.34) (end -14.51 4.34)
      (stroke (width 0.05) (type solid)) (layer "F.CrtYd"))
    (fp_line (start -14.356 -2.15) (end 2.293 -2.15)
      (stroke (width 0.15) (type solid)) (layer "F.Fab"))
    (fp_line (start -14.356 -1.898) (end -14.356 4.15)
      (stroke (width 0.15) (type solid)) (layer "F.Fab"))
    (fp_line (start -14.356 4.15) (end 2.32 4.15)
      (stroke (width 0.15) (type solid)) (layer "F.Fab"))
    (fp_line (start 2.33 -2.15) (end 2.33 4.13)
      (stroke (width 0.15) (type solid)) (layer "F.Fab"))
    (pad "1" thru_hole rect (at 0 0 90) (size 1.75 1.75) (drill 1) (layers "*.Cu" "*.Mask")
      (net 1 "GND") (pintype "passive"))
    (pad "2" thru_hole circle (at 0 1.999 90) (size 1.75 1.75) (drill 1) (layers "*.Cu" "*.Mask")
      (net 17 "PS_1V8") (pintype "passive"))
    (pad "3" thru_hole circle (at -2 0 90) (size 1.75 1.75) (drill 1) (layers "*.Cu" "*.Mask")
      (net 1 "GND") (pintype "passive"))
    (pad "4" thru_hole circle (at -2 1.999 90) (size 1.75 1.75) (drill 1) (layers "*.Cu" "*.Mask")
      (net 145 "/Debug and JTAG/JTAG_TMS_C2M") (pintype "passive"))
    (pad "5" thru_hole circle (at -4 0 90) (size 1.75 1.75) (drill 1) (layers "*.Cu" "*.Mask")
      (net 1 "GND") (pintype "passive"))
    (pad "6" thru_hole circle (at -4 1.999 90) (size 1.75 1.75) (drill 1) (layers "*.Cu" "*.Mask")
      (net 143 "/Debug and JTAG/JTAG_TCK_C2M") (pintype "passive"))
    (pad "7" thru_hole circle (at -6 0 90) (size 1.75 1.75) (drill 1) (layers "*.Cu" "*.Mask")
      (net 1 "GND") (pintype "passive"))
    (pad "8" thru_hole circle (at -6 1.999 90) (size 1.75 1.75) (drill 1) (layers "*.Cu" "*.Mask")
      (net 142 "/Debug and JTAG/JTAG_TDO_M2C") (pintype "passive"))
    (pad "9" thru_hole circle (at -8 0 90) (size 1.75 1.75) (drill 1) (layers "*.Cu" "*.Mask")
      (net 1 "GND") (pintype "passive"))
    (pad "10" thru_hole circle (at -8 1.999 90) (size 1.75 1.75) (drill 1) (layers "*.Cu" "*.Mask")
      (net 141 "/Debug and JTAG/JTAG_TDI_C2M") (pintype "passive"))
    (pad "11" thru_hole circle (at -10 0 90) (size 1.75 1.75) (drill 1) (layers "*.Cu" "*.Mask")
      (net 1 "GND") (pintype "passive"))
    (pad "12" thru_hole circle (at -10 1.999 90) (size 1.75 1.75) (drill 1) (layers "*.Cu" "*.Mask")
      (net 434 "unconnected-(J9-Pad12)") (pintype "passive+no_connect"))
    (pad "13" thru_hole circle (at -12 0 90) (size 1.75 1.75) (drill 1) (layers "*.Cu" "*.Mask")
      (net 140 "/Debug and JTAG/~{PS_SRST_C2M}") (pintype "passive"))
    (pad "14" thru_hole circle (at -12 1.999 90) (size 1.75 1.75) (drill 1) (layers "*.Cu" "*.Mask")
      (net 220 "/Debug and JTAG/CONN_GND") (pintype "passive"))
  )

  (footprint "kria-k26-devboard-footprints:DFN-14-1EP_4x3mm_P0.5mm" (layer "F.Cu")
    (at 186.6 122.1 90)
    (property "Author" "Antmicro")
    (property "License" "Apache-2.0")
    (property "MPN" "LTC4358CDE#PBF")
    (property "Manufacturer" "Analog Devices")
    (property "Sheetfile" "supply-oring.kicad_sch")
    (property "Sheetname" "Supply ORing")
    (property "ki_description" "Ideal diode")
    (property "ki_keywords" "SMT, PMIC, IC, POWER, MANAGEMENT, DIODE, CONTROLLER")
    (attr smd)
    (fp_text reference "U56" (at 0.02 2.97 90) (layer "F.SilkS")
        (effects (font (size 0.7 0.7) (thickness 0.15)) (justify left bottom))
    )
    (fp_text value "LTC4358CDE" (at 0 3.2 90) (layer "F.Fab") hide
        (effects (font (size 0.7 0.7) (thickness 0.15)) (justify left bottom))
    )
    (fp_text user "${REFERENCE}" (at -0.659 5.797 90) (layer "F.Fab") hide
        (effects (font (size 0.7 0.7) (thickness 0.15)) (justify left bottom))
    )
    (fp_text user "Author: Antmicro" (at -0.659 6.998 90) (layer "F.Fab") hide
        (effects (font (size 0.7 0.7) (thickness 0.15)) (justify left bottom))
    )
    (fp_text user "License: Apache-2.0" (at -0.659 8.198 90) (layer "F.Fab") hide
        (effects (font (size 0.7 0.7) (thickness 0.15)) (justify left bottom))
    )
    (fp_line (start -1.6 -2.045) (end 1.5995 -2.045)
      (stroke (width 0.15) (type solid)) (layer "F.SilkS"))
    (fp_line (start -1.6 2.044) (end 1.6 2.044)
      (stroke (width 0.15) (type solid)) (layer "F.SilkS"))
    (fp_circle (center -1.85 -1.9) (end -1.8 -1.9)
      (stroke (width 0.15) (type solid)) (fill solid) (layer "F.SilkS"))
    (fp_line (start -2.1 -1.87) (end -1.79 -1.87)
      (stroke (width 0.05) (type solid)) (layer "F.CrtYd"))
    (fp_line (start -2.1 1.9) (end -2.1 -1.87)
      (stroke (width 0.05) (type solid)) (layer "F.CrtYd"))
    (fp_line (start -1.79 -2.28) (end 1.81 -2.28)
      (stroke (width 0.05) (type solid)) (layer "F.CrtYd"))
    (fp_line (start -1.79 -1.87) (end -1.79 -2.28)
      (stroke (width 0.05) (type solid)) (layer "F.CrtYd"))
    (fp_line (start -1.79 1.9) (end -2.1 1.9)
      (stroke (width 0.05) (type solid)) (layer "F.CrtYd"))
    (fp_line (start -1.79 2.31) (end -1.79 1.9)
      (stroke (width 0.05) (type solid)) (layer "F.CrtYd"))
    (fp_line (start 1.81 -2.28) (end 1.81 -1.87)
      (stroke (width 0.05) (type solid)) (layer "F.CrtYd"))
    (fp_line (start 1.81 1.9) (end 1.81 2.31)
      (stroke (width 0.05) (type solid)) (layer "F.CrtYd"))
    (fp_line (start 1.81 2.31) (end -1.79 2.31)
      (stroke (width 0.05) (type solid)) (layer "F.CrtYd"))
    (fp_line (start 2.1 -1.87) (end 1.81 -1.87)
      (stroke (width 0.05) (type solid)) (layer "F.CrtYd"))
    (fp_line (start 2.1 -1.87) (end 2.1 1.9)
      (stroke (width 0.05) (type solid)) (layer "F.CrtYd"))
    (fp_line (start 2.1 1.9) (end 1.81 1.9)
      (stroke (width 0.05) (type solid)) (layer "F.CrtYd"))
    (fp_line (start -1.55 -2.045) (end -1.55 2.044)
      (stroke (width 0.15) (type solid)) (layer "F.Fab"))
    (fp_line (start -1.55 2.044) (end 1.549 2.044)
      (stroke (width 0.15) (type solid)) (layer "F.Fab"))
    (fp_line (start 1.549 -2.045) (end -1.55 -2.045)
      (stroke (width 0.15) (type solid)) (layer "F.Fab"))
    (fp_line (start 1.549 2.044) (end 1.549 -2.045)
      (stroke (width 0.15) (type solid)) (layer "F.Fab"))
    (pad "" smd roundrect (at 0 -0.8 90) (size 1.3 1.3) (layers "F.Paste") (roundrect_rratio 0.05))
    (pad "" smd roundrect (at 0 0.8 90) (size 1.3 1.3) (layers "F.Paste") (roundrect_rratio 0.05))
    (pad "1" smd roundrect (at -1.445 -1.499 90) (size 0.807999 0.2548) (layers "F.Cu" "F.Paste" "F.Mask") (roundrect_rratio 0.25)
      (net 13 "/Power Supply/PoE/POE_12V") (pinfunction "IN") (pintype "input"))
    (pad "2" smd roundrect (at -1.445 -1.001 90) (size 0.807999 0.2548) (layers "F.Cu" "F.Paste" "F.Mask") (roundrect_rratio 0.25)
      (net 13 "/Power Supply/PoE/POE_12V") (pinfunction "IN") (pintype "passive"))
    (pad "3" smd roundrect (at -1.445 -0.5 90) (size 0.807999 0.2548) (layers "F.Cu" "F.Paste" "F.Mask") (roundrect_rratio 0.25)
      (net 13 "/Power Supply/PoE/POE_12V") (pinfunction "IN") (pintype "passive"))
    (pad "4" smd roundrect (at -1.445 0 90) (size 0.807999 0.2548) (layers "F.Cu" "F.Paste" "F.Mask") (roundrect_rratio 0.25)
      (net 13 "/Power Supply/PoE/POE_12V") (pinfunction "IN") (pintype "passive"))
    (pad "5" smd roundrect (at -1.445 0.5 90) (size 0.807999 0.2548) (layers "F.Cu" "F.Paste" "F.Mask") (roundrect_rratio 0.25)
      (net 785 "unconnected-(U56-GATE-Pad5)") (pinfunction "GATE") (pintype "output+no_connect"))
    (pad "6" smd roundrect (at -1.445 1 90) (size 0.807999 0.2548) (layers "F.Cu" "F.Paste" "F.Mask") (roundrect_rratio 0.25)
      (net 786 "unconnected-(U56-NC-Pad6)") (pinfunction "NC") (pintype "no_connect"))
    (pad "7" smd roundrect (at -1.445 1.5 90) (size 0.807999 0.2548) (layers "F.Cu" "F.Paste" "F.Mask") (roundrect_rratio 0.25)
      (net 1 "GND") (pinfunction "GND") (pintype "power_in"))
    (pad "8" smd roundrect (at 1.445 1.5 90) (size 0.807999 0.2548) (layers "F.Cu" "F.Paste" "F.Mask") (roundrect_rratio 0.25)
      (net 14 "/Power Supply/DC/DC conventers/DC_MAIN_BUS") (pinfunction "VDD") (pintype "passive"))
    (pad "9" smd roundrect (at 1.445 1 90) (size 0.807999 0.2548) (layers "F.Cu" "F.Paste" "F.Mask") (roundrect_rratio 0.25)
      (net 14 "/Power Supply/DC/DC conventers/DC_MAIN_BUS") (pinfunction "OUT") (pintype "passive"))
    (pad "10" smd roundrect (at 1.445 0.5 90) (size 0.807999 0.2548) (layers "F.Cu" "F.Paste" "F.Mask") (roundrect_rratio 0.25)
      (net 787 "unconnected-(U56-NC-Pad10)") (pinfunction "NC") (pintype "no_connect"))
    (pad "11" smd roundrect (at 1.445 0 90) (size 0.807999 0.2548) (layers "F.Cu" "F.Paste" "F.Mask") (roundrect_rratio 0.25)
      (net 13 "/Power Supply/PoE/POE_12V") (pinfunction "IN") (pintype "passive"))
    (pad "12" smd roundrect (at 1.445 -0.501 90) (size 0.807999 0.2548) (layers "F.Cu" "F.Paste" "F.Mask") (roundrect_rratio 0.25)
      (net 13 "/Power Supply/PoE/POE_12V") (pinfunction "IN") (pintype "passive"))
    (pad "13" smd roundrect (at 1.445 -1.001 90) (size 0.807999 0.2548) (layers "F.Cu" "F.Paste" "F.Mask") (roundrect_rratio 0.25)
      (net 13 "/Power Supply/PoE/POE_12V") (pinfunction "IN") (pintype "passive"))
    (pad "14" smd roundrect (at 1.445 -1.499 90) (size 0.807999 0.2548) (layers "F.Cu" "F.Paste" "F.Mask") (roundrect_rratio 0.25)
      (net 13 "/Power Supply/PoE/POE_12V") (pinfunction "IN") (pintype "passive"))
    (pad "15" smd roundrect (at 0 0 90) (size 1.8034 3.4036) (layers "F.Cu" "F.Mask") (roundrect_rratio 0.05)
      (net 14 "/Power Supply/DC/DC conventers/DC_MAIN_BUS") (pinfunction "DRAIN") (pintype "passive"))
  )

  (footprint "kria-k26-devboard-footprints:R_0402_1005Metric" (layer "F.Cu")
    (at 188.475 137.575 180)
    (descr "Resistor SMD 0402")
    (tags "resistor SMD 0402")
    (property "Author" "Antmicro")
    (property "License" "Apache-2.0")
    (property "MPN" "CR0402-FX-1001GLF")
    (property "Manufacturer" "Bourns")
    (property "Sheetfile" "dc-dc-conventers.kicad_sch")
    (property "Sheetname" "DC/DC conventers")
    (property "Tolerance" "1%")
    (property "Val" "1k")
    (property "ki_description" "1k resistor in 0402 package with 1% tolerance")
    (attr smd)
    (fp_text reference "R143" (at -0.185 -3.315 270) (layer "F.SilkS")
        (effects (font (size 0.7 0.7) (thickness 0.15)) (justify left bottom))
    )
    (fp_text value "R_1k_0402" (at 0 1.4 180) (layer "F.Fab") hide
        (effects (font (size 0.7 0.7) (thickness 0.15)) (justify left bottom))
    )
    (fp_text user "License: Apache-2.0" (at -0.95 5.169 180) (layer "F.Fab") hide
        (effects (font (size 0.7 0.7) (thickness 0.15)) (justify left bottom))
    )
    (fp_text user "${REFERENCE}" (at -0.95 3.168 180) (layer "F.Fab") hide
        (effects (font (size 0.7 0.7) (thickness 0.15)) (justify left bottom))
    )
    (fp_text user "Author: Antmicro" (at -0.95 4.169 180) (layer "F.Fab") hide
        (effects (font (size 0.7 0.7) (thickness 0.15)) (justify left bottom))
    )
    (fp_rect (start -0.93 -0.47) (end 0.93 0.47)
      (stroke (width 0.05) (type solid)) (fill none) (layer "F.CrtYd"))
    (fp_rect (start -0.5 -0.25) (end 0.5 0.25)
      (stroke (width 0.15) (type solid)) (fill none) (layer "F.Fab"))
    (pad "1" smd roundrect (at -0.485 0 180) (size 0.59 0.64) (layers "F.Cu" "F.Paste" "F.Mask") (roundrect_rratio 0.25)
      (net 770 "/Power Supply/DC/DC conventers/PL_3V3_OUT") (pintype "passive"))
    (pad "2" smd roundrect (at 0.485 0 180) (size 0.59 0.64) (layers "F.Cu" "F.Paste" "F.Mask") (roundrect_rratio 0.25)
      (net 192 "Net-(D20-Pad1)") (pintype "passive"))
  )

  (footprint "kria-k26-devboard-footprints:LED_0603_1608Metric_G" (layer "F.Cu")
    (at 186 137.8 180)
    (descr "LED SMD 0603 Green")
    (tags "LED SMD 0603 Green")
    (property "Author" "Antmicro")
    (property "Color" "Green")
    (property "License" "Apache-2.0")
    (property "MPN" "LG L29K-G2J1-24-Z")
    (property "Manufacturer" "OSRAM")
    (property "Sheetfile" "dc-dc-conventers.kicad_sch")
    (property "Sheetname" "DC/DC conventers")
    (property "ki_description" "LED, Green, SMT, 0603, 20 mA, 2.1 V, 570 nm")
    (property "ki_keywords" "0603, SMT, DIODE, SEMICONDUCTOR, UNICOLOR")
    (attr smd)
    (fp_text reference "D20" (at 1.21 -0.74) (layer "F.SilkS")
        (effects (font (size 0.7 0.7) (thickness 0.15)) (justify right bottom))
    )
    (fp_text value "LED_G_0603_LG_L29K-G2J1-24-Z" (at 0 1.6) (layer "F.Fab") hide
        (effects (font (size 0.7 0.7) (thickness 0.15)) (justify right bottom))
    )
    (fp_text user "License: Apache-2.0" (at -1.31 5.769) (layer "F.Fab") hide
        (effects (font (size 0.7 0.7) (thickness 0.15)) (justify right bottom))
    )
    (fp_text user "${REFERENCE}" (at -1.31 3.769) (layer "F.Fab") hide
        (effects (font (size 0.7 0.7) (thickness 0.15)) (justify right bottom))
    )
    (fp_text user "Author: Antmicro" (at -1.31 4.769) (layer "F.Fab") hide
        (effects (font (size 0.7 0.7) (thickness 0.15)) (justify right bottom))
    )
    (fp_line (start -0.27 -0.35) (end 0.27 -0.35)
      (stroke (width 0.15) (type solid)) (layer "F.SilkS"))
    (fp_line (start -0.27 0.351) (end 0.27 0.351)
      (stroke (width 0.15) (type solid)) (layer "F.SilkS"))
    (fp_line (start -0.106328 -0.200008) (end -0.106328 0.199992)
      (stroke (width 0.1) (type solid)) (layer "F.SilkS"))
    (fp_line (start -0.106328 -0.200008) (end 0.093672 -0.000008)
      (stroke (width 0.1) (type solid)) (layer "F.SilkS"))
    (fp_line (start -0.106328 -0.000008) (end -0.29 0)
      (stroke (width 0.1) (type solid)) (layer "F.SilkS"))
    (fp_line (start 0.093672 -0.200008) (end 0.093672 0.199992)
      (stroke (width 0.1) (type solid)) (layer "F.SilkS"))
    (fp_line (start 0.093672 -0.000008) (end -0.106328 0.199992)
      (stroke (width 0.1) (type solid)) (layer "F.SilkS"))
    (fp_line (start 0.093672 -0.000008) (end 0.293672 -0.000008)
      (stroke (width 0.1) (type solid)) (layer "F.SilkS"))
    (fp_line (start 1.25 0.32) (end 1.25 -0.32)
      (stroke (width 0.15) (type solid)) (layer "F.SilkS"))
    (fp_rect (start 1.26 0.65) (end -1.26 -0.65)
      (stroke (width 0.05) (type solid)) (fill none) (layer "F.CrtYd"))
    (fp_line (start -0.599 0) (end -0.201 0)
      (stroke (width 0.15) (type solid)) (layer "F.Fab"))
    (fp_line (start -0.201 -0.2) (end -0.201 0)
      (stroke (width 0.15) (type solid)) (layer "F.Fab"))
    (fp_line (start -0.201 0) (end -0.201 0.202)
      (stroke (width 0.15) (type solid)) (layer "F.Fab"))
    (fp_line (start -0.201 0.202) (end 0.101 0)
      (stroke (width 0.15) (type solid)) (layer "F.Fab"))
    (fp_line (start 0.101 0) (end -0.201 -0.2)
      (stroke (width 0.15) (type solid)) (layer "F.Fab"))
    (fp_line (start 0.199 -0.2) (end 0.199 -0.1)
      (stroke (width 0.15) (type solid)) (layer "F.Fab"))
    (fp_line (start 0.199 0) (end 0.597 0)
      (stroke (width 0.15) (type solid)) (layer "F.Fab"))
    (fp_line (start 0.199 0.202) (end 0.199 -0.1)
      (stroke (width 0.15) (type solid)) (layer "F.Fab"))
    (fp_rect (start -0.848 -0.4) (end 0.85 0.402)
      (stroke (width 0.15) (type solid)) (fill none) (layer "F.Fab"))
    (pad "1" smd rect (at -0.75 0) (size 0.8 0.8) (layers "F.Cu" "F.Paste" "F.Mask")
      (net 192 "Net-(D20-Pad1)") (pintype "passive"))
    (pad "2" smd rect (at 0.75 0) (size 0.8 0.8) (layers "F.Cu" "F.Paste" "F.Mask")
      (net 340 "Net-(Q15-C)") (pinfunction "2") (pintype "passive"))
  )

  (footprint "kria-k26-devboard-footprints:C_0603_1608Metric" (layer "F.Cu")
    (at 191.2 135.846752 90)
    (descr "Capacitor SMD 0603")
    (tags "capacitor 0603")
    (property "Author" "Antmicro")
    (property "Dielectric" "")
    (property "License" "Apache-2.0")
    (property "MPN" "GRM188R60J226MEA0D")
    (property "Manufacturer" "Murata")
    (property "Sheetfile" "dc-dc-conventers.kicad_sch")
    (property "Sheetname" "DC/DC conventers")
    (property "Val" "22u")
    (property "Voltage" "")
    (property "ki_description" " ")
    (attr smd)
    (fp_text reference "C226" (at -6.613248 0.34 90) (layer "F.SilkS")
        (effects (font (size 0.7 0.7) (thickness 0.15)) (justify left bottom))
    )
    (fp_text value "C_22u_0603" (at 0 1.6 90) (layer "F.Fab") hide
        (effects (font (size 0.7 0.7) (thickness 0.15)) (justify left bottom))
    )
    (fp_text user "${REFERENCE}" (at -1.682 3.895 90) (layer "F.Fab") hide
        (effects (font (size 0.7 0.7) (thickness 0.15)) (justify left bottom))
    )
    (fp_text user "Author: Antmicro" (at -1.682 4.894 90) (layer "F.Fab") hide
        (effects (font (size 0.7 0.7) (thickness 0.15)) (justify left bottom))
    )
    (fp_text user "License: Apache-2.0" (at -1.682 5.895 90) (layer "F.Fab") hide
        (effects (font (size 0.7 0.7) (thickness 0.15)) (justify left bottom))
    )
    (fp_line (start -0.3 -0.3) (end 0.3 -0.3)
      (stroke (width 0.15) (type solid)) (layer "F.SilkS"))
    (fp_line (start -0.3 0.3) (end 0.3 0.3)
      (stroke (width 0.15) (type solid)) (layer "F.SilkS"))
    (fp_rect (start -1.24 -0.7) (end 1.24 0.7)
      (stroke (width 0.05) (type solid)) (fill none) (layer "F.CrtYd"))
    (fp_rect (start -0.8 -0.4) (end 0.8 0.4)
      (stroke (width 0.15) (type solid)) (fill none) (layer "F.Fab"))
    (pad "1" smd roundrect (at -0.7 0 90) (size 0.6 0.8) (layers "F.Cu" "F.Paste" "F.Mask") (roundrect_rratio 0.2)
      (net 771 "/Power Supply/DC/DC conventers/PL_1V2_OUT") (pintype "passive"))
    (pad "2" smd roundrect (at 0.7 0 90) (size 0.6 0.8) (layers "F.Cu" "F.Paste" "F.Mask") (roundrect_rratio 0.2)
      (net 1 "GND") (pintype "passive"))
  )

  (footprint "kria-k26-devboard-footprints:C_0603_1608Metric" (layer "F.Cu")
    (at 189.9 133.1 -90)
    (descr "Capacitor SMD 0603")
    (tags "capacitor 0603")
    (property "Author" "Antmicro")
    (property "Dielectric" "")
    (property "License" "Apache-2.0")
    (property "MPN" "C1608X5R1E106M080AC")
    (property "Manufacturer" "TDK")
    (property "Sheetfile" "dc-dc-conventers.kicad_sch")
    (property "Sheetname" "DC/DC conventers")
    (property "Val" "10u/25V")
    (property "Voltage" "")
    (property "ki_description" " ")
    (attr smd)
    (fp_text reference "C220" (at 0.09 -1.63 -90) (layer "F.SilkS")
        (effects (font (size 0.7 0.7) (thickness 0.15)) (justify left bottom))
    )
    (fp_text value "C_10u_25V_0603" (at 0 1.6 -90) (layer "F.Fab") hide
        (effects (font (size 0.7 0.7) (thickness 0.15)) (justify left bottom))
    )
    (fp_text user "License: Apache-2.0" (at -1.682 5.895 -90) (layer "F.Fab") hide
        (effects (font (size 0.7 0.7) (thickness 0.15)) (justify left bottom))
    )
    (fp_text user "${REFERENCE}" (at -1.682 3.895 -90) (layer "F.Fab") hide
        (effects (font (size 0.7 0.7) (thickness 0.15)) (justify left bottom))
    )
    (fp_text user "Author: Antmicro" (at -1.682 4.894 -90) (layer "F.Fab") hide
        (effects (font (size 0.7 0.7) (thickness 0.15)) (justify left bottom))
    )
    (fp_line (start -0.3 -0.3) (end 0.3 -0.3)
      (stroke (width 0.15) (type solid)) (layer "F.SilkS"))
    (fp_line (start -0.3 0.3) (end 0.3 0.3)
      (stroke (width 0.15) (type solid)) (layer "F.SilkS"))
    (fp_rect (start -1.24 -0.7) (end 1.24 0.7)
      (stroke (width 0.05) (type solid)) (fill none) (layer "F.CrtYd"))
    (fp_rect (start -0.8 -0.4) (end 0.8 0.4)
      (stroke (width 0.15) (type solid)) (fill none) (layer "F.Fab"))
    (pad "1" smd roundrect (at -0.7 0 270) (size 0.6 0.8) (layers "F.Cu" "F.Paste" "F.Mask") (roundrect_rratio 0.2)
      (net 14 "/Power Supply/DC/DC conventers/DC_MAIN_BUS") (pintype "passive"))
    (pad "2" smd roundrect (at 0.7 0 270) (size 0.6 0.8) (layers "F.Cu" "F.Paste" "F.Mask") (roundrect_rratio 0.2)
      (net 1 "GND") (pintype "passive"))
  )

  (footprint "kria-k26-devboard-footprints:C_0603_1608Metric" (layer "F.Cu")
    (at 189.985356 135.846752 90)
    (descr "Capacitor SMD 0603")
    (tags "capacitor 0603")
    (property "Author" "Antmicro")
    (property "Dielectric" "")
    (property "License" "Apache-2.0")
    (property "MPN" "GRM188R60J226MEA0D")
    (property "Manufacturer" "Murata")
    (property "Sheetfile" "dc-dc-conventers.kicad_sch")
    (property "Sheetname" "DC/DC conventers")
    (property "Val" "22u")
    (property "Voltage" "")
    (property "ki_description" " ")
    (attr smd)
    (fp_text reference "C224" (at -6.613248 0.34 90) (layer "F.SilkS")
        (effects (font (size 0.7 0.7) (thickness 0.15)) (justify left bottom))
    )
    (fp_text value "C_22u_0603" (at 0 1.6 90) (layer "F.Fab") hide
        (effects (font (size 0.7 0.7) (thickness 0.15)) (justify left bottom))
    )
    (fp_text user "${REFERENCE}" (at -1.682 3.895 90) (layer "F.Fab") hide
        (effects (font (size 0.7 0.7) (thickness 0.15)) (justify left bottom))
    )
    (fp_text user "License: Apache-2.0" (at -1.682 5.895 90) (layer "F.Fab") hide
        (effects (font (size 0.7 0.7) (thickness 0.15)) (justify left bottom))
    )
    (fp_text user "Author: Antmicro" (at -1.682 4.894 90) (layer "F.Fab") hide
        (effects (font (size 0.7 0.7) (thickness 0.15)) (justify left bottom))
    )
    (fp_line (start -0.3 -0.3) (end 0.3 -0.3)
      (stroke (width 0.15) (type solid)) (layer "F.SilkS"))
    (fp_line (start -0.3 0.3) (end 0.3 0.3)
      (stroke (width 0.15) (type solid)) (layer "F.SilkS"))
    (fp_rect (start -1.24 -0.7) (end 1.24 0.7)
      (stroke (width 0.05) (type solid)) (fill none) (layer "F.CrtYd"))
    (fp_rect (start -0.8 -0.4) (end 0.8 0.4)
      (stroke (width 0.15) (type solid)) (fill none) (layer "F.Fab"))
    (pad "1" smd roundrect (at -0.7 0 90) (size 0.6 0.8) (layers "F.Cu" "F.Paste" "F.Mask") (roundrect_rratio 0.2)
      (net 771 "/Power Supply/DC/DC conventers/PL_1V2_OUT") (pintype "passive"))
    (pad "2" smd roundrect (at 0.7 0 90) (size 0.6 0.8) (layers "F.Cu" "F.Paste" "F.Mask") (roundrect_rratio 0.2)
      (net 1 "GND") (pintype "passive"))
  )

  (footprint "kria-k26-devboard-footprints:L_0806_2016Metric" (layer "F.Cu")
    (at 187.8 135.925001)
    (property "Author" "Antmicro")
    (property "IMax" "")
    (property "ISat" "")
    (property "License" "Apache-2.0")
    (property "MPN" "SRP2010-1R0M")
    (property "Manufacturer" "Bourns")
    (property "Sheetfile" "dc-dc-conventers.kicad_sch")
    (property "Sheetname" "DC/DC conventers")
    (property "Size" "2.0x1.6")
    (property "Val" "1u/2.6A")
    (attr smd)
    (fp_text reference "L9" (at 0.98 -4.225001) (layer "F.SilkS")
        (effects (font (size 0.7 0.7) (thickness 0.15)) (justify left bottom))
    )
    (fp_text value "L_1u_2.6A_0806" (at 0 2) (layer "F.Fab") hide
        (effects (font (size 0.7 0.7) (thickness 0.15)) (justify left bottom))
    )
    (fp_text user "Author: Antmicro" (at -1.9 4.4) (layer "F.Fab") hide
        (effects (font (size 0.7 0.7) (thickness 0.15)) (justify left bottom))
    )
    (fp_text user "License: Apache-2.0" (at -1.9 5.75) (layer "F.Fab") hide
        (effects (font (size 0.7 0.7) (thickness 0.15)) (justify left bottom))
    )
    (fp_text user "${REFERENCE}" (at -1.9 3.1) (layer "F.Fab") hide
        (effects (font (size 0.7 0.7) (thickness 0.15)) (justify left bottom))
    )
    (fp_line (start -0.301 0.9) (end 0.299 0.9)
      (stroke (width 0.15) (type solid)) (layer "F.SilkS"))
    (fp_line (start -0.3 -0.9) (end 0.298 -0.9)
      (stroke (width 0.15) (type solid)) (layer "F.SilkS"))
    (fp_rect (start -1.75 -1.05) (end 1.75 1.05)
      (stroke (width 0.05) (type solid)) (fill none) (layer "F.CrtYd"))
    (fp_rect (start -0.951 -0.882) (end 0.949 0.875)
      (stroke (width 0.15) (type solid)) (fill none) (layer "F.Fab"))
    (pad "1" smd roundrect (at -1.1 -0.001) (size 1 1.8) (layers "F.Cu" "F.Paste" "F.Mask") (roundrect_rratio 0.15)
      (net 316 "/Power Supply/DC/DC conventers/SW_PL_1V2") (pintype "passive"))
    (pad "2" smd roundrect (at 1.1 -0.001) (size 1 1.8) (layers "F.Cu" "F.Paste" "F.Mask") (roundrect_rratio 0.15)
      (net 771 "/Power Supply/DC/DC conventers/PL_1V2_OUT") (pintype "passive"))
  )

  (footprint "kria-k26-devboard-footprints:R_0402_1005Metric" (layer "F.Cu")
    (at 184.524999 131.985 90)
    (descr "Resistor SMD 0402")
    (tags "resistor SMD 0402")
    (property "Author" "Antmicro")
    (property "License" "Apache-2.0")
    (property "MPN" "CR0402-FX-4991GLF")
    (property "Manufacturer" "Bourns")
    (property "Sheetfile" "dc-dc-conventers.kicad_sch")
    (property "Sheetname" "DC/DC conventers")
    (property "Tolerance" "1%")
    (property "Val" "4k99")
    (property "ki_description" "4k99 resistor in 0402 package with 1% tolerance")
    (attr smd)
    (fp_text reference "R146" (at -0.295 -0.604999 90) (layer "F.SilkS")
        (effects (font (size 0.7 0.7) (thickness 0.15)) (justify left bottom))
    )
    (fp_text value "R_4k99_0402" (at 0 1.4 90) (layer "F.Fab") hide
        (effects (font (size 0.7 0.7) (thickness 0.15)) (justify left bottom))
    )
    (fp_text user "Author: Antmicro" (at -0.95 4.169 90) (layer "F.Fab") hide
        (effects (font (size 0.7 0.7) (thickness 0.15)) (justify left bottom))
    )
    (fp_text user "${REFERENCE}" (at -0.95 3.168 90) (layer "F.Fab") hide
        (effects (font (size 0.7 0.7) (thickness 0.15)) (justify left bottom))
    )
    (fp_text user "License: Apache-2.0" (at -0.95 5.169 90) (layer "F.Fab") hide
        (effects (font (size 0.7 0.7) (thickness 0.15)) (justify left bottom))
    )
    (fp_rect (start -0.93 -0.47) (end 0.93 0.47)
      (stroke (width 0.05) (type solid)) (fill none) (layer "F.CrtYd"))
    (fp_rect (start -0.5 -0.25) (end 0.5 0.25)
      (stroke (width 0.15) (type solid)) (fill none) (layer "F.Fab"))
    (pad "1" smd roundrect (at -0.485 0 90) (size 0.59 0.64) (layers "F.Cu" "F.Paste" "F.Mask") (roundrect_rratio 0.25)
      (net 771 "/Power Supply/DC/DC conventers/PL_1V2_OUT") (pintype "passive"))
    (pad "2" smd roundrect (at 0.485 0 90) (size 0.59 0.64) (layers "F.Cu" "F.Paste" "F.Mask") (roundrect_rratio 0.25)
      (net 694 "Net-(U55-FB)") (pintype "passive"))
  )

  (footprint "kria-k26-devboard-footprints:R_0402_1005Metric" (layer "F.Cu")
    (at 186.060355 130.496751)
    (descr "Resistor SMD 0402")
    (tags "resistor SMD 0402")
    (property "Author" "Antmicro")
    (property "License" "Apache-2.0")
    (property "MPN" "CR0402-FX-1002GLF")
    (property "Manufacturer" "Bourns")
    (property "Sheetfile" "dc-dc-conventers.kicad_sch")
    (property "Sheetname" "DC/DC conventers")
    (property "Tolerance" "1%")
    (property "Val" "10k")
    (property "ki_description" "10k resistor in 0402 package with 1% tolerance")
    (attr smd)
    (fp_text reference "R147" (at 0.609645 -0.446751) (layer "F.SilkS")
        (effects (font (size 0.7 0.7) (thickness 0.15)) (justify left bottom))
    )
    (fp_text value "R_10k_0402" (at 0 1.4) (layer "F.Fab") hide
        (effects (font (size 0.7 0.7) (thickness 0.15)) (justify left bottom))
    )
    (fp_text user "${REFERENCE}" (at -0.95 3.168) (layer "F.Fab") hide
        (effects (font (size 0.7 0.7) (thickness 0.15)) (justify left bottom))
    )
    (fp_text user "Author: Antmicro" (at -0.95 4.169) (layer "F.Fab") hide
        (effects (font (size 0.7 0.7) (thickness 0.15)) (justify left bottom))
    )
    (fp_text user "License: Apache-2.0" (at -0.95 5.169) (layer "F.Fab") hide
        (effects (font (size 0.7 0.7) (thickness 0.15)) (justify left bottom))
    )
    (fp_rect (start -0.93 -0.47) (end 0.93 0.47)
      (stroke (width 0.05) (type solid)) (fill none) (layer "F.CrtYd"))
    (fp_rect (start -0.5 -0.25) (end 0.5 0.25)
      (stroke (width 0.15) (type solid)) (fill none) (layer "F.Fab"))
    (pad "1" smd roundrect (at -0.485 0) (size 0.59 0.64) (layers "F.Cu" "F.Paste" "F.Mask") (roundrect_rratio 0.25)
      (net 694 "Net-(U55-FB)") (pintype "passive"))
    (pad "2" smd roundrect (at 0.485 0) (size 0.59 0.64) (layers "F.Cu" "F.Paste" "F.Mask") (roundrect_rratio 0.25)
      (net 1 "GND") (pintype "passive"))
  )

  (footprint "kria-k26-devboard-footprints:C_0402_1005Metric" (layer "F.Cu")
    (at 138.845 136 -90)
    (descr "Capacitor SMD 0402")
    (tags "capacitor SMD 0402")
    (property "Author" "Antmicro")
    (property "Dielectric" "X5R")
    (property "License" "Apache-2.0")
    (property "MPN" "GRM155R61H104KE14D")
    (property "Manufacturer" "Murata")
    (property "Sheetfile" "sd-3-card.kicad_sch")
    (property "Sheetname" "SD 3.0 card")
    (property "Val" "100n")
    (property "Voltage" "50V")
    (property "ki_description" " ")
    (attr smd)
    (fp_text reference "C13" (at 1.05 -1.325 -90) (layer "F.SilkS")
        (effects (font (size 0.7 0.7) (thickness 0.15)) (justify left bottom))
    )
    (fp_text value "C_100n_0402" (at 0 1.4 -90) (layer "F.Fab") hide
        (effects (font (size 0.7 0.7) (thickness 0.15)) (justify left bottom))
    )
    (fp_text user "Author: Antmicro" (at -0.932 4.17 -90) (layer "F.Fab") hide
        (effects (font (size 0.7 0.7) (thickness 0.15)) (justify left bottom))
    )
    (fp_text user "License: Apache-2.0" (at -0.932 5.17 -90) (layer "F.Fab") hide
        (effects (font (size 0.7 0.7) (thickness 0.15)) (justify left bottom))
    )
    (fp_text user "${REFERENCE}" (at -0.932 3.168 -90) (layer "F.Fab") hide
        (effects (font (size 0.7 0.7) (thickness 0.15)) (justify left bottom))
    )
    (fp_rect (start -0.94 -0.47) (end 0.94 0.47)
      (stroke (width 0.05) (type solid)) (fill none) (layer "F.CrtYd"))
    (fp_rect (start -0.499 -0.249) (end 0.499 0.249)
      (stroke (width 0.15) (type solid)) (fill none) (layer "F.Fab"))
    (pad "1" smd roundrect (at -0.484 0 270) (size 0.59 0.64) (layers "F.Cu" "F.Paste" "F.Mask") (roundrect_rratio 0.25)
      (net 17 "PS_1V8") (pintype "passive"))
    (pad "2" smd roundrect (at 0.484 0 270) (size 0.59 0.64) (layers "F.Cu" "F.Paste" "F.Mask") (roundrect_rratio 0.25)
      (net 1 "GND") (pintype "passive"))
  )

  (footprint "kria-k26-devboard-footprints:SOT-583" (layer "F.Cu")
    (at 136.983 136.374 -90)
    (property "Author" "Antmicro")
    (property "License" "Apache-2.0")
    (property "MPN" "TPS2116DRLR")
    (property "Manufacturer" "Texas Instruments")
    (property "Sheetfile" "sd-3-card.kicad_sch")
    (property "Sheetname" "SD 3.0 card")
    (property "ki_description" "Power switch")
    (property "ki_keywords" "SMT, SWITCH, IC, POWER, DRIVER")
    (attr smd)
    (fp_text reference "U6" (at -1.254 0.683) (layer "F.SilkS")
        (effects (font (size 0.7 0.7) (thickness 0.15)) (justify left bottom))
    )
    (fp_text value "TPS2116DRLR" (at 0 2.3 -90) (layer "F.Fab") hide
        (effects (font (size 0.7 0.7) (thickness 0.15)) (justify left bottom))
    )
    (fp_text user "Author: Antmicro" (at -0.06 5.025 -90) (layer "F.Fab") hide
        (effects (font (size 0.7 0.7) (thickness 0.15)) (justify left bottom))
    )
    (fp_text user "${REFERENCE}" (at -0.06 4.025 -90) (layer "F.Fab") hide
        (effects (font (size 0.7 0.7) (thickness 0.15)) (justify left bottom))
    )
    (fp_text user "License: Apache-2.0" (at -0.06 6.025 -90) (layer "F.Fab") hide
        (effects (font (size 0.7 0.7) (thickness 0.15)) (justify left bottom))
    )
    (fp_line (start -0.651 1.15) (end 0.651 1.15)
      (stroke (width 0.15) (type solid)) (layer "F.SilkS"))
    (fp_line (start -0.65 -1.15) (end 0.65 -1.15)
      (stroke (width 0.15) (type solid)) (layer "F.SilkS"))
    (fp_circle (center -0.9 -1.1) (end -0.85 -1.05)
      (stroke (width 0.15) (type solid)) (fill solid) (layer "F.SilkS"))
    (fp_rect (start -1.15 -1.3) (end 1.15 1.3)
      (stroke (width 0.05) (type solid)) (fill none) (layer "F.CrtYd"))
    (fp_line (start -0.651 -1.1005) (end 0.651 -1.1005)
      (stroke (width 0.15) (type solid)) (layer "F.Fab"))
    (fp_line (start -0.651 1.1005) (end -0.651 -1.1005)
      (stroke (width 0.15) (type solid)) (layer "F.Fab"))
    (fp_line (start -0.651 1.1005) (end 0.651 1.1005)
      (stroke (width 0.15) (type solid)) (layer "F.Fab"))
    (fp_line (start 0.651 1.1005) (end 0.651 -1.1005)
      (stroke (width 0.15) (type solid)) (layer "F.Fab"))
    (pad "1" smd roundrect (at -0.739 -0.7495 270) (size 0.670001 0.299999) (layers "F.Cu" "F.Paste" "F.Mask") (roundrect_rratio 0.25)
      (net 1 "GND") (pinfunction "GND") (pintype "power_in"))
    (pad "2" smd roundrect (at -0.739 -0.2505 270) (size 0.670001 0.299999) (layers "F.Cu" "F.Paste" "F.Mask") (roundrect_rratio 0.25)
      (net 104 "/SD 3.0 card/VCCB") (pinfunction "VOUT") (pintype "power_out"))
    (pad "3" smd roundrect (at -0.739 0.2495 270) (size 0.670001 0.299999) (layers "F.Cu" "F.Paste" "F.Mask") (roundrect_rratio 0.25)
      (net 17 "PS_1V8") (pinfunction "VIN1") (pintype "power_in"))
    (pad "4" smd roundrect (at -0.739 0.7495 270) (size 0.670001 0.299999) (layers "F.Cu" "F.Paste" "F.Mask") (roundrect_rratio 0.25)
      (net 109 "/SD 3.0 card/MIO39") (pinfunction "PR1") (pintype "input"))
    (pad "5" smd roundrect (at 0.74 0.7495 270) (size 0.670001 0.299999) (layers "F.Cu" "F.Paste" "F.Mask") (roundrect_rratio 0.25)
      (net 15 "PS_3V3") (pinfunction "MODE") (pintype "input"))
    (pad "6" smd roundrect (at 0.74 0.2495 270) (size 0.670001 0.299999) (layers "F.Cu" "F.Paste" "F.Mask") (roundrect_rratio 0.25)
      (net 15 "PS_3V3") (pinfunction "VIN2") (pintype "power_in"))
    (pad "7" smd roundrect (at 0.74 -0.2505 270) (size 0.670001 0.299999) (layers "F.Cu" "F.Paste" "F.Mask") (roundrect_rratio 0.25)
      (net 104 "/SD 3.0 card/VCCB") (pinfunction "VOUT") (pintype "passive"))
    (pad "8" smd roundrect (at 0.74 -0.7495 270) (size 0.670001 0.299999) (layers "F.Cu" "F.Paste" "F.Mask") (roundrect_rratio 0.25)
      (net 695 "Net-(U6-ST)") (pinfunction "ST") (pintype "output"))
  )

  (footprint "kria-k26-devboard-footprints:SOT-563" (layer "F.Cu")
    (at 144.35 142.1 90)
    (property "Author" "Antmicro")
    (property "License" "Apache-2.0")
    (property "MPN" "82400152")
    (property "Manufacturer" "Würth Elektronik")
    (property "Sheetfile" "debug.kicad_sch")
    (property "Sheetname" "Debug and JTAG")
    (property "ki_description" "Low Capacitance TVS Diode Array, 2 Channels, SOT563")
    (property "ki_keywords" "ESD Protection TVS High-speed USB")
    (attr smd)
    (fp_text reference "U37" (at 1.33 -1.17 180) (layer "F.SilkS")
        (effects (font (size 0.7 0.7) (thickness 0.15)) (justify left bottom))
    )
    (fp_text value "82400152" (at 0 2 90) (layer "F.Fab") hide
        (effects (font (size 0.7 0.7) (thickness 0.15)) (justify left bottom))
    )
    (fp_text user "Author: Antmicro" (at -1.299 6.124 90) (layer "F.Fab") hide
        (effects (font (size 0.7 0.7) (thickness 0.15)) (justify left bottom))
    )
    (fp_text user "${REFERENCE}" (at -1.299 7.323 90) (layer "F.Fab") hide
        (effects (font (size 0.7 0.7) (thickness 0.15)) (justify left bottom))
    )
    (fp_text user "License: Apache-2.0" (at -1.299 4.924 90) (layer "F.Fab") hide
        (effects (font (size 0.7 0.7) (thickness 0.15)) (justify left bottom))
    )
    (fp_line (start -0.778 0.776) (end -0.778 0.949)
      (stroke (width 0.15) (type solid)) (layer "F.SilkS"))
    (fp_line (start -0.778 0.949) (end -0.424 0.949)
      (stroke (width 0.15) (type solid)) (layer "F.SilkS"))
    (fp_line (start -0.499 -0.974) (end -0.724 -0.778)
      (stroke (width 0.15) (type solid)) (layer "F.SilkS"))
    (fp_line (start 0.776 -0.974) (end 0.526 -0.974)
      (stroke (width 0.15) (type solid)) (layer "F.SilkS"))
    (fp_line (start 0.776 -0.974) (end 0.776 -0.778)
      (stroke (width 0.15) (type solid)) (layer "F.SilkS"))
    (fp_line (start 0.776 0.776) (end 0.776 0.972)
      (stroke (width 0.15) (type solid)) (layer "F.SilkS"))
    (fp_line (start 0.776 0.972) (end 0.526 0.972)
      (stroke (width 0.15) (type solid)) (layer "F.SilkS"))
    (fp_circle (center -0.903 -0.999) (end -0.952 -0.95)
      (stroke (width 0.15) (type solid)) (fill solid) (layer "F.SilkS"))
    (fp_rect (start 1.19 -1.12) (end -1.2 1.1)
      (stroke (width 0.05) (type solid)) (fill none) (layer "F.CrtYd"))
    (fp_line (start -0.653 -0.678) (end -0.653 0.847)
      (stroke (width 0.15) (type solid)) (layer "F.Fab"))
    (fp_line (start -0.453 -0.849) (end -0.653 -0.678)
      (stroke (width 0.15) (type solid)) (layer "F.Fab"))
    (fp_line (start -0.453 -0.849) (end 0.651 -0.849)
      (stroke (width 0.15) (type solid)) (layer "F.Fab"))
    (fp_line (start 0.651 -0.849) (end 0.651 0.847)
      (stroke (width 0.15) (type solid)) (layer "F.Fab"))
    (fp_line (start 0.651 0.847) (end -0.653 0.847)
      (stroke (width 0.15) (type solid)) (layer "F.Fab"))
    (pad "1" smd roundrect (at -0.749 -0.499) (size 0.3 0.6) (layers "F.Cu" "F.Paste" "F.Mask") (roundrect_rratio 0.25)
      (net 355 "Net-(J8-D_{A}+)") (pintype "passive"))
    (pad "2" smd roundrect (at -0.749 0.001) (size 0.3 0.6) (layers "F.Cu" "F.Paste" "F.Mask") (roundrect_rratio 0.25)
      (net 1 "GND") (pintype "passive"))
    (pad "3" smd roundrect (at -0.749 0.497) (size 0.3 0.6) (layers "F.Cu" "F.Paste" "F.Mask") (roundrect_rratio 0.25)
      (net 356 "Net-(J8-D_{A}-)") (pintype "passive"))
    (pad "4" smd roundrect (at 0.747 0.497) (size 0.3 0.6) (layers "F.Cu" "F.Paste" "F.Mask") (roundrect_rratio 0.25)
      (net 223 "/Debug and JTAG/USBB_N") (pintype "passive"))
    (pad "5" smd roundrect (at 0.747 0.001) (size 0.3 0.6) (layers "F.Cu" "F.Paste" "F.Mask") (roundrect_rratio 0.25)
      (net 763 "unconnected-(U37-Pad5)") (pintype "passive+no_connect"))
    (pad "6" smd roundrect (at 0.747 -0.499) (size 0.3 0.6) (layers "F.Cu" "F.Paste" "F.Mask") (roundrect_rratio 0.25)
      (net 222 "/Debug and JTAG/USBB_P") (pintype "passive"))
  )

  (footprint "kria-k26-devboard-footprints:MP_Pad6mm_Drill3mm" (layer "F.Cu")
    (at 188.5 148.5)
    (property "Author" "Antmicro")
    (property "License" "Apache-2.0")
    (property "MPN" "")
    (property "Manufacturer" "")
    (property "Sheetfile" "k26_som.kicad_sch")
    (property "Sheetname" "Xilinx K26 SOM")
    (property "exclude_from_bom" "")
    (property "ki_description" "Mechanical part")
    (property "ki_keywords" "MECHANICAL")
    (attr through_hole exclude_from_bom)
    (fp_text reference "MP2" (at -0.178 4.025) (layer "F.SilkS") hide
        (effects (font (size 0.7 0.7) (thickness 0.15)) (justify left bottom))
    )
    (fp_text value "MP_Pad6mm_Drill3mm" (at -0.153 -4.153) (layer "F.Fab") hide
        (effects (font (size 0.7 0.7) (thickness 0.15)) (justify left bottom))
    )
    (fp_text user "License: Apache-2.0" (at -0.178 8.425) (layer "F.Fab") hide
        (effects (font (size 0.7 0.7) (thickness 0.15)) (justify left bottom))
    )
    (fp_text user "Author: Antmicro" (at -0.178 7.225) (layer "F.Fab") hide
        (effects (font (size 0.7 0.7) (thickness 0.15)) (justify left bottom))
    )
    (fp_text user "${REFERENCE}" (at -0.178 6.025) (layer "F.Fab") hide
        (effects (font (size 0.7 0.7) (thickness 0.15)) (justify left bottom))
    )
    (pad "1" thru_hole circle (at 0 0) (size 6 6) (drill 3.2) (layers "*.Cu" "*.Mask")
      (net 1 "GND") (pintype "passive"))
  )

  (footprint "kria-k26-devboard-footprints:MP_Pad6mm_Drill3mm" (layer "F.Cu")
    (at 77.5 148.5)
    (property "Author" "Antmicro")
    (property "License" "Apache-2.0")
    (property "MPN" "")
    (property "Manufacturer" "")
    (property "Sheetfile" "k26_som.kicad_sch")
    (property "Sheetname" "Xilinx K26 SOM")
    (property "exclude_from_bom" "")
    (property "ki_description" "Mechanical part")
    (property "ki_keywords" "MECHANICAL")
    (attr through_hole exclude_from_bom)
    (fp_text reference "MP1" (at -0.178 4.025) (layer "F.SilkS") hide
        (effects (font (size 0.7 0.7) (thickness 0.15)) (justify left bottom))
    )
    (fp_text value "MP_Pad6mm_Drill3mm" (at -0.153 -4.153) (layer "F.Fab") hide
        (effects (font (size 0.7 0.7) (thickness 0.15)) (justify left bottom))
    )
    (fp_text user "${REFERENCE}" (at -0.178 6.025) (layer "F.Fab") hide
        (effects (font (size 0.7 0.7) (thickness 0.15)) (justify left bottom))
    )
    (fp_text user "License: Apache-2.0" (at -0.178 8.425) (layer "F.Fab") hide
        (effects (font (size 0.7 0.7) (thickness 0.15)) (justify left bottom))
    )
    (fp_text user "Author: Antmicro" (at -0.178 7.225) (layer "F.Fab") hide
        (effects (font (size 0.7 0.7) (thickness 0.15)) (justify left bottom))
    )
    (pad "1" thru_hole circle (at 0 0) (size 6 6) (drill 3.2) (layers "*.Cu" "*.Mask")
      (net 1 "GND") (pintype "passive"))
  )

  (footprint "kria-k26-devboard-footprints:MP_Pad6mm_Drill3mm" (layer "F.Cu")
    (at 77.5 55.5)
    (property "Author" "Antmicro")
    (property "License" "Apache-2.0")
    (property "MPN" "")
    (property "Manufacturer" "")
    (property "Sheetfile" "k26_som.kicad_sch")
    (property "Sheetname" "Xilinx K26 SOM")
    (property "exclude_from_bom" "")
    (property "ki_description" "Mechanical part")
    (property "ki_keywords" "MECHANICAL")
    (attr through_hole exclude_from_bom)
    (fp_text reference "MP4" (at -1.18 2.54) (layer "F.SilkS") hide
        (effects (font (size 0.7 0.7) (thickness 0.15)) (justify left bottom))
    )
    (fp_text value "MP_Pad6mm_Drill3mm" (at -0.153 -4.153) (layer "F.Fab") hide
        (effects (font (size 0.7 0.7) (thickness 0.15)) (justify left bottom))
    )
    (fp_text user "${REFERENCE}" (at -0.178 6.025) (layer "F.Fab") hide
        (effects (font (size 0.7 0.7) (thickness 0.15)) (justify left bottom))
    )
    (fp_text user "Author: Antmicro" (at -0.178 7.225) (layer "F.Fab") hide
        (effects (font (size 0.7 0.7) (thickness 0.15)) (justify left bottom))
    )
    (fp_text user "License: Apache-2.0" (at -0.178 8.425) (layer "F.Fab") hide
        (effects (font (size 0.7 0.7) (thickness 0.15)) (justify left bottom))
    )
    (pad "1" thru_hole circle (at 0 0) (size 6 6) (drill 3.2) (layers "*.Cu" "*.Mask")
      (net 1 "GND") (pintype "passive"))
  )

  (footprint "kria-k26-devboard-footprints:MP_Pad6mm_Drill3mm" (layer "F.Cu")
    (at 188.5 55.5)
    (property "Author" "Antmicro")
    (property "License" "Apache-2.0")
    (property "MPN" "")
    (property "Manufacturer" "")
    (property "Sheetfile" "k26_som.kicad_sch")
    (property "Sheetname" "Xilinx K26 SOM")
    (property "exclude_from_bom" "")
    (property "ki_description" "Mechanical part")
    (property "ki_keywords" "MECHANICAL")
    (attr through_hole exclude_from_bom)
    (fp_text reference "MP3" (at -3.76 -2.56) (layer "F.SilkS") hide
        (effects (font (size 0.7 0.7) (thickness 0.15)) (justify left bottom))
    )
    (fp_text value "MP_Pad6mm_Drill3mm" (at -0.153 -4.153) (layer "F.Fab") hide
        (effects (font (size 0.7 0.7) (thickness 0.15)) (justify left bottom))
    )
    (fp_text user "${REFERENCE}" (at -0.178 6.025) (layer "F.Fab") hide
        (effects (font (size 0.7 0.7) (thickness 0.15)) (justify left bottom))
    )
    (fp_text user "Author: Antmicro" (at -0.178 7.225) (layer "F.Fab") hide
        (effects (font (size 0.7 0.7) (thickness 0.15)) (justify left bottom))
    )
    (fp_text user "License: Apache-2.0" (at -0.178 8.425) (layer "F.Fab") hide
        (effects (font (size 0.7 0.7) (thickness 0.15)) (justify left bottom))
    )
    (pad "1" thru_hole circle (at 0 0) (size 6 6) (drill 3.2) (layers "*.Cu" "*.Mask")
      (net 1 "GND") (pintype "passive"))
  )

  (footprint "kria-k26-devboard-footprints:C_0402_1005Metric" (layer "F.Cu")
    (at 123.075 130.3 90)
    (descr "Capacitor SMD 0402")
    (tags "capacitor SMD 0402")
    (property "Author" "Antmicro")
    (property "Dielectric" "X5R")
    (property "License" "Apache-2.0")
    (property "MPN" "GRM155R61H104KE14D")
    (property "Manufacturer" "Murata")
    (property "Sheetfile" "pcie-m2-key-e.kicad_sch")
    (property "Sheetname" "PCIE M2 key E ")
    (property "Val" "100n")
    (property "Voltage" "50V")
    (property "ki_description" " ")
    (attr smd)
    (fp_text reference "C235" (at -1.3 -0.605 90) (layer "F.SilkS")
        (effects (font (size 0.7 0.7) (thickness 0.15)) (justify left bottom))
    )
    (fp_text value "C_100n_0402" (at 0 1.4 90) (layer "F.Fab") hide
        (effects (font (size 0.7 0.7) (thickness 0.15)) (justify left bottom))
    )
    (fp_text user "Author: Antmicro" (at -0.932 4.17 90) (layer "F.Fab") hide
        (effects (font (size 0.7 0.7) (thickness 0.15)) (justify left bottom))
    )
    (fp_text user "${REFERENCE}" (at -0.932 3.168 90) (layer "F.Fab") hide
        (effects (font (size 0.7 0.7) (thickness 0.15)) (justify left bottom))
    )
    (fp_text user "License: Apache-2.0" (at -0.932 5.17 90) (layer "F.Fab") hide
        (effects (font (size 0.7 0.7) (thickness 0.15)) (justify left bottom))
    )
    (fp_rect (start -0.94 -0.47) (end 0.94 0.47)
      (stroke (width 0.05) (type solid)) (fill none) (layer "F.CrtYd"))
    (fp_rect (start -0.499 -0.249) (end 0.499 0.249)
      (stroke (width 0.15) (type solid)) (fill none) (layer "F.Fab"))
    (pad "1" smd roundrect (at -0.484 0 90) (size 0.59 0.64) (layers "F.Cu" "F.Paste" "F.Mask") (roundrect_rratio 0.25)
      (net 15 "PS_3V3") (pintype "passive"))
    (pad "2" smd roundrect (at 0.484 0 90) (size 0.59 0.64) (layers "F.Cu" "F.Paste" "F.Mask") (roundrect_rratio 0.25)
      (net 1 "GND") (pintype "passive"))
  )

  (footprint "kria-k26-devboard-footprints:C_0402_1005Metric" (layer "F.Cu")
    (at 122.9 113.75 -90)
    (descr "Capacitor SMD 0402")
    (tags "capacitor SMD 0402")
    (property "Author" "Antmicro")
    (property "Dielectric" "X5R")
    (property "License" "Apache-2.0")
    (property "MPN" "GRM155R61H104KE14D")
    (property "Manufacturer" "Murata")
    (property "Sheetfile" "pcie-m2-key-e.kicad_sch")
    (property "Sheetname" "PCIE M2 key E ")
    (property "Val" "100n")
    (property "Voltage" "50V")
    (property "ki_description" " ")
    (attr smd)
    (fp_text reference "C236" (at 1.38 0.57 -90) (layer "F.SilkS")
        (effects (font (size 0.7 0.7) (thickness 0.15)) (justify left bottom))
    )
    (fp_text value "C_100n_0402" (at 0 1.4 -90) (layer "F.Fab") hide
        (effects (font (size 0.7 0.7) (thickness 0.15)) (justify left bottom))
    )
    (fp_text user "Author: Antmicro" (at -0.932 4.17 -90) (layer "F.Fab") hide
        (effects (font (size 0.7 0.7) (thickness 0.15)) (justify left bottom))
    )
    (fp_text user "${REFERENCE}" (at -0.932 3.168 -90) (layer "F.Fab") hide
        (effects (font (size 0.7 0.7) (thickness 0.15)) (justify left bottom))
    )
    (fp_text user "License: Apache-2.0" (at -0.932 5.17 -90) (layer "F.Fab") hide
        (effects (font (size 0.7 0.7) (thickness 0.15)) (justify left bottom))
    )
    (fp_rect (start -0.94 -0.47) (end 0.94 0.47)
      (stroke (width 0.05) (type solid)) (fill none) (layer "F.CrtYd"))
    (fp_rect (start -0.499 -0.249) (end 0.499 0.249)
      (stroke (width 0.15) (type solid)) (fill none) (layer "F.Fab"))
    (pad "1" smd roundrect (at -0.484 0 270) (size 0.59 0.64) (layers "F.Cu" "F.Paste" "F.Mask") (roundrect_rratio 0.25)
      (net 15 "PS_3V3") (pintype "passive"))
    (pad "2" smd roundrect (at 0.484 0 270) (size 0.59 0.64) (layers "F.Cu" "F.Paste" "F.Mask") (roundrect_rratio 0.25)
      (net 1 "GND") (pintype "passive"))
  )

  (footprint "kria-k26-devboard-footprints:C_0603_1608Metric" (layer "F.Cu")
    (at 125 130.775)
    (descr "Capacitor SMD 0603")
    (tags "capacitor 0603")
    (property "Author" "Antmicro")
    (property "License" "Apache-2.0")
    (property "MPN" "GRM188R61A106KE69D")
    (property "Manufacturer" "Murata")
    (property "Sheetfile" "pcie-m2-key-e.kicad_sch")
    (property "Sheetname" "PCIE M2 key E ")
    (property "Val" "10u")
    (property "Voltage" "")
    (property "ki_description" " ")
    (attr smd)
    (fp_text reference "C237" (at -1.37 -0.565) (layer "F.SilkS")
        (effects (font (size 0.7 0.7) (thickness 0.15)) (justify left bottom))
    )
    (fp_text value "C_10u_0603" (at 0 1.6) (layer "F.Fab") hide
        (effects (font (size 0.7 0.7) (thickness 0.15)) (justify left bottom))
    )
    (fp_text user "License: Apache-2.0" (at -1.682 5.895) (layer "F.Fab") hide
        (effects (font (size 0.7 0.7) (thickness 0.15)) (justify left bottom))
    )
    (fp_text user "Author: Antmicro" (at -1.682 4.894) (layer "F.Fab") hide
        (effects (font (size 0.7 0.7) (thickness 0.15)) (justify left bottom))
    )
    (fp_text user "${REFERENCE}" (at -1.682 3.895) (layer "F.Fab") hide
        (effects (font (size 0.7 0.7) (thickness 0.15)) (justify left bottom))
    )
    (fp_line (start -0.3 -0.3) (end 0.3 -0.3)
      (stroke (width 0.15) (type solid)) (layer "F.SilkS"))
    (fp_line (start -0.3 0.3) (end 0.3 0.3)
      (stroke (width 0.15) (type solid)) (layer "F.SilkS"))
    (fp_rect (start -1.24 -0.7) (end 1.24 0.7)
      (stroke (width 0.05) (type solid)) (fill none) (layer "F.CrtYd"))
    (fp_rect (start -0.8 -0.4) (end 0.8 0.4)
      (stroke (width 0.15) (type solid)) (fill none) (layer "F.Fab"))
    (pad "1" smd roundrect (at -0.7 0) (size 0.6 0.8) (layers "F.Cu" "F.Paste" "F.Mask") (roundrect_rratio 0.2)
      (net 15 "PS_3V3") (pintype "passive"))
    (pad "2" smd roundrect (at 0.7 0) (size 0.6 0.8) (layers "F.Cu" "F.Paste" "F.Mask") (roundrect_rratio 0.2)
      (net 1 "GND") (pintype "passive"))
  )

  (footprint "kria-k26-devboard-footprints:C_0603_1608Metric" (layer "F.Cu")
    (at 125.05 113.2)
    (descr "Capacitor SMD 0603")
    (tags "capacitor 0603")
    (property "Author" "Antmicro")
    (property "License" "Apache-2.0")
    (property "MPN" "GRM188R61A106KE69D")
    (property "Manufacturer" "Murata")
    (property "Sheetfile" "pcie-m2-key-e.kicad_sch")
    (property "Sheetname" "PCIE M2 key E ")
    (property "Val" "10u")
    (property "Voltage" "")
    (property "ki_description" " ")
    (attr smd)
    (fp_text reference "C238" (at -1.63 -0.59) (layer "F.SilkS")
        (effects (font (size 0.7 0.7) (thickness 0.15)) (justify left bottom))
    )
    (fp_text value "C_10u_0603" (at 0 1.6) (layer "F.Fab") hide
        (effects (font (size 0.7 0.7) (thickness 0.15)) (justify left bottom))
    )
    (fp_text user "License: Apache-2.0" (at -1.682 5.895) (layer "F.Fab") hide
        (effects (font (size 0.7 0.7) (thickness 0.15)) (justify left bottom))
    )
    (fp_text user "${REFERENCE}" (at -1.682 3.895) (layer "F.Fab") hide
        (effects (font (size 0.7 0.7) (thickness 0.15)) (justify left bottom))
    )
    (fp_text user "Author: Antmicro" (at -1.682 4.894) (layer "F.Fab") hide
        (effects (font (size 0.7 0.7) (thickness 0.15)) (justify left bottom))
    )
    (fp_line (start -0.3 -0.3) (end 0.3 -0.3)
      (stroke (width 0.15) (type solid)) (layer "F.SilkS"))
    (fp_line (start -0.3 0.3) (end 0.3 0.3)
      (stroke (width 0.15) (type solid)) (layer "F.SilkS"))
    (fp_rect (start -1.24 -0.7) (end 1.24 0.7)
      (stroke (width 0.05) (type solid)) (fill none) (layer "F.CrtYd"))
    (fp_rect (start -0.8 -0.4) (end 0.8 0.4)
      (stroke (width 0.15) (type solid)) (fill none) (layer "F.Fab"))
    (pad "1" smd roundrect (at -0.7 0) (size 0.6 0.8) (layers "F.Cu" "F.Paste" "F.Mask") (roundrect_rratio 0.2)
      (net 15 "PS_3V3") (pintype "passive"))
    (pad "2" smd roundrect (at 0.7 0) (size 0.6 0.8) (layers "F.Cu" "F.Paste" "F.Mask") (roundrect_rratio 0.2)
      (net 1 "GND") (pintype "passive"))
  )

  (footprint "kria-k26-devboard-footprints:Conn_Plug_Samtec_ADM6_4x60_ADM6-60-01.5-L-4-2-A-TR" (layer "F.Cu")
    (at 158.177 117.6205 -90)
    (property "Author" "Antmicro")
    (property "DNP" "DNP")
    (property "License" "Apache-2.0")
    (property "MPN" "ADM6-60-01.5-L-4-2-A-TR")
    (property "Manufacturer" "Samtec")
    (property "Sheetfile" "k26_som.kicad_sch")
    (property "Sheetname" "Xilinx K26 SOM")
    (property "dnp" "")
    (property "exclude_from_bom" "")
    (property "ki_description" "Board to Board & Mezzanine Connectors 0.635 mm AcceleRate HD High-Density 4-Row Header 60P")
    (attr exclude_from_pos_files exclude_from_bom)
    (fp_text reference "J_SOM240_2" (at -14.0505 -3.623 90) (layer "F.SilkS")
        (effects (font (size 0.7 0.7) (thickness 0.15)) (justify right bottom))
    )
    (fp_text value "ADM6-60-01.5-L-4-2-A-TR" (at 0 3.7 90) (layer "F.Fab") hide
        (effects (font (size 0.7 0.7) (thickness 0.15)) (justify right bottom))
    )
    (fp_text user "License: Apache-2.0" (at -21.66 7.5 90) (layer "F.Fab") hide
        (effects (font (size 0.7 0.7) (thickness 0.15)) (justify right bottom))
    )
    (fp_text user "${REFERENCE}" (at -21.66 5.1 90) (layer "F.Fab") hide
        (effects (font (size 0.7 0.7) (thickness 0.15)) (justify right bottom))
    )
    (fp_text user "Author: Antmicro" (at -21.66 6.3 90) (layer "F.Fab") hide
        (effects (font (size 0.7 0.7) (thickness 0.15)) (justify right bottom))
    )
    (fp_line (start -21.5 -1.7) (end -20.6 -2.6)
      (stroke (width 0.15) (type solid)) (layer "F.SilkS"))
    (fp_line (start -21.5 2.592) (end -21.5 -1.7)
      (stroke (width 0.15) (type solid)) (layer "F.SilkS"))
    (fp_line (start -20.6 -2.6) (end 20.6 -2.6)
      (stroke (width 0.15) (type solid)) (layer "F.SilkS"))
    (fp_line (start 20.6 -2.6) (end 21.5 -1.7)
      (stroke (width 0.15) (type solid)) (layer "F.SilkS"))
    (fp_line (start 21.5 -1.7) (end 21.5 2.592)
      (stroke (width 0.15) (type solid)) (layer "F.SilkS"))
    (fp_line (start 21.5 2.592) (end -21.5 2.592)
      (stroke (width 0.15) (type solid)) (layer "F.SilkS"))
    (fp_circle (center 18.75 -2.9) (end 18.8 -2.9)
      (stroke (width 0.15) (type solid)) (fill solid) (layer "F.SilkS"))
    (fp_line (start -21.66 -1.92) (end -20.83 -2.75)
      (stroke (width 0.05) (type solid)) (layer "F.CrtYd"))
    (fp_line (start -21.66 2.74) (end -21.66 -1.92)
      (stroke (width 0.05) (type solid)) (layer "F.CrtYd"))
    (fp_line (start -20.83 -2.75) (end 20.82 -2.75)
      (stroke (width 0.05) (type solid)) (layer "F.CrtYd"))
    (fp_line (start 20.82 -2.75) (end 21.65 -1.92)
      (stroke (width 0.05) (type solid)) (layer "F.CrtYd"))
    (fp_line (start 21.65 -1.92) (end 21.65 2.74)
      (stroke (width 0.05) (type solid)) (layer "F.CrtYd"))
    (fp_line (start 21.65 2.74) (end -21.66 2.74)
      (stroke (width 0.05) (type solid)) (layer "F.CrtYd"))
    (fp_line (start -21.41 2.499) (end -21.4 -1.7)
      (stroke (width 0.15) (type solid)) (layer "F.Fab"))
    (fp_line (start -21.4 -1.7) (end -20.6 -2.5)
      (stroke (width 0.15) (type solid)) (layer "F.Fab"))
    (fp_line (start -20.6 -2.5) (end 20.6 -2.5)
      (stroke (width 0.15) (type solid)) (layer "F.Fab"))
    (fp_line (start 20.6 -2.5) (end 21.409 -1.7)
      (stroke (width 0.15) (type solid)) (layer "F.Fab"))
    (fp_line (start 21.409 -1.7) (end 21.409 2.499)
      (stroke (width 0.15) (type solid)) (layer "F.Fab"))
    (fp_line (start 21.409 2.499) (end -21.41 2.499)
      (stroke (width 0.15) (type solid)) (layer "F.Fab"))
    (pad "" np_thru_hole circle (at -20.136 -1.27 270) (size 0.95 0.95) (drill 0.95) (layers "*.Cu" "*.Mask"))
    (pad "" np_thru_hole circle (at 20.135 0 270) (size 0.95 0.95) (drill 0.95) (layers "*.Cu" "*.Mask"))
    (pad "A01" smd circle (at 18.732 -1.75 270) (size 0.356 0.356) (layers "F.Cu" "F.Paste" "F.Mask")
      (net 1 "GND") (pinfunction "A01") (pintype "passive"))
    (pad "A02" smd circle (at 18.097 -1.75 270) (size 0.356 0.356) (layers "F.Cu" "F.Paste" "F.Mask")
      (net 1 "GND") (pinfunction "A02") (pintype "passive"))
    (pad "A03" smd circle (at 17.462 -1.75 270) (size 0.356 0.356) (layers "F.Cu" "F.Paste" "F.Mask")
      (net 478 "/Xilinx K26 SOM/GTH_DP3_M2C_P") (pinfunction "A03") (pintype "passive"))
    (pad "A04" smd circle (at 16.827 -1.75 270) (size 0.356 0.356) (layers "F.Cu" "F.Paste" "F.Mask")
      (net 479 "/Xilinx K26 SOM/GTH_DP3_M2C_N") (pinfunction "A04") (pintype "passive"))
    (pad "A05" smd circle (at 16.192 -1.75 270) (size 0.356 0.356) (layers "F.Cu" "F.Paste" "F.Mask")
      (net 1 "GND") (pinfunction "A05") (pintype "passive"))
    (pad "A06" smd circle (at 15.557 -1.75 270) (size 0.356 0.356) (layers "F.Cu" "F.Paste" "F.Mask")
      (net 1 "GND") (pinfunction "A06") (pintype "passive"))
    (pad "A07" smd circle (at 14.922 -1.75 270) (size 0.356 0.356) (layers "F.Cu" "F.Paste" "F.Mask")
      (net 480 "/Xilinx K26 SOM/GTH_REFCLK1_C2M_P") (pinfunction "A07") (pintype "passive"))
    (pad "A08" smd circle (at 14.287 -1.75 270) (size 0.356 0.356) (layers "F.Cu" "F.Paste" "F.Mask")
      (net 481 "/Xilinx K26 SOM/GTH_REFCLK1_C2M_N") (pinfunction "A08") (pintype "passive"))
    (pad "A09" smd circle (at 13.652 -1.75 270) (size 0.356 0.356) (layers "F.Cu" "F.Paste" "F.Mask")
      (net 1 "GND") (pinfunction "A09") (pintype "passive"))
    (pad "A10" smd circle (at 13.017 -1.75 270) (size 0.356 0.356) (layers "F.Cu" "F.Paste" "F.Mask")
      (net 1 "GND") (pinfunction "A10") (pintype "passive"))
    (pad "A11" smd circle (at 12.382 -1.75 270) (size 0.356 0.356) (layers "F.Cu" "F.Paste" "F.Mask")
      (net 482 "/Xilinx K26 SOM/HPB15_CC_P") (pinfunction "A11") (pintype "passive"))
    (pad "A12" smd circle (at 11.747 -1.75 270) (size 0.356 0.356) (layers "F.Cu" "F.Paste" "F.Mask")
      (net 483 "/Xilinx K26 SOM/HPB_15_CC_N") (pinfunction "A12") (pintype "passive"))
    (pad "A13" smd circle (at 11.112 -1.75 270) (size 0.356 0.356) (layers "F.Cu" "F.Paste" "F.Mask")
      (net 1 "GND") (pinfunction "A13") (pintype "passive"))
    (pad "A14" smd circle (at 10.477 -1.75 270) (size 0.356 0.356) (layers "F.Cu" "F.Paste" "F.Mask")
      (net 484 "/Xilinx K26 SOM/HPB08_P") (pinfunction "A14") (pintype "passive"))
    (pad "A15" smd circle (at 9.842 -1.75 270) (size 0.356 0.356) (layers "F.Cu" "F.Paste" "F.Mask")
      (net 485 "/Xilinx K26 SOM/HPB08_N") (pinfunction "A15") (pintype "passive"))
    (pad "A16" smd circle (at 9.207 -1.75 270) (size 0.356 0.356) (layers "F.Cu" "F.Paste" "F.Mask")
      (net 1 "GND") (pinfunction "A16") (pintype "passive"))
    (pad "A17" smd circle (at 8.572 -1.75 270) (size 0.356 0.356) (layers "F.Cu" "F.Paste" "F.Mask")
      (net 486 "/Xilinx K26 SOM/HPB12_P") (pinfunction "A17") (pintype "passive"))
    (pad "A18" smd circle (at 7.937 -1.75 270) (size 0.356 0.356) (layers "F.Cu" "F.Paste" "F.Mask")
      (net 487 "/Xilinx K26 SOM/HPB12_N") (pinfunction "A18") (pintype "passive"))
    (pad "A19" smd circle (at 7.302 -1.75 270) (size 0.356 0.356) (layers "F.Cu" "F.Paste" "F.Mask")
      (net 1 "GND") (pinfunction "A19") (pintype "passive"))
    (pad "A20" smd circle (at 6.667 -1.75 270) (size 0.356 0.356) (layers "F.Cu" "F.Paste" "F.Mask")
      (net 488 "/Xilinx K26 SOM/HPB06_P") (pinfunction "A20") (pintype "passive"))
    (pad "A21" smd circle (at 6.032 -1.75 270) (size 0.356 0.356) (layers "F.Cu" "F.Paste" "F.Mask")
      (net 489 "/Xilinx K26 SOM/HPB06_N") (pinfunction "A21") (pintype "passive"))
    (pad "A22" smd circle (at 5.397 -1.75 270) (size 0.356 0.356) (layers "F.Cu" "F.Paste" "F.Mask")
      (net 1 "GND") (pinfunction "A22") (pintype "passive"))
    (pad "A23" smd circle (at 4.762 -1.75 270) (size 0.356 0.356) (layers "F.Cu" "F.Paste" "F.Mask")
      (net 490 "/Xilinx K26 SOM/HPB16_P") (pinfunction "A23") (pintype "passive"))
    (pad "A24" smd circle (at 4.127 -1.75 270) (size 0.356 0.356) (layers "F.Cu" "F.Paste" "F.Mask")
      (net 491 "/Xilinx K26 SOM/HPB16_N") (pinfunction "A24") (pintype "passive"))
    (pad "A25" smd circle (at 3.492 -1.75 270) (size 0.356 0.356) (layers "F.Cu" "F.Paste" "F.Mask")
      (net 1 "GND") (pinfunction "A25") (pintype "passive"))
    (pad "A26" smd circle (at 2.857 -1.75 270) (size 0.356 0.356) (layers "F.Cu" "F.Paste" "F.Mask")
      (net 492 "/Xilinx K26 SOM/HPB19_P") (pinfunction "A26") (pintype "passive"))
    (pad "A27" smd circle (at 2.222 -1.75 270) (size 0.356 0.356) (layers "F.Cu" "F.Paste" "F.Mask")
      (net 493 "/Xilinx K26 SOM/HPB19_N") (pinfunction "A27") (pintype "passive"))
    (pad "A28" smd circle (at 1.587 -1.75 270) (size 0.356 0.356) (layers "F.Cu" "F.Paste" "F.Mask")
      (net 1 "GND") (pinfunction "A28") (pintype "passive"))
    (pad "A29" smd circle (at 0.952 -1.75 270) (size 0.356 0.356) (layers "F.Cu" "F.Paste" "F.Mask")
      (net 494 "/Xilinx K26 SOM/HPC08_P") (pinfunction "A29") (pintype "passive"))
    (pad "A30" smd circle (at 0.317 -1.75 270) (size 0.356 0.356) (layers "F.Cu" "F.Paste" "F.Mask")
      (net 495 "/Xilinx K26 SOM/HPC08_N") (pinfunction "A30") (pintype "passive"))
    (pad "A31" smd circle (at -0.318 -1.75 270) (size 0.356 0.356) (layers "F.Cu" "F.Paste" "F.Mask")
      (net 1 "GND") (pinfunction "A31") (pintype "passive"))
    (pad "A32" smd circle (at -0.953 -1.75 270) (size 0.356 0.356) (layers "F.Cu" "F.Paste" "F.Mask")
      (net 496 "/Xilinx K26 SOM/HPC19_P") (pinfunction "A32") (pintype "passive"))
    (pad "A33" smd circle (at -1.588 -1.75 270) (size 0.356 0.356) (layers "F.Cu" "F.Paste" "F.Mask")
      (net 497 "/Xilinx K26 SOM/HPC19_N") (pinfunction "A33") (pintype "passive"))
    (pad "A34" smd circle (at -2.223 -1.75 270) (size 0.356 0.356) (layers "F.Cu" "F.Paste" "F.Mask")
      (net 1 "GND") (pinfunction "A34") (pintype "passive"))
    (pad "A35" smd circle (at -2.858 -1.75 270) (size 0.356 0.356) (layers "F.Cu" "F.Paste" "F.Mask")
      (net 498 "/Xilinx K26 SOM/HPC14_P") (pinfunction "A35") (pintype "passive"))
    (pad "A36" smd circle (at -3.493 -1.75 270) (size 0.356 0.356) (layers "F.Cu" "F.Paste" "F.Mask")
      (net 499 "/Xilinx K26 SOM/HPC14_N") (pinfunction "A36") (pintype "passive"))
    (pad "A37" smd circle (at -4.128 -1.75 270) (size 0.356 0.356) (layers "F.Cu" "F.Paste" "F.Mask")
      (net 1 "GND") (pinfunction "A37") (pintype "passive"))
    (pad "A38" smd circle (at -4.763 -1.75 270) (size 0.356 0.356) (layers "F.Cu" "F.Paste" "F.Mask")
      (net 500 "/Xilinx K26 SOM/HPC15_CC_P") (pinfunction "A38") (pintype "passive"))
    (pad "A39" smd circle (at -5.398 -1.75 270) (size 0.356 0.356) (layers "F.Cu" "F.Paste" "F.Mask")
      (net 501 "/Xilinx K26 SOM/HPC15_CC_N") (pinfunction "A39") (pintype "passive"))
    (pad "A40" smd circle (at -6.033 -1.75 270) (size 0.356 0.356) (layers "F.Cu" "F.Paste" "F.Mask")
      (net 1 "GND") (pinfunction "A40") (pintype "passive"))
    (pad "A41" smd circle (at -6.668 -1.75 270) (size 0.356 0.356) (layers "F.Cu" "F.Paste" "F.Mask")
      (net 502 "/Xilinx K26 SOM/HPC03_P") (pinfunction "A41") (pintype "passive"))
    (pad "A42" smd circle (at -7.303 -1.75 270) (size 0.356 0.356) (layers "F.Cu" "F.Paste" "F.Mask")
      (net 503 "/Xilinx K26 SOM/HPC03_N") (pinfunction "A42") (pintype "passive"))
    (pad "A43" smd circle (at -7.938 -1.75 270) (size 0.356 0.356) (layers "F.Cu" "F.Paste" "F.Mask")
      (net 1 "GND") (pinfunction "A43") (pintype "passive"))
    (pad "A44" smd circle (at -8.573 -1.75 270) (size 0.356 0.356) (layers "F.Cu" "F.Paste" "F.Mask")
      (net 504 "/Xilinx K26 SOM/VCCO_HPB_1") (pinfunction "A44") (pintype "passive"))
    (pad "A45" smd circle (at -9.208 -1.75 270) (size 0.356 0.356) (layers "F.Cu" "F.Paste" "F.Mask")
      (net 1 "GND") (pinfunction "A45") (pintype "passive"))
    (pad "A46" smd circle (at -9.843 -1.75 270) (size 0.356 0.356) (layers "F.Cu" "F.Paste" "F.Mask")
      (net 505 "/Xilinx K26 SOM/HDB18") (pinfunction "A46") (pintype "passive"))
    (pad "A47" smd circle (at -10.478 -1.75 270) (size 0.356 0.356) (layers "F.Cu" "F.Paste" "F.Mask")
      (net 506 "/Xilinx K26 SOM/HDB19") (pinfunction "A47") (pintype "passive"))
    (pad "A48" smd circle (at -11.113 -1.75 270) (size 0.356 0.356) (layers "F.Cu" "F.Paste" "F.Mask")
      (net 507 "/Xilinx K26 SOM/HDB20") (pinfunction "A48") (pintype "passive"))
    (pad "A49" smd circle (at -11.748 -1.75 270) (size 0.356 0.356) (layers "F.Cu" "F.Paste" "F.Mask")
      (net 1 "GND") (pinfunction "A49") (pintype "passive"))
    (pad "A50" smd circle (at -12.383 -1.75 270) (size 0.356 0.356) (layers "F.Cu" "F.Paste" "F.Mask")
      (net 508 "/Xilinx K26 SOM/HDB21") (pinfunction "A50") (pintype "passive"))
    (pad "A51" smd circle (at -13.018 -1.75 270) (size 0.356 0.356) (layers "F.Cu" "F.Paste" "F.Mask")
      (net 509 "/Xilinx K26 SOM/HDB22") (pinfunction "A51") (pintype "passive"))
    (pad "A52" smd circle (at -13.653 -1.75 270) (size 0.356 0.356) (layers "F.Cu" "F.Paste" "F.Mask")
      (net 510 "/Xilinx K26 SOM/HDB23") (pinfunction "A52") (pintype "passive"))
    (pad "A53" smd circle (at -14.288 -1.75 270) (size 0.356 0.356) (layers "F.Cu" "F.Paste" "F.Mask")
      (net 1 "GND") (pinfunction "A53") (pintype "passive"))
    (pad "A54" smd circle (at -14.923 -1.75 270) (size 0.356 0.356) (layers "F.Cu" "F.Paste" "F.Mask")
      (net 511 "/Xilinx K26 SOM/HDC18") (pinfunction "A54") (pintype "passive"))
    (pad "A55" smd circle (at -15.558 -1.75 270) (size 0.356 0.356) (layers "F.Cu" "F.Paste" "F.Mask")
      (net 512 "/Xilinx K26 SOM/HDC19") (pinfunction "A55") (pintype "passive"))
    (pad "A56" smd circle (at -16.193 -1.75 270) (size 0.356 0.356) (layers "F.Cu" "F.Paste" "F.Mask")
      (net 513 "/Xilinx K26 SOM/HDC20") (pinfunction "A56") (pintype "passive"))
    (pad "A57" smd circle (at -16.828 -1.75 270) (size 0.356 0.356) (layers "F.Cu" "F.Paste" "F.Mask")
      (net 1 "GND") (pinfunction "A57") (pintype "passive"))
    (pad "A58" smd circle (at -17.463 -1.75 270) (size 0.356 0.356) (layers "F.Cu" "F.Paste" "F.Mask")
      (net 514 "/Xilinx K26 SOM/HDC21") (pinfunction "A58") (pintype "passive"))
    (pad "A59" smd circle (at -18.098 -1.75 270) (size 0.356 0.356) (layers "F.Cu" "F.Paste" "F.Mask")
      (net 515 "/Xilinx K26 SOM/HDC22") (pinfunction "A59") (pintype "passive"))
    (pad "A60" smd circle (at -18.733 -1.75 270) (size 0.356 0.356) (layers "F.Cu" "F.Paste" "F.Mask")
      (net 516 "/Xilinx K26 SOM/HDC23") (pinfunction "A60") (pintype "passive"))
    (pad "B01" smd circle (at 18.732 -0.791 270) (size 0.356 0.356) (layers "F.Cu" "F.Paste" "F.Mask")
      (net 517 "/Xilinx K26 SOM/GTH_DP2_C2M_P") (pinfunction "B01") (pintype "passive"))
    (pad "B02" smd circle (at 18.097 -0.791 270) (size 0.356 0.356) (layers "F.Cu" "F.Paste" "F.Mask")
      (net 518 "/Xilinx K26 SOM/GTH_DP2_C2M_N") (pinfunction "B02") (pintype "passive"))
    (pad "B03" smd circle (at 17.462 -0.791 270) (size 0.356 0.356) (layers "F.Cu" "F.Paste" "F.Mask")
      (net 1 "GND") (pinfunction "B03") (pintype "passive"))
    (pad "B04" smd circle (at 16.827 -0.791 270) (size 0.356 0.356) (layers "F.Cu" "F.Paste" "F.Mask")
      (net 1 "GND") (pinfunction "B04") (pintype "passive"))
    (pad "B05" smd circle (at 16.192 -0.791 270) (size 0.356 0.356) (layers "F.Cu" "F.Paste" "F.Mask")
      (net 519 "/Xilinx K26 SOM/GTH_DP2_M2C_P") (pinfunction "B05") (pintype "passive"))
    (pad "B06" smd circle (at 15.557 -0.791 270) (size 0.356 0.356) (layers "F.Cu" "F.Paste" "F.Mask")
      (net 520 "/Xilinx K26 SOM/GTH_DP2_M2C_N") (pinfunction "B06") (pintype "passive"))
    (pad "B07" smd circle (at 14.922 -0.791 270) (size 0.356 0.356) (layers "F.Cu" "F.Paste" "F.Mask")
      (net 1 "GND") (pinfunction "B07") (pintype "passive"))
    (pad "B08" smd circle (at 14.287 -0.791 270) (size 0.356 0.356) (layers "F.Cu" "F.Paste" "F.Mask")
      (net 1 "GND") (pinfunction "B08") (pintype "passive"))
    (pad "B09" smd circle (at 13.652 -0.791 270) (size 0.356 0.356) (layers "F.Cu" "F.Paste" "F.Mask")
      (net 521 "/Xilinx K26 SOM/GTH_DP0_C2M_P") (pinfunction "B09") (pintype "passive"))
    (pad "B10" smd circle (at 13.017 -0.791 270) (size 0.356 0.356) (layers "F.Cu" "F.Paste" "F.Mask")
      (net 522 "/Xilinx K26 SOM/GTH_DP0_C2M_N") (pinfunction "B10") (pintype "passive"))
    (pad "B11" smd circle (at 12.382 -0.791 270) (size 0.356 0.356) (layers "F.Cu" "F.Paste" "F.Mask")
      (net 1 "GND") (pinfunction "B11") (pintype "passive"))
    (pad "B12" smd circle (at 11.747 -0.791 270) (size 0.356 0.356) (layers "F.Cu" "F.Paste" "F.Mask")
      (net 523 "/Xilinx K26 SOM/HPB10_CC_P") (pinfunction "B12") (pintype "passive"))
    (pad "B13" smd circle (at 11.112 -0.791 270) (size 0.356 0.356) (layers "F.Cu" "F.Paste" "F.Mask")
      (net 524 "/Xilinx K26 SOM/HPB10_CC_N") (pinfunction "B13") (pintype "passive"))
    (pad "B14" smd circle (at 10.477 -0.791 270) (size 0.356 0.356) (layers "F.Cu" "F.Paste" "F.Mask")
      (net 1 "GND") (pinfunction "B14") (pintype "passive"))
    (pad "B15" smd circle (at 9.842 -0.791 270) (size 0.356 0.356) (layers "F.Cu" "F.Paste" "F.Mask")
      (net 525 "/Xilinx K26 SOM/HPB07_P") (pinfunction "B15") (pintype "passive"))
    (pad "B16" smd circle (at 9.207 -0.791 270) (size 0.356 0.356) (layers "F.Cu" "F.Paste" "F.Mask")
      (net 526 "/Xilinx K26 SOM/HPB07_N") (pinfunction "B16") (pintype "passive"))
    (pad "B17" smd circle (at 8.572 -0.791 270) (size 0.356 0.356) (layers "F.Cu" "F.Paste" "F.Mask")
      (net 1 "GND") (pinfunction "B17") (pintype "passive"))
    (pad "B18" smd circle (at 7.937 -0.791 270) (size 0.356 0.356) (layers "F.Cu" "F.Paste" "F.Mask")
      (net 527 "/Xilinx K26 SOM/HPB05_CC_P") (pinfunction "B18") (pintype "passive"))
    (pad "B19" smd circle (at 7.302 -0.791 270) (size 0.356 0.356) (layers "F.Cu" "F.Paste" "F.Mask")
      (net 528 "/Xilinx K26 SOM/HPB05_CC_N") (pinfunction "B19") (pintype "passive"))
    (pad "B20" smd circle (at 6.667 -0.791 270) (size 0.356 0.356) (layers "F.Cu" "F.Paste" "F.Mask")
      (net 1 "GND") (pinfunction "B20") (pintype "passive"))
    (pad "B21" smd circle (at 6.032 -0.791 270) (size 0.356 0.356) (layers "F.Cu" "F.Paste" "F.Mask")
      (net 529 "/Xilinx K26 SOM/HPB11_P") (pinfunction "B21") (pintype "passive"))
    (pad "B22" smd circle (at 5.397 -0.791 270) (size 0.356 0.356) (layers "F.Cu" "F.Paste" "F.Mask")
      (net 530 "/Xilinx K26 SOM/HPB11_N") (pinfunction "B22") (pintype "passive"))
    (pad "B23" smd circle (at 4.762 -0.791 270) (size 0.356 0.356) (layers "F.Cu" "F.Paste" "F.Mask")
      (net 1 "GND") (pinfunction "B23") (pintype "passive"))
    (pad "B24" smd circle (at 4.127 -0.791 270) (size 0.356 0.356) (layers "F.Cu" "F.Paste" "F.Mask")
      (net 531 "/Xilinx K26 SOM/HPB03_P") (pinfunction "B24") (pintype "passive"))
    (pad "B25" smd circle (at 3.492 -0.791 270) (size 0.356 0.356) (layers "F.Cu" "F.Paste" "F.Mask")
      (net 532 "/Xilinx K26 SOM/HPB03_N") (pinfunction "B25") (pintype "passive"))
    (pad "B26" smd circle (at 2.857 -0.791 270) (size 0.356 0.356) (layers "F.Cu" "F.Paste" "F.Mask")
      (net 1 "GND") (pinfunction "B26") (pintype "passive"))
    (pad "B27" smd circle (at 2.222 -0.791 270) (size 0.356 0.356) (layers "F.Cu" "F.Paste" "F.Mask")
      (net 533 "/Xilinx K26 SOM/HPC06_P") (pinfunction "B27") (pintype "passive"))
    (pad "B28" smd circle (at 1.587 -0.791 270) (size 0.356 0.356) (layers "F.Cu" "F.Paste" "F.Mask")
      (net 534 "/Xilinx K26 SOM/HPC06_N") (pinfunction "B28") (pintype "passive"))
    (pad "B29" smd circle (at 0.952 -0.791 270) (size 0.356 0.356) (layers "F.Cu" "F.Paste" "F.Mask")
      (net 1 "GND") (pinfunction "B29") (pintype "passive"))
    (pad "B30" smd circle (at 0.317 -0.791 270) (size 0.356 0.356) (layers "F.Cu" "F.Paste" "F.Mask")
      (net 535 "/Xilinx K26 SOM/HPC13_P") (pinfunction "B30") (pintype "passive"))
    (pad "B31" smd circle (at -0.318 -0.791 270) (size 0.356 0.356) (layers "F.Cu" "F.Paste" "F.Mask")
      (net 536 "/Xilinx K26 SOM/HPC13_N") (pinfunction "B31") (pintype "passive"))
    (pad "B32" smd circle (at -0.953 -0.791 270) (size 0.356 0.356) (layers "F.Cu" "F.Paste" "F.Mask")
      (net 1 "GND") (pinfunction "B32") (pintype "passive"))
    (pad "B33" smd circle (at -1.588 -0.791 270) (size 0.356 0.356) (layers "F.Cu" "F.Paste" "F.Mask")
      (net 537 "/Xilinx K26 SOM/HPC16_P") (pinfunction "B33") (pintype "passive"))
    (pad "B34" smd circle (at -2.223 -0.791 270) (size 0.356 0.356) (layers "F.Cu" "F.Paste" "F.Mask")
      (net 538 "/Xilinx K26 SOM/HPC16_N") (pinfunction "B34") (pintype "passive"))
    (pad "B35" smd circle (at -2.858 -0.791 270) (size 0.356 0.356) (layers "F.Cu" "F.Paste" "F.Mask")
      (net 1 "GND") (pinfunction "B35") (pintype "passive"))
    (pad "B36" smd circle (at -3.493 -0.791 270) (size 0.356 0.356) (layers "F.Cu" "F.Paste" "F.Mask")
      (net 539 "/Xilinx K26 SOM/HPC07_P") (pinfunction "B36") (pintype "passive"))
    (pad "B37" smd circle (at -4.128 -0.791 270) (size 0.356 0.356) (layers "F.Cu" "F.Paste" "F.Mask")
      (net 540 "/Xilinx K26 SOM/HPC07_N") (pinfunction "B37") (pintype "passive"))
    (pad "B38" smd circle (at -4.763 -0.791 270) (size 0.356 0.356) (layers "F.Cu" "F.Paste" "F.Mask")
      (net 1 "GND") (pinfunction "B38") (pintype "passive"))
    (pad "B39" smd circle (at -5.398 -0.791 270) (size 0.356 0.356) (layers "F.Cu" "F.Paste" "F.Mask")
      (net 541 "/Xilinx K26 SOM/HPC18_P") (pinfunction "B39") (pintype "passive"))
    (pad "B40" smd circle (at -6.033 -0.791 270) (size 0.356 0.356) (layers "F.Cu" "F.Paste" "F.Mask")
      (net 542 "/Xilinx K26 SOM/HPC18_N") (pinfunction "B40") (pintype "passive"))
    (pad "B41" smd circle (at -6.668 -0.791 270) (size 0.356 0.356) (layers "F.Cu" "F.Paste" "F.Mask")
      (net 1 "GND") (pinfunction "B41") (pintype "passive"))
    (pad "B42" smd circle (at -7.303 -0.791 270) (size 0.356 0.356) (layers "F.Cu" "F.Paste" "F.Mask")
      (net 543 "/Xilinx K26 SOM/VCCO_HPB_2") (pinfunction "B42") (pintype "passive"))
    (pad "B43" smd circle (at -7.938 -0.791 270) (size 0.356 0.356) (layers "F.Cu" "F.Paste" "F.Mask")
      (net 1 "GND") (pinfunction "B43") (pintype "passive"))
    (pad "B44" smd circle (at -8.573 -0.791 270) (size 0.356 0.356) (layers "F.Cu" "F.Paste" "F.Mask")
      (net 544 "/Xilinx K26 SOM/HDB12") (pinfunction "B44") (pintype "passive"))
    (pad "B45" smd circle (at -9.208 -0.791 270) (size 0.356 0.356) (layers "F.Cu" "F.Paste" "F.Mask")
      (net 545 "/Xilinx K26 SOM/HDB13") (pinfunction "B45") (pintype "passive"))
    (pad "B46" smd circle (at -9.843 -0.791 270) (size 0.356 0.356) (layers "F.Cu" "F.Paste" "F.Mask")
      (net 546 "/Xilinx K26 SOM/HDB14") (pinfunction "B46") (pintype "passive"))
    (pad "B47" smd circle (at -10.478 -0.791 270) (size 0.356 0.356) (layers "F.Cu" "F.Paste" "F.Mask")
      (net 1 "GND") (pinfunction "B47") (pintype "passive"))
    (pad "B48" smd circle (at -11.113 -0.791 270) (size 0.356 0.356) (layers "F.Cu" "F.Paste" "F.Mask")
      (net 547 "/Xilinx K26 SOM/HDB15") (pinfunction "B48") (pintype "passive"))
    (pad "B49" smd circle (at -11.748 -0.791 270) (size 0.356 0.356) (layers "F.Cu" "F.Paste" "F.Mask")
      (net 548 "/Xilinx K26 SOM/HDB16_CC") (pinfunction "B49") (pintype "passive"))
    (pad "B50" smd circle (at -12.383 -0.791 270) (size 0.356 0.356) (layers "F.Cu" "F.Paste" "F.Mask")
      (net 549 "/Xilinx K26 SOM/HDB17") (pinfunction "B50") (pintype "passive"))
    (pad "B51" smd circle (at -13.018 -0.791 270) (size 0.356 0.356) (layers "F.Cu" "F.Paste" "F.Mask")
      (net 1 "GND") (pinfunction "B51") (pintype "passive"))
    (pad "B52" smd circle (at -13.653 -0.791 270) (size 0.356 0.356) (layers "F.Cu" "F.Paste" "F.Mask")
      (net 550 "/Xilinx K26 SOM/HDC12") (pinfunction "B52") (pintype "passive"))
    (pad "B53" smd circle (at -14.288 -0.791 270) (size 0.356 0.356) (layers "F.Cu" "F.Paste" "F.Mask")
      (net 551 "/Xilinx K26 SOM/HDC13") (pinfunction "B53") (pintype "passive"))
    (pad "B54" smd circle (at -14.923 -0.791 270) (size 0.356 0.356) (layers "F.Cu" "F.Paste" "F.Mask")
      (net 552 "/Xilinx K26 SOM/HDC14") (pinfunction "B54") (pintype "passive"))
    (pad "B55" smd circle (at -15.558 -0.791 270) (size 0.356 0.356) (layers "F.Cu" "F.Paste" "F.Mask")
      (net 1 "GND") (pinfunction "B55") (pintype "passive"))
    (pad "B56" smd circle (at -16.193 -0.791 270) (size 0.356 0.356) (layers "F.Cu" "F.Paste" "F.Mask")
      (net 553 "/Xilinx K26 SOM/HDC15") (pinfunction "B56") (pintype "passive"))
    (pad "B57" smd circle (at -16.828 -0.791 270) (size 0.356 0.356) (layers "F.Cu" "F.Paste" "F.Mask")
      (net 554 "/Xilinx K26 SOM/HDC16_CC") (pinfunction "B57") (pintype "passive"))
    (pad "B58" smd circle (at -17.463 -0.791 270) (size 0.356 0.356) (layers "F.Cu" "F.Paste" "F.Mask")
      (net 555 "/Xilinx K26 SOM/HDC17") (pinfunction "B58") (pintype "passive"))
    (pad "B59" smd circle (at -18.098 -0.791 270) (size 0.356 0.356) (layers "F.Cu" "F.Paste" "F.Mask")
      (net 556 "/Xilinx K26 SOM/VCCO_HDB_1") (pinfunction "B59") (pintype "passive"))
    (pad "B60" smd circle (at -18.733 -0.791 270) (size 0.356 0.356) (layers "F.Cu" "F.Paste" "F.Mask")
      (net 557 "/Xilinx K26 SOM/VCCO_HDB_2") (pinfunction "B60") (pintype "passive"))
    (pad "C01" smd circle (at 18.732 0.79 270) (size 0.356 0.356) (layers "F.Cu" "F.Paste" "F.Mask")
      (net 1 "GND") (pinfunction "C01") (pintype "passive"))
    (pad "C02" smd circle (at 18.097 0.79 270) (size 0.356 0.356) (layers "F.Cu" "F.Paste" "F.Mask")
      (net 1 "GND") (pinfunction "C02") (pintype "passive"))
    (pad "C03" smd circle (at 17.462 0.79 270) (size 0.356 0.356) (layers "F.Cu" "F.Paste" "F.Mask")
      (net 558 "/Xilinx K26 SOM/GTH_REFCLK0_C2M_P") (pinfunction "C03") (pintype "passive"))
    (pad "C04" smd circle (at 16.827 0.79 270) (size 0.356 0.356) (layers "F.Cu" "F.Paste" "F.Mask")
      (net 559 "/Xilinx K26 SOM/GTH_REFCLK0_C2M_N") (pinfunction "C04") (pintype "passive"))
    (pad "C05" smd circle (at 16.192 0.79 270) (size 0.356 0.356) (layers "F.Cu" "F.Paste" "F.Mask")
      (net 1 "GND") (pinfunction "C05") (pintype "passive"))
    (pad "C06" smd circle (at 15.557 0.79 270) (size 0.356 0.356) (layers "F.Cu" "F.Paste" "F.Mask")
      (net 1 "GND") (pinfunction "C06") (pintype "passive"))
    (pad "C07" smd circle (at 14.922 0.79 270) (size 0.356 0.356) (layers "F.Cu" "F.Paste" "F.Mask")
      (net 560 "/Xilinx K26 SOM/GTH_DP1_M2C_P") (pinfunction "C07") (pintype "passive"))
    (pad "C08" smd circle (at 14.287 0.79 270) (size 0.356 0.356) (layers "F.Cu" "F.Paste" "F.Mask")
      (net 561 "/Xilinx K26 SOM/GTH_DP1_M2C_N") (pinfunction "C08") (pintype "passive"))
    (pad "C09" smd circle (at 13.652 0.79 270) (size 0.356 0.356) (layers "F.Cu" "F.Paste" "F.Mask")
      (net 1 "GND") (pinfunction "C09") (pintype "passive"))
    (pad "C10" smd circle (at 13.017 0.79 270) (size 0.356 0.356) (layers "F.Cu" "F.Paste" "F.Mask")
      (net 1 "GND") (pinfunction "C10") (pintype "passive"))
    (pad "C11" smd circle (at 12.382 0.79 270) (size 0.356 0.356) (layers "F.Cu" "F.Paste" "F.Mask")
      (net 562 "/Xilinx K26 SOM/HPB09_P") (pinfunction "C11") (pintype "passive"))
    (pad "C12" smd circle (at 11.747 0.79 270) (size 0.356 0.356) (layers "F.Cu" "F.Paste" "F.Mask")
      (net 563 "/Xilinx K26 SOM/HPB09_N") (pinfunction "C12") (pintype "passive"))
    (pad "C13" smd circle (at 11.112 0.79 270) (size 0.356 0.356) (layers "F.Cu" "F.Paste" "F.Mask")
      (net 1 "GND") (pinfunction "C13") (pintype "passive"))
    (pad "C14" smd circle (at 10.477 0.79 270) (size 0.356 0.356) (layers "F.Cu" "F.Paste" "F.Mask")
      (net 564 "/Xilinx K26 SOM/HPB14_P") (pinfunction "C14") (pintype "passive"))
    (pad "C15" smd circle (at 9.842 0.79 270) (size 0.356 0.356) (layers "F.Cu" "F.Paste" "F.Mask")
      (net 565 "/Xilinx K26 SOM/HPB14_N") (pinfunction "C15") (pintype "passive"))
    (pad "C16" smd circle (at 9.207 0.79 270) (size 0.356 0.356) (layers "F.Cu" "F.Paste" "F.Mask")
      (net 1 "GND") (pinfunction "C16") (pintype "passive"))
    (pad "C17" smd circle (at 8.572 0.79 270) (size 0.356 0.356) (layers "F.Cu" "F.Paste" "F.Mask")
      (net 566 "/Xilinx K26 SOM/HPB02_P") (pinfunction "C17") (pintype "passive"))
    (pad "C18" smd circle (at 7.937 0.79 270) (size 0.356 0.356) (layers "F.Cu" "F.Paste" "F.Mask")
      (net 567 "/Xilinx K26 SOM/HPB02_N") (pinfunction "C18") (pintype "passive"))
    (pad "C19" smd circle (at 7.302 0.79 270) (size 0.356 0.356) (layers "F.Cu" "F.Paste" "F.Mask")
      (net 1 "GND") (pinfunction "C19") (pintype "passive"))
    (pad "C20" smd circle (at 6.667 0.79 270) (size 0.356 0.356) (layers "F.Cu" "F.Paste" "F.Mask")
      (net 568 "/Xilinx K26 SOM/HPB13_P") (pinfunction "C20") (pintype "passive"))
    (pad "C21" smd circle (at 6.032 0.79 270) (size 0.356 0.356) (layers "F.Cu" "F.Paste" "F.Mask")
      (net 569 "/Xilinx K26 SOM/HPB13_N") (pinfunction "C21") (pintype "passive"))
    (pad "C22" smd circle (at 5.397 0.79 270) (size 0.356 0.356) (layers "F.Cu" "F.Paste" "F.Mask")
      (net 1 "GND") (pinfunction "C22") (pintype "passive"))
    (pad "C23" smd circle (at 4.762 0.79 270) (size 0.356 0.356) (layers "F.Cu" "F.Paste" "F.Mask")
      (net 570 "/Xilinx K26 SOM/HPB_18_P") (pinfunction "C23") (pintype "passive"))
    (pad "C24" smd circle (at 4.127 0.79 270) (size 0.356 0.356) (layers "F.Cu" "F.Paste" "F.Mask")
      (net 571 "/Xilinx K26 SOM/HPB_18_N") (pinfunction "C24") (pintype "passive"))
    (pad "C25" smd circle (at 3.492 0.79 270) (size 0.356 0.356) (layers "F.Cu" "F.Paste" "F.Mask")
      (net 1 "GND") (pinfunction "C25") (pintype "passive"))
    (pad "C26" smd circle (at 2.857 0.79 270) (size 0.356 0.356) (layers "F.Cu" "F.Paste" "F.Mask")
      (net 572 "/Xilinx K26 SOM/HPC17_P") (pinfunction "C26") (pintype "passive"))
    (pad "C27" smd circle (at 2.222 0.79 270) (size 0.356 0.356) (layers "F.Cu" "F.Paste" "F.Mask")
      (net 573 "/Xilinx K26 SOM/HPC17_N") (pinfunction "C27") (pintype "passive"))
    (pad "C28" smd circle (at 1.587 0.79 270) (size 0.356 0.356) (layers "F.Cu" "F.Paste" "F.Mask")
      (net 1 "GND") (pinfunction "C28") (pintype "passive"))
    (pad "C29" smd circle (at 0.952 0.79 270) (size 0.356 0.356) (layers "F.Cu" "F.Paste" "F.Mask")
      (net 574 "/Xilinx K26 SOM/HPC10_CC_P") (pinfunction "C29") (pintype "passive"))
    (pad "C30" smd circle (at 0.317 0.79 270) (size 0.356 0.356) (layers "F.Cu" "F.Paste" "F.Mask")
      (net 575 "/Xilinx K26 SOM/HPC10_CC_N") (pinfunction "C30") (pintype "passive"))
    (pad "C31" smd circle (at -0.318 0.79 270) (size 0.356 0.356) (layers "F.Cu" "F.Paste" "F.Mask")
      (net 1 "GND") (pinfunction "C31") (pintype "passive"))
    (pad "C32" smd circle (at -0.953 0.79 270) (size 0.356 0.356) (layers "F.Cu" "F.Paste" "F.Mask")
      (net 576 "/Xilinx K26 SOM/HPC11_P") (pinfunction "C32") (pintype "passive"))
    (pad "C33" smd circle (at -1.588 0.79 270) (size 0.356 0.356) (layers "F.Cu" "F.Paste" "F.Mask")
      (net 577 "/Xilinx K26 SOM/HPC11_N") (pinfunction "C33") (pintype "passive"))
    (pad "C34" smd circle (at -2.223 0.79 270) (size 0.356 0.356) (layers "F.Cu" "F.Paste" "F.Mask")
      (net 1 "GND") (pinfunction "C34") (pintype "passive"))
    (pad "C35" smd circle (at -2.858 0.79 270) (size 0.356 0.356) (layers "F.Cu" "F.Paste" "F.Mask")
      (net 578 "/Xilinx K26 SOM/HPC12_P") (pinfunction "C35") (pintype "passive"))
    (pad "C36" smd circle (at -3.493 0.79 270) (size 0.356 0.356) (layers "F.Cu" "F.Paste" "F.Mask")
      (net 579 "/Xilinx K26 SOM/HPC12_N") (pinfunction "C36") (pintype "passive"))
    (pad "C37" smd circle (at -4.128 0.79 270) (size 0.356 0.356) (layers "F.Cu" "F.Paste" "F.Mask")
      (net 1 "GND") (pinfunction "C37") (pintype "passive"))
    (pad "C38" smd circle (at -4.763 0.79 270) (size 0.356 0.356) (layers "F.Cu" "F.Paste" "F.Mask")
      (net 580 "/Xilinx K26 SOM/HPC05_CC_P") (pinfunction "C38") (pintype "passive"))
    (pad "C39" smd circle (at -5.398 0.79 270) (size 0.356 0.356) (layers "F.Cu" "F.Paste" "F.Mask")
      (net 581 "/Xilinx K26 SOM/HPC05_CC_N") (pinfunction "C39") (pintype "passive"))
    (pad "C40" smd circle (at -6.033 0.79 270) (size 0.356 0.356) (layers "F.Cu" "F.Paste" "F.Mask")
      (net 1 "GND") (pinfunction "C40") (pintype "passive"))
    (pad "C41" smd circle (at -6.668 0.79 270) (size 0.356 0.356) (layers "F.Cu" "F.Paste" "F.Mask")
      (net 582 "/Xilinx K26 SOM/HPC_CLK0_P") (pinfunction "C41") (pintype "passive"))
    (pad "C42" smd circle (at -7.303 0.79 270) (size 0.356 0.356) (layers "F.Cu" "F.Paste" "F.Mask")
      (net 583 "/Xilinx K26 SOM/HPC_CLK0_N") (pinfunction "C42") (pintype "passive"))
    (pad "C43" smd circle (at -7.938 0.79 270) (size 0.356 0.356) (layers "F.Cu" "F.Paste" "F.Mask")
      (net 1 "GND") (pinfunction "C43") (pintype "passive"))
    (pad "C44" smd circle (at -8.573 0.79 270) (size 0.356 0.356) (layers "F.Cu" "F.Paste" "F.Mask")
      (net 584 "/Xilinx K26 SOM/VCCO_HPC_1") (pinfunction "C44") (pintype "passive"))
    (pad "C45" smd circle (at -9.208 0.79 270) (size 0.356 0.356) (layers "F.Cu" "F.Paste" "F.Mask")
      (net 1 "GND") (pinfunction "C45") (pintype "passive"))
    (pad "C46" smd circle (at -9.843 0.79 270) (size 0.356 0.356) (layers "F.Cu" "F.Paste" "F.Mask")
      (net 585 "/Xilinx K26 SOM/HDB06") (pinfunction "C46") (pintype "passive"))
    (pad "C47" smd circle (at -10.478 0.79 270) (size 0.356 0.356) (layers "F.Cu" "F.Paste" "F.Mask")
      (net 586 "/Xilinx K26 SOM/HDB07") (pinfunction "C47") (pintype "passive"))
    (pad "C48" smd circle (at -11.113 0.79 270) (size 0.356 0.356) (layers "F.Cu" "F.Paste" "F.Mask")
      (net 587 "/Xilinx K26 SOM/HDB08_CC") (pinfunction "C48") (pintype "passive"))
    (pad "C49" smd circle (at -11.748 0.79 270) (size 0.356 0.356) (layers "F.Cu" "F.Paste" "F.Mask")
      (net 1 "GND") (pinfunction "C49") (pintype "passive"))
    (pad "C50" smd circle (at -12.383 0.79 270) (size 0.356 0.356) (layers "F.Cu" "F.Paste" "F.Mask")
      (net 588 "/Xilinx K26 SOM/HDB09") (pinfunction "C50") (pintype "passive"))
    (pad "C51" smd circle (at -13.018 0.79 270) (size 0.356 0.356) (layers "F.Cu" "F.Paste" "F.Mask")
      (net 589 "/Xilinx K26 SOM/HDB10") (pinfunction "C51") (pintype "passive"))
    (pad "C52" smd circle (at -13.653 0.79 270) (size 0.356 0.356) (layers "F.Cu" "F.Paste" "F.Mask")
      (net 590 "/Xilinx K26 SOM/HDB11") (pinfunction "C52") (pintype "passive"))
    (pad "C53" smd circle (at -14.288 0.79 270) (size 0.356 0.356) (layers "F.Cu" "F.Paste" "F.Mask")
      (net 1 "GND") (pinfunction "C53") (pintype "passive"))
    (pad "C54" smd circle (at -14.923 0.79 270) (size 0.356 0.356) (layers "F.Cu" "F.Paste" "F.Mask")
      (net 591 "/Xilinx K26 SOM/HDC06") (pinfunction "C54") (pintype "passive"))
    (pad "C55" smd circle (at -15.558 0.79 270) (size 0.356 0.356) (layers "F.Cu" "F.Paste" "F.Mask")
      (net 592 "/Xilinx K26 SOM/HDC07") (pinfunction "C55") (pintype "passive"))
    (pad "C56" smd circle (at -16.193 0.79 270) (size 0.356 0.356) (layers "F.Cu" "F.Paste" "F.Mask")
      (net 593 "/Xilinx K26 SOM/HDC08_CC") (pinfunction "C56") (pintype "passive"))
    (pad "C57" smd circle (at -16.828 0.79 270) (size 0.356 0.356) (layers "F.Cu" "F.Paste" "F.Mask")
      (net 1 "GND") (pinfunction "C57") (pintype "passive"))
    (pad "C58" smd circle (at -17.463 0.79 270) (size 0.356 0.356) (layers "F.Cu" "F.Paste" "F.Mask")
      (net 594 "/Xilinx K26 SOM/HDC09") (pinfunction "C58") (pintype "passive"))
    (pad "C59" smd circle (at -18.098 0.79 270) (size 0.356 0.356) (layers "F.Cu" "F.Paste" "F.Mask")
      (net 595 "/Xilinx K26 SOM/HDC10") (pinfunction "C59") (pintype "passive"))
    (pad "C60" smd circle (at -18.733 0.79 270) (size 0.356 0.356) (layers "F.Cu" "F.Paste" "F.Mask")
      (net 596 "/Xilinx K26 SOM/HDC11") (pinfunction "C60") (pintype "passive"))
    (pad "D01" smd circle (at 18.732 1.749 270) (size 0.356 0.356) (layers "F.Cu" "F.Paste" "F.Mask")
      (net 597 "/Xilinx K26 SOM/GTH_DP1_C2M_P") (pinfunction "D01") (pintype "passive"))
    (pad "D02" smd circle (at 18.097 1.749 270) (size 0.356 0.356) (layers "F.Cu" "F.Paste" "F.Mask")
      (net 598 "/Xilinx K26 SOM/GTH_DP1_C2M_N") (pinfunction "D02") (pintype "passive"))
    (pad "D03" smd circle (at 17.462 1.749 270) (size 0.356 0.356) (layers "F.Cu" "F.Paste" "F.Mask")
      (net 1 "GND") (pinfunction "D03") (pintype "passive"))
    (pad "D04" smd circle (at 16.827 1.749 270) (size 0.356 0.356) (layers "F.Cu" "F.Paste" "F.Mask")
      (net 1 "GND") (pinfunction "D04") (pintype "passive"))
    (pad "D05" smd circle (at 16.192 1.749 270) (size 0.356 0.356) (layers "F.Cu" "F.Paste" "F.Mask")
      (net 599 "/Xilinx K26 SOM/GTH_DP3_C2M_P") (pinfunction "D05") (pintype "passive"))
    (pad "D06" smd circle (at 15.557 1.749 270) (size 0.356 0.356) (layers "F.Cu" "F.Paste" "F.Mask")
      (net 600 "/Xilinx K26 SOM/GTH_DP3_C2M_N") (pinfunction "D06") (pintype "passive"))
    (pad "D07" smd circle (at 14.922 1.749 270) (size 0.356 0.356) (layers "F.Cu" "F.Paste" "F.Mask")
      (net 1 "GND") (pinfunction "D07") (pintype "passive"))
    (pad "D08" smd circle (at 14.287 1.749 270) (size 0.356 0.356) (layers "F.Cu" "F.Paste" "F.Mask")
      (net 1 "GND") (pinfunction "D08") (pintype "passive"))
    (pad "D09" smd circle (at 13.652 1.749 270) (size 0.356 0.356) (layers "F.Cu" "F.Paste" "F.Mask")
      (net 601 "/Xilinx K26 SOM/GTH_DP0_M2C_P") (pinfunction "D09") (pintype "passive"))
    (pad "D10" smd circle (at 13.017 1.749 270) (size 0.356 0.356) (layers "F.Cu" "F.Paste" "F.Mask")
      (net 602 "/Xilinx K26 SOM/GTH_DP0_M2C_N") (pinfunction "D10") (pintype "passive"))
    (pad "D11" smd circle (at 12.382 1.749 270) (size 0.356 0.356) (layers "F.Cu" "F.Paste" "F.Mask")
      (net 1 "GND") (pinfunction "D11") (pintype "passive"))
    (pad "D12" smd circle (at 11.747 1.749 270) (size 0.356 0.356) (layers "F.Cu" "F.Paste" "F.Mask")
      (net 603 "/Xilinx K26 SOM/HPB01_P") (pinfunction "D12") (pintype "passive"))
    (pad "D13" smd circle (at 11.112 1.749 270) (size 0.356 0.356) (layers "F.Cu" "F.Paste" "F.Mask")
      (net 604 "/Xilinx K26 SOM/HPB01_N") (pinfunction "D13") (pintype "passive"))
    (pad "D14" smd circle (at 10.477 1.749 270) (size 0.356 0.356) (layers "F.Cu" "F.Paste" "F.Mask")
      (net 1 "GND") (pinfunction "D14") (pintype "passive"))
    (pad "D15" smd circle (at 9.842 1.749 270) (size 0.356 0.356) (layers "F.Cu" "F.Paste" "F.Mask")
      (net 605 "/Xilinx K26 SOM/HPB00_CC_P") (pinfunction "D15") (pintype "passive"))
    (pad "D16" smd circle (at 9.207 1.749 270) (size 0.356 0.356) (layers "F.Cu" "F.Paste" "F.Mask")
      (net 606 "/Xilinx K26 SOM/HPB00_CC_N") (pinfunction "D16") (pintype "passive"))
    (pad "D17" smd circle (at 8.572 1.749 270) (size 0.356 0.356) (layers "F.Cu" "F.Paste" "F.Mask")
      (net 1 "GND") (pinfunction "D17") (pintype "passive"))
    (pad "D18" smd circle (at 7.937 1.749 270) (size 0.356 0.356) (layers "F.Cu" "F.Paste" "F.Mask")
      (net 607 "/Xilinx K26 SOM/HPB_CLK0_P") (pinfunction "D18") (pintype "passive"))
    (pad "D19" smd circle (at 7.302 1.749 270) (size 0.356 0.356) (layers "F.Cu" "F.Paste" "F.Mask")
      (net 608 "/Xilinx K26 SOM/HPB_CLK0_N") (pinfunction "D19") (pintype "passive"))
    (pad "D20" smd circle (at 6.667 1.749 270) (size 0.356 0.356) (layers "F.Cu" "F.Paste" "F.Mask")
      (net 1 "GND") (pinfunction "D20") (pintype "passive"))
    (pad "D21" smd circle (at 6.032 1.749 270) (size 0.356 0.356) (layers "F.Cu" "F.Paste" "F.Mask")
      (net 609 "/Xilinx K26 SOM/HPB04_P") (pinfunction "D21") (pintype "passive"))
    (pad "D22" smd circle (at 5.397 1.749 270) (size 0.356 0.356) (layers "F.Cu" "F.Paste" "F.Mask")
      (net 610 "/Xilinx K26 SOM/HPB04_N") (pinfunction "D22") (pintype "passive"))
    (pad "D23" smd circle (at 4.762 1.749 270) (size 0.356 0.356) (layers "F.Cu" "F.Paste" "F.Mask")
      (net 1 "GND") (pinfunction "D23") (pintype "passive"))
    (pad "D24" smd circle (at 4.127 1.749 270) (size 0.356 0.356) (layers "F.Cu" "F.Paste" "F.Mask")
      (net 611 "/Xilinx K26 SOM/HPB17_P") (pinfunction "D24") (pintype "passive"))
    (pad "D25" smd circle (at 3.492 1.749 270) (size 0.356 0.356) (layers "F.Cu" "F.Paste" "F.Mask")
      (net 612 "/Xilinx K26 SOM/HPB17_N") (pinfunction "D25") (pintype "passive"))
    (pad "D26" smd circle (at 2.857 1.749 270) (size 0.356 0.356) (layers "F.Cu" "F.Paste" "F.Mask")
      (net 1 "GND") (pinfunction "D26") (pintype "passive"))
    (pad "D27" smd circle (at 2.222 1.749 270) (size 0.356 0.356) (layers "F.Cu" "F.Paste" "F.Mask")
      (net 613 "/Xilinx K26 SOM/HPC09_P") (pinfunction "D27") (pintype "passive"))
    (pad "D28" smd circle (at 1.587 1.749 270) (size 0.356 0.356) (layers "F.Cu" "F.Paste" "F.Mask")
      (net 614 "/Xilinx K26 SOM/HPC09_N") (pinfunction "D28") (pintype "passive"))
    (pad "D29" smd circle (at 0.952 1.749 270) (size 0.356 0.356) (layers "F.Cu" "F.Paste" "F.Mask")
      (net 1 "GND") (pinfunction "D29") (pintype "passive"))
    (pad "D30" smd circle (at 0.317 1.749 270) (size 0.356 0.356) (layers "F.Cu" "F.Paste" "F.Mask")
      (net 615 "/Xilinx K26 SOM/HPC01_P") (pinfunction "D30") (pintype "passive"))
    (pad "D31" smd circle (at -0.318 1.749 270) (size 0.356 0.356) (layers "F.Cu" "F.Paste" "F.Mask")
      (net 616 "/Xilinx K26 SOM/HPC01_N") (pinfunction "D31") (pintype "passive"))
    (pad "D32" smd circle (at -0.953 1.749 270) (size 0.356 0.356) (layers "F.Cu" "F.Paste" "F.Mask")
      (net 1 "GND") (pinfunction "D32") (pintype "passive"))
    (pad "D33" smd circle (at -1.588 1.749 270) (size 0.356 0.356) (layers "F.Cu" "F.Paste" "F.Mask")
      (net 617 "/Xilinx K26 SOM/HPC00_CC_P") (pinfunction "D33") (pintype "passive"))
    (pad "D34" smd circle (at -2.223 1.749 270) (size 0.356 0.356) (layers "F.Cu" "F.Paste" "F.Mask")
      (net 618 "/Xilinx K26 SOM/HPC00_CC_N") (pinfunction "D34") (pintype "passive"))
    (pad "D35" smd circle (at -2.858 1.749 270) (size 0.356 0.356) (layers "F.Cu" "F.Paste" "F.Mask")
      (net 1 "GND") (pinfunction "D35") (pintype "passive"))
    (pad "D36" smd circle (at -3.493 1.749 270) (size 0.356 0.356) (layers "F.Cu" "F.Paste" "F.Mask")
      (net 619 "/Xilinx K26 SOM/HPC02_P") (pinfunction "D36") (pintype "passive"))
    (pad "D37" smd circle (at -4.128 1.749 270) (size 0.356 0.356) (layers "F.Cu" "F.Paste" "F.Mask")
      (net 620 "/Xilinx K26 SOM/HPC02_N") (pinfunction "D37") (pintype "passive"))
    (pad "D38" smd circle (at -4.763 1.749 270) (size 0.356 0.356) (layers "F.Cu" "F.Paste" "F.Mask")
      (net 1 "GND") (pinfunction "D38") (pintype "passive"))
    (pad "D39" smd circle (at -5.398 1.749 270) (size 0.356 0.356) (layers "F.Cu" "F.Paste" "F.Mask")
      (net 621 "/Xilinx K26 SOM/HPC04_P") (pinfunction "D39") (pintype "passive"))
    (pad "D40" smd circle (at -6.033 1.749 270) (size 0.356 0.356) (layers "F.Cu" "F.Paste" "F.Mask")
      (net 622 "/Xilinx K26 SOM/HPC04_N") (pinfunction "D40") (pintype "passive"))
    (pad "D41" smd circle (at -6.668 1.749 270) (size 0.356 0.356) (layers "F.Cu" "F.Paste" "F.Mask")
      (net 1 "GND") (pinfunction "D41") (pintype "passive"))
    (pad "D42" smd circle (at -7.303 1.749 270) (size 0.356 0.356) (layers "F.Cu" "F.Paste" "F.Mask")
      (net 623 "/Xilinx K26 SOM/VCCO_HPC_2") (pinfunction "D42") (pintype "passive"))
    (pad "D43" smd circle (at -7.938 1.749 270) (size 0.356 0.356) (layers "F.Cu" "F.Paste" "F.Mask")
      (net 1 "GND") (pinfunction "D43") (pintype "passive"))
    (pad "D44" smd circle (at -8.573 1.749 270) (size 0.356 0.356) (layers "F.Cu" "F.Paste" "F.Mask")
      (net 624 "/Xilinx K26 SOM/HDB00_CC") (pinfunction "D44") (pintype "passive"))
    (pad "D45" smd circle (at -9.208 1.749 270) (size 0.356 0.356) (layers "F.Cu" "F.Paste" "F.Mask")
      (net 625 "/Xilinx K26 SOM/HDB01") (pinfunction "D45") (pintype "passive"))
    (pad "D46" smd circle (at -9.843 1.749 270) (size 0.356 0.356) (layers "F.Cu" "F.Paste" "F.Mask")
      (net 626 "/Xilinx K26 SOM/HDB02") (pinfunction "D46") (pintype "passive"))
    (pad "D47" smd circle (at -10.478 1.749 270) (size 0.356 0.356) (layers "F.Cu" "F.Paste" "F.Mask")
      (net 1 "GND") (pinfunction "D47") (pintype "passive"))
    (pad "D48" smd circle (at -11.113 1.749 270) (size 0.356 0.356) (layers "F.Cu" "F.Paste" "F.Mask")
      (net 627 "/Xilinx K26 SOM/HDB03") (pinfunction "D48") (pintype "passive"))
    (pad "D49" smd circle (at -11.748 1.749 270) (size 0.356 0.356) (layers "F.Cu" "F.Paste" "F.Mask")
      (net 628 "/Xilinx K26 SOM/HDB04") (pinfunction "D49") (pintype "passive"))
    (pad "D50" smd circle (at -12.383 1.749 270) (size 0.356 0.356) (layers "F.Cu" "F.Paste" "F.Mask")
      (net 629 "/Xilinx K26 SOM/HDB05") (pinfunction "D50") (pintype "passive"))
    (pad "D51" smd circle (at -13.018 1.749 270) (size 0.356 0.356) (layers "F.Cu" "F.Paste" "F.Mask")
      (net 1 "GND") (pinfunction "D51") (pintype "passive"))
    (pad "D52" smd circle (at -13.653 1.749 270) (size 0.356 0.356) (layers "F.Cu" "F.Paste" "F.Mask")
      (net 630 "/Xilinx K26 SOM/HDC00_CC") (pinfunction "D52") (pintype "passive"))
    (pad "D53" smd circle (at -14.288 1.749 270) (size 0.356 0.356) (layers "F.Cu" "F.Paste" "F.Mask")
      (net 631 "/Xilinx K26 SOM/HDC01") (pinfunction "D53") (pintype "passive"))
    (pad "D54" smd circle (at -14.923 1.749 270) (size 0.356 0.356) (layers "F.Cu" "F.Paste" "F.Mask")
      (net 632 "/Xilinx K26 SOM/HDC02") (pinfunction "D54") (pintype "passive"))
    (pad "D55" smd circle (at -15.558 1.749 270) (size 0.356 0.356) (layers "F.Cu" "F.Paste" "F.Mask")
      (net 1 "GND") (pinfunction "D55") (pintype "passive"))
    (pad "D56" smd circle (at -16.193 1.749 270) (size 0.356 0.356) (layers "F.Cu" "F.Paste" "F.Mask")
      (net 633 "/Xilinx K26 SOM/HDC03") (pinfunction "D56") (pintype "passive"))
    (pad "D57" smd circle (at -16.828 1.749 270) (size 0.356 0.356) (layers "F.Cu" "F.Paste" "F.Mask")
      (net 634 "/Xilinx K26 SOM/HDC04") (pinfunction "D57") (pintype "passive"))
    (pad "D58" smd circle (at -17.463 1.749 270) (size 0.356 0.356) (layers "F.Cu" "F.Paste" "F.Mask")
      (net 635 "/Xilinx K26 SOM/HDC05") (pinfunction "D58") (pintype "passive"))
    (pad "D59" smd circle (at -18.098 1.749 270) (size 0.356 0.356) (layers "F.Cu" "F.Paste" "F.Mask")
      (net 636 "/Xilinx K26 SOM/VCCO_HDC_1") (pinfunction "D59") (pintype "passive"))
    (pad "D60" smd circle (at -18.733 1.749 270) (size 0.356 0.356) (layers "F.Cu" "F.Paste" "F.Mask")
      (net 637 "/Xilinx K26 SOM/VCCO_HDC_2") (pinfunction "D60") (pintype "passive"))
  )

  (footprint "kria-k26-devboard-footprints:SOT-563" (layer "F.Cu")
    (at 146.72 61.9 90)
    (property "Author" "Antmicro")
    (property "License" "Apache-2.0")
    (property "MPN" "82400152")
    (property "Manufacturer" "Würth Elektronik")
    (property "Sheetfile" "usbc-socket.kicad_sch")
    (property "Sheetname" "USB-C socket")
    (property "ki_description" "TVS diode")
    (property "ki_keywords" "SMT, DIODE, IC, ESD, TVS")
    (attr smd)
    (fp_text reference "U60" (at -1.92 -1.12 180) (layer "F.SilkS")
        (effects (font (size 0.7 0.7) (thickness 0.15)) (justify left bottom))
    )
    (fp_text value "82400152" (at 0 2 90) (layer "F.Fab") hide
        (effects (font (size 0.7 0.7) (thickness 0.15)) (justify left bottom))
    )
    (fp_text user "Author: Antmicro" (at -1.299 6.124 90) (layer "F.Fab") hide
        (effects (font (size 0.7 0.7) (thickness 0.15)) (justify left bottom))
    )
    (fp_text user "License: Apache-2.0" (at -1.299 4.924 90) (layer "F.Fab") hide
        (effects (font (size 0.7 0.7) (thickness 0.15)) (justify left bottom))
    )
    (fp_text user "${REFERENCE}" (at -1.299 7.323 90) (layer "F.Fab") hide
        (effects (font (size 0.7 0.7) (thickness 0.15)) (justify left bottom))
    )
    (fp_line (start -0.778 0.776) (end -0.778 0.949)
      (stroke (width 0.15) (type solid)) (layer "F.SilkS"))
    (fp_line (start -0.778 0.949) (end -0.424 0.949)
      (stroke (width 0.15) (type solid)) (layer "F.SilkS"))
    (fp_line (start -0.499 -0.974) (end -0.724 -0.778)
      (stroke (width 0.15) (type solid)) (layer "F.SilkS"))
    (fp_line (start 0.776 -0.974) (end 0.526 -0.974)
      (stroke (width 0.15) (type solid)) (layer "F.SilkS"))
    (fp_line (start 0.776 -0.974) (end 0.776 -0.778)
      (stroke (width 0.15) (type solid)) (layer "F.SilkS"))
    (fp_line (start 0.776 0.776) (end 0.776 0.972)
      (stroke (width 0.15) (type solid)) (layer "F.SilkS"))
    (fp_line (start 0.776 0.972) (end 0.526 0.972)
      (stroke (width 0.15) (type solid)) (layer "F.SilkS"))
    (fp_circle (center -0.903 -0.999) (end -0.952 -0.95)
      (stroke (width 0.15) (type solid)) (fill solid) (layer "F.SilkS"))
    (fp_rect (start 1.19 -1.12) (end -1.2 1.1)
      (stroke (width 0.05) (type solid)) (fill none) (layer "F.CrtYd"))
    (fp_line (start -0.653 -0.678) (end -0.653 0.847)
      (stroke (width 0.15) (type solid)) (layer "F.Fab"))
    (fp_line (start -0.453 -0.849) (end -0.653 -0.678)
      (stroke (width 0.15) (type solid)) (layer "F.Fab"))
    (fp_line (start -0.453 -0.849) (end 0.651 -0.849)
      (stroke (width 0.15) (type solid)) (layer "F.Fab"))
    (fp_line (start 0.651 -0.849) (end 0.651 0.847)
      (stroke (width 0.15) (type solid)) (layer "F.Fab"))
    (fp_line (start 0.651 0.847) (end -0.653 0.847)
      (stroke (width 0.15) (type solid)) (layer "F.Fab"))
    (pad "1" smd roundrect (at -0.749 -0.499) (size 0.3 0.6) (layers "F.Cu" "F.Paste" "F.Mask") (roundrect_rratio 0.25)
      (net 189 "/Debug and JTAG/USBC_N") (pintype "passive"))
    (pad "2" smd roundrect (at -0.749 0.001) (size 0.3 0.6) (layers "F.Cu" "F.Paste" "F.Mask") (roundrect_rratio 0.25)
      (net 1 "GND") (pintype "passive"))
    (pad "3" smd roundrect (at -0.749 0.497) (size 0.3 0.6) (layers "F.Cu" "F.Paste" "F.Mask") (roundrect_rratio 0.25)
      (net 188 "/Debug and JTAG/USBC_P") (pintype "passive"))
    (pad "4" smd roundrect (at 0.747 0.497) (size 0.3 0.6) (layers "F.Cu" "F.Paste" "F.Mask") (roundrect_rratio 0.25)
      (net 299 "/Power Supply/USB-C socket/USBC_TVS_P") (pintype "passive"))
    (pad "5" smd roundrect (at 0.747 0.001) (size 0.3 0.6) (layers "F.Cu" "F.Paste" "F.Mask") (roundrect_rratio 0.25)
      (net 757 "unconnected-(U60-Pad5)") (pintype "passive+no_connect"))
    (pad "6" smd roundrect (at 0.747 -0.499) (size 0.3 0.6) (layers "F.Cu" "F.Paste" "F.Mask") (roundrect_rratio 0.25)
      (net 298 "/Power Supply/USB-C socket/USBC_TVS_N") (pintype "passive"))
  )

  (footprint "kria-k26-devboard-footprints:SOT-23-5" (layer "F.Cu")
    (at 102.825 140.925 180)
    (property "Author" "Antmicro")
    (property "License" "Apache-2.0")
    (property "MPN" "TPS3840PH30DBVR")
    (property "Manufacturer" "Texas Instruments")
    (property "Sheetfile" "reset.kicad_sch")
    (property "Sheetname" "Reset logic")
    (property "ki_description" "Voltage supervisor")
    (property "ki_keywords" "SMT, PMIC, IC, CONTROLLER")
    (attr smd)
    (fp_text reference "U31" (at 0.855 -0.345) (layer "F.SilkS")
        (effects (font (size 0.7 0.7) (thickness 0.15)) (justify right bottom))
    )
    (fp_text value "TPS3840PH30DBVR" (at 0.002 2.799) (layer "F.Fab") hide
        (effects (font (size 0.7 0.7) (thickness 0.15)) (justify right bottom))
    )
    (fp_text user "${REFERENCE}" (at -1.898 4.299) (layer "F.Fab") hide
        (effects (font (size 0.7 0.7) (thickness 0.15)) (justify right bottom))
    )
    (fp_text user "License: Apache-2.0" (at -1.898 6.7) (layer "F.Fab") hide
        (effects (font (size 0.7 0.7) (thickness 0.15)) (justify right bottom))
    )
    (fp_text user "Author: Antmicro" (at -1.898 5.499) (layer "F.Fab") hide
        (effects (font (size 0.7 0.7) (thickness 0.15)) (justify right bottom))
    )
    (fp_line (start -0.85 1.6) (end -0.85 1.301)
      (stroke (width 0.15) (type solid)) (layer "F.SilkS"))
    (fp_line (start -0.8 -1.6) (end -0.8 -1.3)
      (stroke (width 0.15) (type solid)) (layer "F.SilkS"))
    (fp_line (start -0.8 -1.6) (end -0.5 -1.6)
      (stroke (width 0.15) (type solid)) (layer "F.SilkS"))
    (fp_line (start -0.55 1.6) (end -0.85 1.6)
      (stroke (width 0.15) (type solid)) (layer "F.SilkS"))
    (fp_line (start 0.8 -1.6) (end 0.5 -1.6)
      (stroke (width 0.15) (type solid)) (layer "F.SilkS"))
    (fp_line (start 0.8 -1.3) (end 0.8 -1.6)
      (stroke (width 0.15) (type solid)) (layer "F.SilkS"))
    (fp_line (start 0.8 0.55) (end 0.8 -0.55)
      (stroke (width 0.15) (type solid)) (layer "F.SilkS"))
    (fp_line (start 0.8 1.3) (end 0.8 1.599)
      (stroke (width 0.15) (type solid)) (layer "F.SilkS"))
    (fp_line (start 0.8 1.599) (end 0.549 1.599)
      (stroke (width 0.15) (type solid)) (layer "F.SilkS"))
    (fp_circle (center -1.25 -1.5) (end -1.2 -1.5)
      (stroke (width 0.15) (type solid)) (fill solid) (layer "F.SilkS"))
    (fp_rect (start 1.9 -1.76) (end -1.9 1.75)
      (stroke (width 0.05) (type solid)) (fill none) (layer "F.CrtYd"))
    (fp_line (start -0.398 -1.526) (end -0.874 -1.05)
      (stroke (width 0.15) (type solid)) (layer "F.Fab"))
    (fp_rect (start 0.874 1.523) (end -0.873 -1.525)
      (stroke (width 0.15) (type solid)) (fill none) (layer "F.Fab"))
    (pad "1" smd rect (at -1.351 -0.951 90) (size 0.55 1) (layers "F.Cu" "F.Paste" "F.Mask")
      (net 161 "/Reset logic/PS_RST") (pinfunction "RESET") (pintype "open_collector"))
    (pad "2" smd rect (at -1.351 0 90) (size 0.55 1) (layers "F.Cu" "F.Paste" "F.Mask")
      (net 15 "PS_3V3") (pinfunction "VDD") (pintype "power_in"))
    (pad "3" smd rect (at -1.351 0.949 90) (size 0.55 1) (layers "F.Cu" "F.Paste" "F.Mask")
      (net 1 "GND") (pinfunction "GND") (pintype "power_in"))
    (pad "4" smd rect (at 1.35 0.949 90) (size 0.55 1) (layers "F.Cu" "F.Paste" "F.Mask")
      (net 336 "Net-(U31-MR_N)") (pinfunction "MR_N") (pintype "input"))
    (pad "5" smd rect (at 1.35 -0.951 90) (size 0.55 1) (layers "F.Cu" "F.Paste" "F.Mask")
      (net 247 "Net-(U31-CT)") (pinfunction "CT") (pintype "input"))
  )

  (footprint "kria-k26-devboard-footprints:UQFN-16-1.8x2.6mm_P0.4mm_Texas_RSV0016A" (layer "F.Cu")
    (at 107.75 140.6 90)
    (descr "https://www.ti.com/lit/ds/symlink/sn74avch4t245-ep.pdf?ts=1679484181203&ref_url=https%253A%252F%252Fwww.ti.com%252Fproduct%252FSN74AVCH4T245-EP%253Futm_source%253Dgoogle%2526utm_medium%253Dcpc%2526utm_campaign%253Dasc-int-null-prodfolderdynamic-cpc-pf-google-wwe_int%2526utm_content%253Dprodfolddynamic%2526ds_k%253DDYNAMIC%2BSEARCH%2BADS%2526DCM%253Dyes%2526gclid%253DCjwKCAjwzuqgBhAcEiwAdj5dRvR_WgyvqqhLxMx8zfbFv2a6tg33JIMv01Bn4M1kA4JzW1nDDW7OzhoCRbkQAvD_BwE%2526gclsrc%253Daw.ds")
    (property "Author" "Antmicro")
    (property "License" "Apache-2.0")
    (property "MPN" "74AVC4T245RSVRG4")
    (property "Manufacturer" "Texas Instruments")
    (property "Sheetfile" "reset.kicad_sch")
    (property "Sheetname" "Reset logic")
    (property "ki_description" "Logic translator/level shifter")
    (property "ki_keywords" "SMT, LOGIC, IC, LEVEL-SHIFTER")
    (attr smd)
    (fp_text reference "U33" (at -1.25 -1.75 90) (layer "F.SilkS")
        (effects (font (size 0.7 0.7) (thickness 0.15)) (justify left bottom))
    )
    (fp_text value "74AVC4T245_UQFN" (at -1.25 2.5 90) (layer "F.Fab") hide
        (effects (font (size 0.7 0.7) (thickness 0.15)) (justify left bottom))
    )
    (fp_text user "." (at -1.45 -0.75 90) (layer "F.SilkS")
        (effects (font (size 0.7 0.7) (thickness 0.15)) (justify left bottom))
    )
    (fp_text user "License: Apache-2.0" (at -1.25 6.25 90) (layer "F.Fab") hide
        (effects (font (size 0.7 0.7) (thickness 0.15)) (justify left bottom))
    )
    (fp_text user "${REFERENCE}" (at -1.25 3.75 90) (layer "F.Fab") hide
        (effects (font (size 0.7 0.7) (thickness 0.15)) (justify left bottom))
    )
    (fp_text user "Author: Antmicro" (at -1.25 5 90) (layer "F.Fab") hide
        (effects (font (size 0.7 0.7) (thickness 0.15)) (justify left bottom))
    )
    (fp_line (start -0.9 1.2995) (end -0.9 0.8)
      (stroke (width 0.15) (type solid)) (layer "F.SilkS"))
    (fp_line (start -0.8 -1.3) (end -0.9 -1.3)
      (stroke (width 0.15) (type solid)) (layer "F.SilkS"))
    (fp_line (start -0.8 1.2995) (end -0.9 1.2995)
      (stroke (width 0.15) (type solid)) (layer "F.SilkS"))
    (fp_line (start 0.8 -1.3) (end 0.9 -1.3)
      (stroke (width 0.15) (type solid)) (layer "F.SilkS"))
    (fp_line (start 0.8 1.3) (end 0.899 1.3)
      (stroke (width 0.15) (type solid)) (layer "F.SilkS"))
    (fp_line (start 0.9 -1.3) (end 0.9 -0.8005)
      (stroke (width 0.15) (type solid)) (layer "F.SilkS"))
    (fp_line (start 0.9 0.8) (end 0.899 1.3)
      (stroke (width 0.15) (type solid)) (layer "F.SilkS"))
    (fp_rect (start -1.25 -1.65) (end 1.25 1.65)
      (stroke (width 0.05) (type solid)) (fill none) (layer "F.CrtYd"))
    (fp_line (start -0.902 1.3) (end -0.902 -1.301)
      (stroke (width 0.15) (type solid)) (layer "F.Fab"))
    (fp_line (start 0.9 -1.301) (end -0.902 -1.301)
      (stroke (width 0.15) (type solid)) (layer "F.Fab"))
    (fp_line (start 0.9 1.3) (end -0.902 1.3)
      (stroke (width 0.15) (type solid)) (layer "F.Fab"))
    (fp_line (start 0.9 1.3) (end 0.9 -1.301)
      (stroke (width 0.15) (type solid)) (layer "F.Fab"))
    (pad "1" smd roundrect (at -0.75 -0.6 90) (size 0.7 0.2) (layers "F.Cu" "F.Paste" "F.Mask") (roundrect_rratio 0.2272727273)
      (net 161 "/Reset logic/PS_RST") (pinfunction "1~{OE}") (pintype "input"))
    (pad "2" smd roundrect (at -0.802 -0.202 90) (size 0.6 0.2) (layers "F.Cu" "F.Paste" "F.Mask") (roundrect_rratio 0.2272727273)
      (net 17 "PS_1V8") (pinfunction "VCCB") (pintype "power_in"))
    (pad "3" smd roundrect (at -0.802 0.2 90) (size 0.6 0.2) (layers "F.Cu" "F.Paste" "F.Mask") (roundrect_rratio 0.2272727273)
      (net 15 "PS_3V3") (pinfunction "VCCA") (pintype "power_in"))
    (pad "4" smd roundrect (at -0.802 0.598 90) (size 0.6 0.2) (layers "F.Cu" "F.Paste" "F.Mask") (roundrect_rratio 0.2272727273)
      (net 1 "GND") (pinfunction "1DIR") (pintype "input"))
    (pad "5" smd roundrect (at -0.6 1.199 180) (size 0.6 0.2) (layers "F.Cu" "F.Paste" "F.Mask") (roundrect_rratio 0.2272727273)
      (net 1 "GND") (pinfunction "2DIR") (pintype "input"))
    (pad "6" smd roundrect (at -0.202 1.199 180) (size 0.6 0.2) (layers "F.Cu" "F.Paste" "F.Mask") (roundrect_rratio 0.2272727273)
      (net 675 "Net-(U33-1A1)") (pinfunction "1A1") (pintype "bidirectional"))
    (pad "7" smd roundrect (at 0.2 1.199 180) (size 0.6 0.2) (layers "F.Cu" "F.Paste" "F.Mask") (roundrect_rratio 0.2272727273)
      (net 677 "Net-(U33-1A2)") (pinfunction "1A2") (pintype "bidirectional"))
    (pad "8" smd roundrect (at 0.598 1.199 180) (size 0.6 0.2) (layers "F.Cu" "F.Paste" "F.Mask") (roundrect_rratio 0.2272727273)
      (net 678 "Net-(U33-2A1)") (pinfunction "2A1") (pintype "bidirectional"))
    (pad "9" smd roundrect (at 0.8 0.598 90) (size 0.6 0.2) (layers "F.Cu" "F.Paste" "F.Mask") (roundrect_rratio 0.2272727273)
      (net 679 "Net-(U33-2A2)") (pinfunction "2A2") (pintype "bidirectional"))
    (pad "10" smd roundrect (at 0.8 0.2 90) (size 0.6 0.2) (layers "F.Cu" "F.Paste" "F.Mask") (roundrect_rratio 0.2272727273)
      (net 1 "GND") (pinfunction "GND") (pintype "power_in"))
    (pad "11" smd roundrect (at 0.8 -0.202 90) (size 0.6 0.2) (layers "F.Cu" "F.Paste" "F.Mask") (roundrect_rratio 0.2272727273)
      (net 1 "GND") (pinfunction "GND") (pintype "passive"))
    (pad "12" smd roundrect (at 0.8 -0.6 90) (size 0.6 0.2) (layers "F.Cu" "F.Paste" "F.Mask") (roundrect_rratio 0.2272727273)
      (net 128 "/Reset logic/MIO38") (pinfunction "2B2") (pintype "bidirectional"))
    (pad "13" smd roundrect (at 0.598 -1.2 180) (size 0.6 0.2) (layers "F.Cu" "F.Paste" "F.Mask") (roundrect_rratio 0.2272727273)
      (net 130 "/Reset logic/MIO44") (pinfunction "2B1") (pintype "bidirectional"))
    (pad "14" smd roundrect (at 0.2 -1.2 180) (size 0.6 0.2) (layers "F.Cu" "F.Paste" "F.Mask") (roundrect_rratio 0.2272727273)
      (net 130 "/Reset logic/MIO44") (pinfunction "1B2") (pintype "bidirectional"))
    (pad "15" smd roundrect (at -0.202 -1.2 180) (size 0.6 0.2) (layers "F.Cu" "F.Paste" "F.Mask") (roundrect_rratio 0.2272727273)
      (net 127 "/Reset logic/MIO43") (pinfunction "1B1") (pintype "bidirectional"))
    (pad "16" smd roundrect (at -0.6 -1.2 180) (size 0.6 0.2) (layers "F.Cu" "F.Paste" "F.Mask") (roundrect_rratio 0.2272727273)
      (net 161 "/Reset logic/PS_RST") (pinfunction "2~{OE}") (pintype "input"))
  )

  (footprint "kria-k26-devboard-footprints:D_SOD-323F" (layer "F.Cu")
    (at 102.7 143.75)
    (property "Author" "Antmicro")
    (property "License" "Apache-2.0")
    (property "MPN" "1N4148WS")
    (property "Manufacturer" "ON Semiconductor")
    (property "Sheetfile" "reset.kicad_sch")
    (property "Sheetname" "Reset logic")
    (property "ki_description" "Small Signal Fast Switching Diode")
    (attr smd)
    (fp_text reference "D5" (at -0.77 1.67) (layer "F.SilkS")
        (effects (font (size 0.7 0.7) (thickness 0.15)) (justify left bottom))
    )
    (fp_text value "1N4148WS" (at -1.7 1.9) (layer "F.Fab") hide
        (effects (font (size 0.7 0.7) (thickness 0.15)) (justify left bottom))
    )
    (fp_text user "${REFERENCE}" (at -1.8 3.2) (layer "F.Fab") hide
        (effects (font (size 0.7 0.7) (thickness 0.15)) (justify left bottom))
    )
    (fp_text user "Author: Antmicro" (at -1.8 4.46) (layer "F.Fab") hide
        (effects (font (size 0.7 0.7) (thickness 0.15)) (justify left bottom))
    )
    (fp_text user "License: Apache-2.0" (at -1.8 5.8) (layer "F.Fab") hide
        (effects (font (size 0.7 0.7) (thickness 0.15)) (justify left bottom))
    )
    (fp_line (start -0.975 -0.75) (end -0.975 -0.45)
      (stroke (width 0.15) (type solid)) (layer "F.SilkS"))
    (fp_line (start -0.975 0.748) (end -0.975 0.45)
      (stroke (width 0.15) (type solid)) (layer "F.SilkS"))
    (fp_line (start -0.625 -0.75) (end -0.975 -0.75)
      (stroke (width 0.15) (type solid)) (layer "F.SilkS"))
    (fp_line (start -0.625 0.748) (end -0.975 0.748)
      (stroke (width 0.15) (type solid)) (layer "F.SilkS"))
    (fp_line (start -0.5 -0.426) (end -0.5 0.424)
      (stroke (width 0.15) (type solid)) (layer "F.SilkS"))
    (fp_line (start 0.623 -0.75) (end 0.973 -0.75)
      (stroke (width 0.15) (type solid)) (layer "F.SilkS"))
    (fp_line (start 0.973 -0.75) (end 0.973 -0.45)
      (stroke (width 0.15) (type solid)) (layer "F.SilkS"))
    (fp_line (start 0.973 0.45) (end 0.973 0.748)
      (stroke (width 0.15) (type solid)) (layer "F.SilkS"))
    (fp_line (start 0.973 0.748) (end 0.623 0.748)
      (stroke (width 0.15) (type solid)) (layer "F.SilkS"))
    (fp_rect (start -1.6 -0.827) (end 1.599 0.825)
      (stroke (width 0.05) (type solid)) (fill none) (layer "F.CrtYd"))
    (fp_line (start -0.85 -0.625) (end 0.848 -0.625)
      (stroke (width 0.15) (type solid)) (layer "F.Fab"))
    (fp_line (start -0.85 0.623) (end -0.85 -0.625)
      (stroke (width 0.15) (type solid)) (layer "F.Fab"))
    (fp_line (start -0.85 0.623) (end 0.848 0.623)
      (stroke (width 0.15) (type solid)) (layer "F.Fab"))
    (fp_line (start 0.848 -0.625) (end 0.848 0.623)
      (stroke (width 0.15) (type solid)) (layer "F.Fab"))
    (pad "A" smd roundrect (at 1.05 0) (size 0.8 0.6) (layers "F.Cu" "F.Paste" "F.Mask") (roundrect_rratio 0.15)
      (net 336 "Net-(U31-MR_N)") (pinfunction "A") (pintype "passive"))
    (pad "K" smd roundrect (at -1.051 0) (size 0.8 0.6) (layers "F.Cu" "F.Paste" "F.Mask") (roundrect_rratio 0.15)
      (net 327 "Net-(D4-PadK)") (pinfunction "K") (pintype "passive"))
  )

  (footprint "kria-k26-devboard-footprints:QFN-14-1EP_2.5x3mm_EP1.15x1.65mm_ONSemi_MLP14A" (layer "F.Cu")
    (at 112.35 141.1 180)
    (descr "https://www.onsemi.cn/pub/Collateral/510CB.PDF")
    (property "Author" "Antmicro")
    (property "License" "Apache-2.0")
    (property "MPN" "74LCX07BQX")
    (property "Manufacturer" "ON Semiconductor")
    (property "Sheetfile" "reset.kicad_sch")
    (property "Sheetname" "Reset logic")
    (property "ki_description" "Buffer, Non-Inverting 6 Element 1 Bit per Element Open Drain Output 14-DQFN (3x2.5)")
    (property "ki_keywords" "SMT, LOGIC, IC, DRIVER")
    (attr smd)
    (fp_text reference "U36" (at -0.52 1.77 180) (layer "F.SilkS")
        (effects (font (size 0.7 0.7) (thickness 0.15)) (justify left bottom))
    )
    (fp_text value "74LCX07_QFN" (at 0 2.9 180) (layer "F.Fab") hide
        (effects (font (size 0.7 0.7) (thickness 0.15)) (justify left bottom))
    )
    (fp_text user "Author: Antmicro" (at -1.75 5.541 180) (layer "F.Fab") hide
        (effects (font (size 0.7 0.7) (thickness 0.15)) (justify left bottom))
    )
    (fp_text user "${REFERENCE}" (at -1.75 4.291 180) (layer "F.Fab") hide
        (effects (font (size 0.7 0.7) (thickness 0.15)) (justify left bottom))
    )
    (fp_text user "License: Apache-2.0" (at -1.75 6.791 180) (layer "F.Fab") hide
        (effects (font (size 0.7 0.7) (thickness 0.15)) (justify left bottom))
    )
    (fp_poly
      (pts
        (xy -0.382 -0.697)
        (xy 0.378 -0.697)
        (xy 0.378 -0.066)
        (xy -0.382 -0.066)
      )

      (stroke (width 0.01) (type solid)) (fill solid) (layer "F.Paste"))
    (fp_poly
      (pts
        (xy -0.382 0.063)
        (xy 0.378 0.063)
        (xy 0.378 0.693)
        (xy -0.382 0.693)
      )

      (stroke (width 0.01) (type solid)) (fill solid) (layer "F.Paste"))
    (fp_line (start -1.28 -1.53) (end -1.28 -1.25)
      (stroke (width 0.15) (type solid)) (layer "F.SilkS"))
    (fp_line (start -1.28 1.241) (end -1.279 1.532)
      (stroke (width 0.15) (type solid)) (layer "F.SilkS"))
    (fp_line (start -0.49 1.532) (end -1.279 1.532)
      (stroke (width 0.15) (type solid)) (layer "F.SilkS"))
    (fp_line (start 0.49 -1.532) (end 1.279 -1.532)
      (stroke (width 0.15) (type solid)) (layer "F.SilkS"))
    (fp_line (start 0.49 1.532) (end 1.279 1.532)
      (stroke (width 0.15) (type solid)) (layer "F.SilkS"))
    (fp_line (start 1.28 -1.24) (end 1.279 -1.532)
      (stroke (width 0.15) (type solid)) (layer "F.SilkS"))
    (fp_line (start 1.28 1.241) (end 1.279 1.532)
      (stroke (width 0.15) (type solid)) (layer "F.SilkS"))
    (fp_circle (center -0.7 -1.81) (end -0.65 -1.81)
      (stroke (width 0.15) (type solid)) (fill none) (layer "F.SilkS"))
    (fp_rect (start -1.75 -2.01) (end 1.75 1.98)
      (stroke (width 0.05) (type solid)) (fill none) (layer "F.CrtYd"))
    (fp_line (start -1.281 -1.532) (end 1.279 -1.532)
      (stroke (width 0.15) (type solid)) (layer "F.Fab"))
    (fp_line (start -1.281 1.531) (end -1.281 -1.532)
      (stroke (width 0.15) (type solid)) (layer "F.Fab"))
    (fp_line (start 1.279 -1.532) (end 1.279 1.531)
      (stroke (width 0.15) (type solid)) (layer "F.Fab"))
    (fp_line (start 1.279 1.531) (end -1.281 1.531)
      (stroke (width 0.15) (type solid)) (layer "F.Fab"))
    (pad "1" smd roundrect (at -0.25 -1.46 270) (size 0.78 0.27) (layers "F.Cu" "F.Paste" "F.Mask") (roundrect_rratio 0.07)
      (net 676 "Net-(U34-A_{1})") (pintype "input"))
    (pad "2" smd roundrect (at -1.21 -1) (size 0.78 0.27) (layers "F.Cu" "F.Paste" "F.Mask") (roundrect_rratio 0.07)
      (net 221 "/PCIE M2 key E /~{M2_PERST}") (pintype "open_collector"))
    (pad "3" smd roundrect (at -1.21 -0.501) (size 0.78 0.27) (layers "F.Cu" "F.Paste" "F.Mask") (roundrect_rratio 0.07)
      (net 679 "Net-(U33-2A2)") (pintype "input"))
    (pad "4" smd roundrect (at -1.21 0) (size 0.78 0.27) (layers "F.Cu" "F.Paste" "F.Mask") (roundrect_rratio 0.07)
      (net 176 "/Ethernet/~{ETH_RESET}") (pintype "open_collector"))
    (pad "5" smd roundrect (at -1.21 0.499) (size 0.78 0.27) (layers "F.Cu" "F.Paste" "F.Mask") (roundrect_rratio 0.07)
      (net 678 "Net-(U33-2A1)") (pintype "input"))
    (pad "6" smd roundrect (at -1.21 0.999) (size 0.78 0.27) (layers "F.Cu" "F.Paste" "F.Mask") (roundrect_rratio 0.07)
      (net 175 "/Reset logic/~{USB_HUB_RESET}") (pintype "open_collector"))
    (pad "7" smd roundrect (at -0.25 1.459 90) (size 0.78 0.27) (layers "F.Cu" "F.Paste" "F.Mask") (roundrect_rratio 0.07)
      (net 1 "GND") (pinfunction "GND") (pintype "power_in"))
    (pad "8" smd roundrect (at 0.248 1.459 90) (size 0.78 0.27) (layers "F.Cu" "F.Paste" "F.Mask") (roundrect_rratio 0.07)
      (net 178 "/Reset logic/~{USB_PHY_RESET}") (pintype "open_collector"))
    (pad "9" smd roundrect (at 1.209 0.999 180) (size 0.78 0.27) (layers "F.Cu" "F.Paste" "F.Mask") (roundrect_rratio 0.07)
      (net 677 "Net-(U33-1A2)") (pintype "input"))
    (pad "10" smd roundrect (at 1.209 0.499 180) (size 0.78 0.27) (layers "F.Cu" "F.Paste" "F.Mask") (roundrect_rratio 0.07)
      (net 177 "/Reset logic/~{SD_CARD_RESET}") (pintype "open_collector"))
    (pad "11" smd roundrect (at 1.209 0 180) (size 0.78 0.27) (layers "F.Cu" "F.Paste" "F.Mask") (roundrect_rratio 0.07)
      (net 675 "Net-(U33-1A1)") (pintype "input"))
    (pad "12" smd roundrect (at 1.209 -0.501 180) (size 0.78 0.27) (layers "F.Cu" "F.Paste" "F.Mask") (roundrect_rratio 0.07)
      (net 800 "unconnected-(U36-Pad12)") (pintype "open_collector+no_connect"))
    (pad "13" smd roundrect (at 1.209 -1 180) (size 0.78 0.27) (layers "F.Cu" "F.Paste" "F.Mask") (roundrect_rratio 0.07)
      (net 801 "unconnected-(U36-Pad13)") (pintype "input+no_connect"))
    (pad "14" smd roundrect (at 0.248 -1.46 270) (size 0.78 0.27) (layers "F.Cu" "F.Paste" "F.Mask") (roundrect_rratio 0.07)
      (net 15 "PS_3V3") (pinfunction "VCC") (pintype "power_in"))
    (pad "15" smd rect (at -0.002 0 270) (size 1.65 1.15) (layers "F.Cu" "F.Mask")
      (net 733 "unconnected-(U36G-DAP-Pad15)") (pinfunction "DAP") (pintype "no_connect"))
  )

  (footprint "kria-k26-devboard-footprints:SOT-23-5" (layer "F.Cu")
    (at 97.675 141.675001 90)
    (property "Author" "Antmicro")
    (property "License" "Apache-2.0")
    (property "MPN" "TPS3840PH30DBVR")
    (property "Manufacturer" "Texas Instruments")
    (property "Sheetfile" "reset.kicad_sch")
    (property "Sheetname" "Reset logic")
    (property "ki_description" "Voltage supervisor")
    (property "ki_keywords" "SMT, PMIC, IC, CONTROLLER")
    (attr smd)
    (fp_text reference "U32" (at 0.865001 0.405 90) (layer "F.SilkS")
        (effects (font (size 0.7 0.7) (thickness 0.15)) (justify left bottom))
    )
    (fp_text value "TPS3840PH30DBVR" (at 0.002 2.799 90) (layer "F.Fab") hide
        (effects (font (size 0.7 0.7) (thickness 0.15)) (justify left bottom))
    )
    (fp_text user "${REFERENCE}" (at -1.898 4.299 90) (layer "F.Fab") hide
        (effects (font (size 0.7 0.7) (thickness 0.15)) (justify left bottom))
    )
    (fp_text user "License: Apache-2.0" (at -1.898 6.7 90) (layer "F.Fab") hide
        (effects (font (size 0.7 0.7) (thickness 0.15)) (justify left bottom))
    )
    (fp_text user "Author: Antmicro" (at -1.898 5.499 90) (layer "F.Fab") hide
        (effects (font (size 0.7 0.7) (thickness 0.15)) (justify left bottom))
    )
    (fp_line (start -0.85 1.6) (end -0.85 1.301)
      (stroke (width 0.15) (type solid)) (layer "F.SilkS"))
    (fp_line (start -0.8 -1.6) (end -0.8 -1.3)
      (stroke (width 0.15) (type solid)) (layer "F.SilkS"))
    (fp_line (start -0.8 -1.6) (end -0.5 -1.6)
      (stroke (width 0.15) (type solid)) (layer "F.SilkS"))
    (fp_line (start -0.55 1.6) (end -0.85 1.6)
      (stroke (width 0.15) (type solid)) (layer "F.SilkS"))
    (fp_line (start 0.8 -1.6) (end 0.5 -1.6)
      (stroke (width 0.15) (type solid)) (layer "F.SilkS"))
    (fp_line (start 0.8 -1.3) (end 0.8 -1.6)
      (stroke (width 0.15) (type solid)) (layer "F.SilkS"))
    (fp_line (start 0.8 0.55) (end 0.8 -0.55)
      (stroke (width 0.15) (type solid)) (layer "F.SilkS"))
    (fp_line (start 0.8 1.3) (end 0.8 1.599)
      (stroke (width 0.15) (type solid)) (layer "F.SilkS"))
    (fp_line (start 0.8 1.599) (end 0.549 1.599)
      (stroke (width 0.15) (type solid)) (layer "F.SilkS"))
    (fp_circle (center -1.25 -1.5) (end -1.2 -1.5)
      (stroke (width 0.15) (type solid)) (fill solid) (layer "F.SilkS"))
    (fp_rect (start 1.9 -1.76) (end -1.9 1.75)
      (stroke (width 0.05) (type solid)) (fill none) (layer "F.CrtYd"))
    (fp_line (start -0.398 -1.526) (end -0.874 -1.05)
      (stroke (width 0.15) (type solid)) (layer "F.Fab"))
    (fp_rect (start 0.874 1.523) (end -0.873 -1.525)
      (stroke (width 0.15) (type solid)) (fill none) (layer "F.Fab"))
    (pad "1" smd rect (at -1.351 -0.951) (size 0.55 1) (layers "F.Cu" "F.Paste" "F.Mask")
      (net 174 "/Reset logic/PL_RST") (pinfunction "RESET") (pintype "open_collector"))
    (pad "2" smd rect (at -1.351 0) (size 0.55 1) (layers "F.Cu" "F.Paste" "F.Mask")
      (net 20 "PL_3V3") (pinfunction "VDD") (pintype "power_in"))
    (pad "3" smd rect (at -1.351 0.949) (size 0.55 1) (layers "F.Cu" "F.Paste" "F.Mask")
      (net 1 "GND") (pinfunction "GND") (pintype "power_in"))
    (pad "4" smd rect (at 1.35 0.949) (size 0.55 1) (layers "F.Cu" "F.Paste" "F.Mask")
      (net 335 "Net-(U32-MR_N)") (pinfunction "MR_N") (pintype "input"))
    (pad "5" smd rect (at 1.35 -0.951) (size 0.55 1) (layers "F.Cu" "F.Paste" "F.Mask")
      (net 246 "Net-(U32-CT)") (pinfunction "CT") (pintype "input"))
  )

  (footprint "kria-k26-devboard-footprints:SOD-123FL" (layer "F.Cu")
    (at 150.2 62.34)
    (property "Author" "Antmicro")
    (property "License" "Apache-2.0")
    (property "MPN" "SMF4L15CA")
    (property "Manufacturer" "Infineon Technologies")
    (property "Sheetfile" "usbc-socket.kicad_sch")
    (property "Sheetname" "USB-C socket")
    (property "ki_description" "SD Suppressors / TVS Diodes TVS SMF4L 15V Bidirectional")
    (attr smd)
    (fp_text reference "D26" (at 2.28 0.29) (layer "F.SilkS")
        (effects (font (size 0.7 0.7) (thickness 0.15)) (justify left bottom))
    )
    (fp_text value "SMF4L15CA" (at 0 1.967) (layer "F.Fab") hide
        (effects (font (size 0.7 0.7) (thickness 0.15)) (justify left bottom))
    )
    (fp_text user "Author: Antmicro" (at -2.406 5.168) (layer "F.Fab") hide
        (effects (font (size 0.7 0.7) (thickness 0.15)) (justify left bottom))
    )
    (fp_text user "${REFERENCE}" (at -2.406 3.967) (layer "F.Fab") hide
        (effects (font (size 0.7 0.7) (thickness 0.15)) (justify left bottom))
    )
    (fp_text user "License: Apache-2.0" (at -2.406 6.368) (layer "F.Fab") hide
        (effects (font (size 0.7 0.7) (thickness 0.15)) (justify left bottom))
    )
    (fp_line (start -2.3 -1.1) (end -2.3 1.1)
      (stroke (width 0.15) (type solid)) (layer "F.SilkS"))
    (fp_line (start -2.3 1.1) (end 0 1.1)
      (stroke (width 0.15) (type solid)) (layer "F.SilkS"))
    (fp_line (start 0 -1.1) (end -2.3 -1.1)
      (stroke (width 0.15) (type solid)) (layer "F.SilkS"))
    (fp_rect (start -2.35 -1.125) (end 2.35 1.125)
      (stroke (width 0.05) (type solid)) (fill none) (layer "F.CrtYd"))
    (fp_rect (start -1.825 -0.875) (end 1.824 0.873)
      (stroke (width 0.15) (type solid)) (fill none) (layer "F.Fab"))
    (fp_rect (start -0.775 -0.875) (end -0.525 0.875)
      (stroke (width 0.15) (type solid)) (fill solid) (layer "F.Fab"))
    (pad "1" smd roundrect (at -1.43 0) (size 1.34 1.8) (layers "F.Cu" "F.Paste" "F.Mask") (roundrect_rratio 0.14)
      (net 265 "/Debug and JTAG/USBC_VBUS") (pinfunction "1") (pintype "passive"))
    (pad "2" smd roundrect (at 1.429 0) (size 1.34 1.8) (layers "F.Cu" "F.Paste" "F.Mask") (roundrect_rratio 0.14)
      (net 1 "GND") (pinfunction "2") (pintype "passive"))
  )

  (footprint "kria-k26-devboard-footprints:SOD-123FL" (layer "F.Cu")
    (at 188.25 59.95)
    (property "Author" "Antmicro")
    (property "License" "Apache-2.0")
    (property "MPN" "SMF4L15CA")
    (property "Manufacturer" "Infineon Technologies")
    (property "Sheetfile" "dc-input.kicad_sch")
    (property "Sheetname" "DC Input")
    (property "ki_description" "SD Suppressors / TVS Diodes TVS SMF4L 15V Bidirectional")
    (attr smd)
    (fp_text reference "D27" (at 3.12 0.97 90) (layer "F.SilkS")
        (effects (font (size 0.7 0.7) (thickness 0.15)) (justify left bottom))
    )
    (fp_text value "SMF4L15CA" (at 0 1.967) (layer "F.Fab") hide
        (effects (font (size 0.7 0.7) (thickness 0.15)) (justify left bottom))
    )
    (fp_text user "License: Apache-2.0" (at -2.406 6.368) (layer "F.Fab") hide
        (effects (font (size 0.7 0.7) (thickness 0.15)) (justify left bottom))
    )
    (fp_text user "${REFERENCE}" (at -2.406 3.967) (layer "F.Fab") hide
        (effects (font (size 0.7 0.7) (thickness 0.15)) (justify left bottom))
    )
    (fp_text user "Author: Antmicro" (at -2.406 5.168) (layer "F.Fab") hide
        (effects (font (size 0.7 0.7) (thickness 0.15)) (justify left bottom))
    )
    (fp_line (start -2.3 -1.1) (end -2.3 1.1)
      (stroke (width 0.15) (type solid)) (layer "F.SilkS"))
    (fp_line (start -2.3 1.1) (end 0 1.1)
      (stroke (width 0.15) (type solid)) (layer "F.SilkS"))
    (fp_line (start 0 -1.1) (end -2.3 -1.1)
      (stroke (width 0.15) (type solid)) (layer "F.SilkS"))
    (fp_rect (start -2.35 -1.125) (end 2.35 1.125)
      (stroke (width 0.05) (type solid)) (fill none) (layer "F.CrtYd"))
    (fp_rect (start -1.825 -0.875) (end 1.824 0.873)
      (stroke (width 0.15) (type solid)) (fill none) (layer "F.Fab"))
    (fp_rect (start -0.775 -0.875) (end -0.525 0.875)
      (stroke (width 0.15) (type solid)) (fill solid) (layer "F.Fab"))
    (pad "1" smd roundrect (at -1.43 0) (size 1.34 1.8) (layers "F.Cu" "F.Paste" "F.Mask") (roundrect_rratio 0.14)
      (net 22 "/Power Supply/DC Input/DC_IN") (pinfunction "1") (pintype "passive"))
    (pad "2" smd roundrect (at 1.429 0) (size 1.34 1.8) (layers "F.Cu" "F.Paste" "F.Mask") (roundrect_rratio 0.14)
      (net 1 "GND") (pinfunction "2") (pintype "passive"))
  )

  (footprint "kria-k26-devboard-footprints:C_0402_1005Metric" (layer "F.Cu")
    (at 126.8 99 180)
    (descr "Capacitor SMD 0402")
    (tags "capacitor SMD 0402")
    (property "Author" "Antmicro")
    (property "Dielectric" "X5R")
    (property "License" "Apache-2.0")
    (property "MPN" "GRM155R61H104KE14D")
    (property "Manufacturer" "Murata")
    (property "Sheetfile" "usb.kicad_sch")
    (property "Sheetname" "USB")
    (property "Val" "100n")
    (property "Voltage" "50V")
    (property "ki_description" " ")
    (attr smd)
    (fp_text reference "C65" (at 1.15 -1.24 180) (layer "F.SilkS")
        (effects (font (size 0.7 0.7) (thickness 0.15)) (justify left bottom))
    )
    (fp_text value "C_100n_0402" (at 0 1.4 180) (layer "F.Fab") hide
        (effects (font (size 0.7 0.7) (thickness 0.15)) (justify left bottom))
    )
    (fp_text user "License: Apache-2.0" (at -0.932 5.17 180) (layer "F.Fab") hide
        (effects (font (size 0.7 0.7) (thickness 0.15)) (justify left bottom))
    )
    (fp_text user "${REFERENCE}" (at -0.932 3.168 180) (layer "F.Fab") hide
        (effects (font (size 0.7 0.7) (thickness 0.15)) (justify left bottom))
    )
    (fp_text user "Author: Antmicro" (at -0.932 4.17 180) (layer "F.Fab") hide
        (effects (font (size 0.7 0.7) (thickness 0.15)) (justify left bottom))
    )
    (fp_rect (start -0.94 -0.47) (end 0.94 0.47)
      (stroke (width 0.05) (type solid)) (fill none) (layer "F.CrtYd"))
    (fp_rect (start -0.499 -0.249) (end 0.499 0.249)
      (stroke (width 0.15) (type solid)) (fill none) (layer "F.Fab"))
    (pad "1" smd roundrect (at -0.484 0 180) (size 0.59 0.64) (layers "F.Cu" "F.Paste" "F.Mask") (roundrect_rratio 0.25)
      (net 17 "PS_1V8") (pintype "passive"))
    (pad "2" smd roundrect (at 0.484 0 180) (size 0.59 0.64) (layers "F.Cu" "F.Paste" "F.Mask") (roundrect_rratio 0.25)
      (net 1 "GND") (pintype "passive"))
  )

  (footprint "kria-k26-devboard-footprints:C_0402_1005Metric" (layer "F.Cu")
    (at 105.5 138.02 180)
    (descr "Capacitor SMD 0402")
    (tags "capacitor SMD 0402")
    (property "Author" "Antmicro")
    (property "Dielectric" "X5R")
    (property "License" "Apache-2.0")
    (property "MPN" "GRM155R61H104KE14D")
    (property "Manufacturer" "Murata")
    (property "Sheetfile" "i2c.kicad_sch")
    (property "Sheetname" "I2C ")
    (property "Val" "100n")
    (property "Voltage" "50V")
    (property "ki_description" " ")
    (attr smd)
    (fp_text reference "C35" (at 1.14 -1.41 180) (layer "F.SilkS")
        (effects (font (size 0.7 0.7) (thickness 0.15)) (justify left bottom))
    )
    (fp_text value "C_100n_0402" (at 0 1.4 180) (layer "F.Fab") hide
        (effects (font (size 0.7 0.7) (thickness 0.15)) (justify left bottom))
    )
    (fp_text user "License: Apache-2.0" (at -0.932 5.17 180) (layer "F.Fab") hide
        (effects (font (size 0.7 0.7) (thickness 0.15)) (justify left bottom))
    )
    (fp_text user "Author: Antmicro" (at -0.932 4.17 180) (layer "F.Fab") hide
        (effects (font (size 0.7 0.7) (thickness 0.15)) (justify left bottom))
    )
    (fp_text user "${REFERENCE}" (at -0.932 3.168 180) (layer "F.Fab") hide
        (effects (font (size 0.7 0.7) (thickness 0.15)) (justify left bottom))
    )
    (fp_rect (start -0.94 -0.47) (end 0.94 0.47)
      (stroke (width 0.05) (type solid)) (fill none) (layer "F.CrtYd"))
    (fp_rect (start -0.499 -0.249) (end 0.499 0.249)
      (stroke (width 0.15) (type solid)) (fill none) (layer "F.Fab"))
    (pad "1" smd roundrect (at -0.484 0 180) (size 0.59 0.64) (layers "F.Cu" "F.Paste" "F.Mask") (roundrect_rratio 0.25)
      (net 15 "PS_3V3") (pintype "passive"))
    (pad "2" smd roundrect (at 0.484 0 180) (size 0.59 0.64) (layers "F.Cu" "F.Paste" "F.Mask") (roundrect_rratio 0.25)
      (net 1 "GND") (pintype "passive"))
  )

  (footprint "kria-k26-devboard-footprints:R_0402_1005Metric" (layer "F.Cu")
    (at 105.5 137.075 180)
    (descr "Resistor SMD 0402")
    (tags "resistor SMD 0402")
    (property "Author" "Antmicro")
    (property "License" "Apache-2.0")
    (property "MPN" "CR0402-FX-1001GLF")
    (property "Manufacturer" "Bourns")
    (property "Sheetfile" "i2c.kicad_sch")
    (property "Sheetname" "I2C ")
    (property "Tolerance" "1%")
    (property "Val" "1k")
    (property "ki_description" "1k resistor in 0402 package with 1% tolerance")
    (attr smd)
    (fp_text reference "R36" (at -0.86 -0.995 180) (layer "F.SilkS")
        (effects (font (size 0.7 0.7) (thickness 0.15)) (justify left bottom))
    )
    (fp_text value "R_1k_0402" (at 0 1.4 180) (layer "F.Fab") hide
        (effects (font (size 0.7 0.7) (thickness 0.15)) (justify left bottom))
    )
    (fp_text user "Author: Antmicro" (at -0.95 4.169 180) (layer "F.Fab") hide
        (effects (font (size 0.7 0.7) (thickness 0.15)) (justify left bottom))
    )
    (fp_text user "License: Apache-2.0" (at -0.95 5.169 180) (layer "F.Fab") hide
        (effects (font (size 0.7 0.7) (thickness 0.15)) (justify left bottom))
    )
    (fp_text user "${REFERENCE}" (at -0.95 3.168 180) (layer "F.Fab") hide
        (effects (font (size 0.7 0.7) (thickness 0.15)) (justify left bottom))
    )
    (fp_rect (start -0.93 -0.47) (end 0.93 0.47)
      (stroke (width 0.05) (type solid)) (fill none) (layer "F.CrtYd"))
    (fp_rect (start -0.5 -0.25) (end 0.5 0.25)
      (stroke (width 0.15) (type solid)) (fill none) (layer "F.Fab"))
    (pad "1" smd roundrect (at -0.485 0 180) (size 0.59 0.64) (layers "F.Cu" "F.Paste" "F.Mask") (roundrect_rratio 0.25)
      (net 15 "PS_3V3") (pintype "passive"))
    (pad "2" smd roundrect (at 0.485 0 180) (size 0.59 0.64) (layers "F.Cu" "F.Paste" "F.Mask") (roundrect_rratio 0.25)
      (net 186 "/Debug and JTAG/~{EEPROM_WC}") (pintype "passive"))
  )

  (footprint "kria-k26-devboard-footprints:SOIC-8_3.9x4.9x1.75mm_P1.27mm" (layer "F.Cu")
    (at 99.4 133.95)
    (tags "Integrated Circuit")
    (property "Author" "Antmicro")
    (property "License" "Apache-2.0")
    (property "MPN" "PCA9306D,118")
    (property "Manufacturer" "NXP")
    (property "Sheetfile" "i2c.kicad_sch")
    (property "Sheetname" "I2C ")
    (property "ki_description" "Specialized Interface, I2C, SMBus, I2C Bus & SMBus Systems Applications, 0 V, 5 V, SOIC, 8 Pins")
    (property "ki_keywords" "SMT, LEVEL-SHIFTER, IC")
    (attr smd)
    (fp_text reference "U12" (at 0 -2.85) (layer "F.SilkS")
        (effects (font (size 0.7 0.7) (thickness 0.15)) (justify left bottom))
    )
    (fp_text value "PCA9306D_SOIC" (at 0 3.65) (layer "F.Fab")
        (effects (font (size 0.7 0.7) (thickness 0.15)) (justify left bottom))
    )
    (fp_text user "License: Apache-2.0" (at -3.476 5.099) (layer "F.Fab") hide
        (effects (font (size 0.7 0.7) (thickness 0.15)) (justify left bottom))
    )
    (fp_text user "${REFERENCE}" (at -3.476 7.099) (layer "F.Fab") hide
        (effects (font (size 0.7 0.7) (thickness 0.15)) (justify left bottom))
    )
    (fp_text user "Author: Antmicro" (at -3.476 6.099) (layer "F.Fab") hide
        (effects (font (size 0.7 0.7) (thickness 0.15)) (justify left bottom))
    )
    (fp_line (start -1.95 -2.452) (end 1.95 -2.45)
      (stroke (width 0.15) (type solid)) (layer "F.SilkS"))
    (fp_line (start -1.95 2.45) (end 1.95 2.45)
      (stroke (width 0.15) (type solid)) (layer "F.SilkS"))
    (fp_circle (center -2.4 -2.45) (end -2.35 -2.4)
      (stroke (width 0.15) (type solid)) (fill solid) (layer "F.SilkS"))
    (fp_rect (start -3.625 -2.7) (end 3.625 2.7)
      (stroke (width 0.05) (type solid)) (fill none) (layer "F.CrtYd"))
    (fp_line (start -1.95 -1.18) (end -0.683 -2.452)
      (stroke (width 0.15) (type solid)) (layer "F.Fab"))
    (fp_line (start -1.95 2.45) (end -1.95 -1.18)
      (stroke (width 0.15) (type solid)) (layer "F.Fab"))
    (fp_line (start -0.683 -2.452) (end 1.949 -2.452)
      (stroke (width 0.15) (type solid)) (layer "F.Fab"))
    (fp_line (start 1.949 -2.452) (end 1.949 2.45)
      (stroke (width 0.15) (type solid)) (layer "F.Fab"))
    (fp_line (start 1.949 2.45) (end -1.95 2.45)
      (stroke (width 0.15) (type solid)) (layer "F.Fab"))
    (pad "1" smd roundrect (at -2.714 -1.905 90) (size 0.65 1.525) (layers "F.Cu" "F.Paste" "F.Mask") (roundrect_rratio 0.25)
      (net 1 "GND") (pinfunction "GND") (pintype "power_in"))
    (pad "2" smd roundrect (at -2.714 -0.635 90) (size 0.65 1.525) (layers "F.Cu" "F.Paste" "F.Mask") (roundrect_rratio 0.25)
      (net 17 "PS_1V8") (pinfunction "VREF_{1}") (pintype "power_in"))
    (pad "3" smd roundrect (at -2.714 0.632 90) (size 0.65 1.525) (layers "F.Cu" "F.Paste" "F.Mask") (roundrect_rratio 0.25)
      (net 153 "/I2C /MIO24_I2C_SCK") (pinfunction "SCL_{1}") (pintype "bidirectional"))
    (pad "4" smd roundrect (at -2.714 1.902 90) (size 0.65 1.525) (layers "F.Cu" "F.Paste" "F.Mask") (roundrect_rratio 0.25)
      (net 432 "/I2C /MIO25_I2C_SDA") (pinfunction "SDA_{1}") (pintype "bidirectional"))
    (pad "5" smd roundrect (at 2.712 1.902 90) (size 0.65 1.525) (layers "F.Cu" "F.Paste" "F.Mask") (roundrect_rratio 0.25)
      (net 163 "/I2C /I2C_SDA_3V3") (pinfunction "SDA_{2}") (pintype "bidirectional"))
    (pad "6" smd roundrect (at 2.712 0.632 90) (size 0.65 1.525) (layers "F.Cu" "F.Paste" "F.Mask") (roundrect_rratio 0.25)
      (net 162 "/I2C /I2C_SCK_3V3") (pinfunction "SCL_{2}") (pintype "bidirectional"))
    (pad "7" smd roundrect (at 2.712 -0.635 90) (size 0.65 1.525) (layers "F.Cu" "F.Paste" "F.Mask") (roundrect_rratio 0.25)
      (net 324 "/I2C /Vref2") (pinfunction "VREF_{2}") (pintype "power_in"))
    (pad "8" smd roundrect (at 2.712 -1.905 90) (size 0.65 1.525) (layers "F.Cu" "F.Paste" "F.Mask") (roundrect_rratio 0.25)
      (net 324 "/I2C /Vref2") (pinfunction "EN") (pintype "input"))
  )

  (footprint "kria-k26-devboard-footprints:C_0402_1005Metric" (layer "F.Cu")
    (at 95.2 132.65 90)
    (descr "Capacitor SMD 0402")
    (tags "capacitor SMD 0402")
    (property "Author" "Antmicro")
    (property "Dielectric" "X5R")
    (property "License" "Apache-2.0")
    (property "MPN" "GRM155R61H104KE14D")
    (property "Manufacturer" "Murata")
    (property "Sheetfile" "i2c.kicad_sch")
    (property "Sheetname" "I2C ")
    (property "Val" "100n")
    (property "Voltage" "50V")
    (property "ki_description" " ")
    (attr smd)
    (fp_text reference "C32" (at 0.82 0.31 90) (layer "F.SilkS")
        (effects (font (size 0.7 0.7) (thickness 0.15)) (justify left bottom))
    )
    (fp_text value "C_100n_0402" (at 0 1.4 90) (layer "F.Fab") hide
        (effects (font (size 0.7 0.7) (thickness 0.15)) (justify left bottom))
    )
    (fp_text user "${REFERENCE}" (at -0.932 3.168 90) (layer "F.Fab") hide
        (effects (font (size 0.7 0.7) (thickness 0.15)) (justify left bottom))
    )
    (fp_text user "Author: Antmicro" (at -0.932 4.17 90) (layer "F.Fab") hide
        (effects (font (size 0.7 0.7) (thickness 0.15)) (justify left bottom))
    )
    (fp_text user "License: Apache-2.0" (at -0.932 5.17 90) (layer "F.Fab") hide
        (effects (font (size 0.7 0.7) (thickness 0.15)) (justify left bottom))
    )
    (fp_rect (start -0.94 -0.47) (end 0.94 0.47)
      (stroke (width 0.05) (type solid)) (fill none) (layer "F.CrtYd"))
    (fp_rect (start -0.499 -0.249) (end 0.499 0.249)
      (stroke (width 0.15) (type solid)) (fill none) (layer "F.Fab"))
    (pad "1" smd roundrect (at -0.484 0 90) (size 0.59 0.64) (layers "F.Cu" "F.Paste" "F.Mask") (roundrect_rratio 0.25)
      (net 17 "PS_1V8") (pintype "passive"))
    (pad "2" smd roundrect (at 0.484 0 90) (size 0.59 0.64) (layers "F.Cu" "F.Paste" "F.Mask") (roundrect_rratio 0.25)
      (net 1 "GND") (pintype "passive"))
  )

  (footprint "kria-k26-devboard-footprints:C_0402_1005Metric" (layer "F.Cu")
    (at 129.975 83.45 90)
    (descr "Capacitor SMD 0402")
    (tags "capacitor SMD 0402")
    (property "Author" "Antmicro")
    (property "Dielectric" "")
    (property "License" "Apache-2.0")
    (property "MPN" "GRM155R61A475MEAAD")
    (property "Manufacturer" "Murata")
    (property "Sheetfile" "usb.kicad_sch")
    (property "Sheetname" "USB")
    (property "Val" "4u7")
    (property "Voltage" "")
    (property "ki_description" " ")
    (attr smd)
    (fp_text reference "C42" (at -1.12 1.295 90) (layer "F.SilkS")
        (effects (font (size 0.7 0.7) (thickness 0.15)) (justify left bottom))
    )
    (fp_text value "C_4u7_0402" (at 0 1.4 90) (layer "F.Fab") hide
        (effects (font (size 0.7 0.7) (thickness 0.15)) (justify left bottom))
    )
    (fp_text user "License: Apache-2.0" (at -0.932 5.17 90) (layer "F.Fab") hide
        (effects (font (size 0.7 0.7) (thickness 0.15)) (justify left bottom))
    )
    (fp_text user "Author: Antmicro" (at -0.932 4.17 90) (layer "F.Fab") hide
        (effects (font (size 0.7 0.7) (thickness 0.15)) (justify left bottom))
    )
    (fp_text user "${REFERENCE}" (at -0.932 3.168 90) (layer "F.Fab") hide
        (effects (font (size 0.7 0.7) (thickness 0.15)) (justify left bottom))
    )
    (fp_rect (start -0.94 -0.47) (end 0.94 0.47)
      (stroke (width 0.05) (type solid)) (fill none) (layer "F.CrtYd"))
    (fp_rect (start -0.499 -0.249) (end 0.499 0.249)
      (stroke (width 0.15) (type solid)) (fill none) (layer "F.Fab"))
    (pad "1" smd roundrect (at -0.484 0 90) (size 0.59 0.64) (layers "F.Cu" "F.Paste" "F.Mask") (roundrect_rratio 0.25)
      (net 15 "PS_3V3") (pintype "passive"))
    (pad "2" smd roundrect (at 0.484 0 90) (size 0.59 0.64) (layers "F.Cu" "F.Paste" "F.Mask") (roundrect_rratio 0.25)
      (net 1 "GND") (pintype "passive"))
  )

  (footprint "kria-k26-devboard-footprints:C_0402_1005Metric" (layer "F.Cu")
    (at 130 90.7 180)
    (descr "Capacitor SMD 0402")
    (tags "capacitor SMD 0402")
    (property "Author" "Antmicro")
    (property "Dielectric" "")
    (property "License" "Apache-2.0")
    (property "MPN" "GRM155R61A475MEAAD")
    (property "Manufacturer" "Murata")
    (property "Sheetfile" "usb.kicad_sch")
    (property "Sheetname" "USB")
    (property "Val" "4u7")
    (property "Voltage" "")
    (property "ki_description" " ")
    (attr smd)
    (fp_text reference "C40" (at -0.72 -0.4 180) (layer "F.SilkS")
        (effects (font (size 0.7 0.7) (thickness 0.15)) (justify left bottom))
    )
    (fp_text value "C_4u7_0402" (at 0 1.4 180) (layer "F.Fab") hide
        (effects (font (size 0.7 0.7) (thickness 0.15)) (justify left bottom))
    )
    (fp_text user "Author: Antmicro" (at -0.932 4.17 180) (layer "F.Fab") hide
        (effects (font (size 0.7 0.7) (thickness 0.15)) (justify left bottom))
    )
    (fp_text user "License: Apache-2.0" (at -0.932 5.17 180) (layer "F.Fab") hide
        (effects (font (size 0.7 0.7) (thickness 0.15)) (justify left bottom))
    )
    (fp_text user "${REFERENCE}" (at -0.932 3.168 180) (layer "F.Fab") hide
        (effects (font (size 0.7 0.7) (thickness 0.15)) (justify left bottom))
    )
    (fp_rect (start -0.94 -0.47) (end 0.94 0.47)
      (stroke (width 0.05) (type solid)) (fill none) (layer "F.CrtYd"))
    (fp_rect (start -0.499 -0.249) (end 0.499 0.249)
      (stroke (width 0.15) (type solid)) (fill none) (layer "F.Fab"))
    (pad "1" smd roundrect (at -0.484 0 180) (size 0.59 0.64) (layers "F.Cu" "F.Paste" "F.Mask") (roundrect_rratio 0.25)
      (net 18 "PS_1V2") (pintype "passive"))
    (pad "2" smd roundrect (at 0.484 0 180) (size 0.59 0.64) (layers "F.Cu" "F.Paste" "F.Mask") (roundrect_rratio 0.25)
      (net 1 "GND") (pintype "passive"))
  )

  (footprint "kria-k26-devboard-footprints:D_SOD-323F" (layer "F.Cu")
    (at 94.89 141.6 -90)
    (property "Author" "Antmicro")
    (property "License" "Apache-2.0")
    (property "MPN" "1N4148WS")
    (property "Manufacturer" "ON Semiconductor")
    (property "Sheetfile" "reset.kicad_sch")
    (property "Sheetname" "Reset logic")
    (property "ki_description" "Small Signal Fast Switching Diode")
    (attr smd)
    (fp_text reference "D4" (at 2.25 0.91 -90) (layer "F.SilkS")
        (effects (font (size 0.7 0.7) (thickness 0.15)) (justify left bottom))
    )
    (fp_text value "1N4148WS" (at -1.7 1.9 -90) (layer "F.Fab") hide
        (effects (font (size 0.7 0.7) (thickness 0.15)) (justify left bottom))
    )
    (fp_text user "License: Apache-2.0" (at -1.8 5.8 -90) (layer "F.Fab") hide
        (effects (font (size 0.7 0.7) (thickness 0.15)) (justify left bottom))
    )
    (fp_text user "${REFERENCE}" (at -1.8 3.2 -90) (layer "F.Fab") hide
        (effects (font (size 0.7 0.7) (thickness 0.15)) (justify left bottom))
    )
    (fp_text user "Author: Antmicro" (at -1.8 4.46 -90) (layer "F.Fab") hide
        (effects (font (size 0.7 0.7) (thickness 0.15)) (justify left bottom))
    )
    (fp_line (start -0.975 -0.75) (end -0.975 -0.45)
      (stroke (width 0.15) (type solid)) (layer "F.SilkS"))
    (fp_line (start -0.975 0.748) (end -0.975 0.45)
      (stroke (width 0.15) (type solid)) (layer "F.SilkS"))
    (fp_line (start -0.625 -0.75) (end -0.975 -0.75)
      (stroke (width 0.15) (type solid)) (layer "F.SilkS"))
    (fp_line (start -0.625 0.748) (end -0.975 0.748)
      (stroke (width 0.15) (type solid)) (layer "F.SilkS"))
    (fp_line (start -0.5 -0.426) (end -0.5 0.424)
      (stroke (width 0.15) (type solid)) (layer "F.SilkS"))
    (fp_line (start 0.623 -0.75) (end 0.973 -0.75)
      (stroke (width 0.15) (type solid)) (layer "F.SilkS"))
    (fp_line (start 0.973 -0.75) (end 0.973 -0.45)
      (stroke (width 0.15) (type solid)) (layer "F.SilkS"))
    (fp_line (start 0.973 0.45) (end 0.973 0.748)
      (stroke (width 0.15) (type solid)) (layer "F.SilkS"))
    (fp_line (start 0.973 0.748) (end 0.623 0.748)
      (stroke (width 0.15) (type solid)) (layer "F.SilkS"))
    (fp_rect (start -1.6 -0.827) (end 1.599 0.825)
      (stroke (width 0.05) (type solid)) (fill none) (layer "F.CrtYd"))
    (fp_line (start -0.85 -0.625) (end 0.848 -0.625)
      (stroke (width 0.15) (type solid)) (layer "F.Fab"))
    (fp_line (start -0.85 0.623) (end -0.85 -0.625)
      (stroke (width 0.15) (type solid)) (layer "F.Fab"))
    (fp_line (start -0.85 0.623) (end 0.848 0.623)
      (stroke (width 0.15) (type solid)) (layer "F.Fab"))
    (fp_line (start 0.848 -0.625) (end 0.848 0.623)
      (stroke (width 0.15) (type solid)) (layer "F.Fab"))
    (pad "A" smd roundrect (at 1.05 0 270) (size 0.8 0.6) (layers "F.Cu" "F.Paste" "F.Mask") (roundrect_rratio 0.15)
      (net 335 "Net-(U32-MR_N)") (pinfunction "A") (pintype "passive"))
    (pad "K" smd roundrect (at -1.051 0 270) (size 0.8 0.6) (layers "F.Cu" "F.Paste" "F.Mask") (roundrect_rratio 0.15)
      (net 327 "Net-(D4-PadK)") (pinfunction "K") (pintype "passive"))
  )

  (footprint "kria-k26-devboard-footprints:C_0402_1005Metric" (layer "F.Cu")
    (at 98.315 144.3)
    (descr "Capacitor SMD 0402")
    (tags "capacitor SMD 0402")
    (property "Author" "Antmicro")
    (property "Dielectric" "X5R")
    (property "License" "Apache-2.0")
    (property "MPN" "GRM155R61H104KE14D")
    (property "Manufacturer" "Murata")
    (property "Sheetfile" "reset.kicad_sch")
    (property "Sheetname" "Reset logic")
    (property "Val" "100n")
    (property "Voltage" "50V")
    (property "ki_description" " ")
    (attr smd)
    (fp_text reference "C133" (at -1.165 1.3) (layer "F.SilkS")
        (effects (font (size 0.7 0.7) (thickness 0.15)) (justify left bottom))
    )
    (fp_text value "C_100n_0402" (at 0 1.4) (layer "F.Fab") hide
        (effects (font (size 0.7 0.7) (thickness 0.15)) (justify left bottom))
    )
    (fp_text user "Author: Antmicro" (at -0.932 4.17) (layer "F.Fab") hide
        (effects (font (size 0.7 0.7) (thickness 0.15)) (justify left bottom))
    )
    (fp_text user "${REFERENCE}" (at -0.932 3.168) (layer "F.Fab") hide
        (effects (font (size 0.7 0.7) (thickness 0.15)) (justify left bottom))
    )
    (fp_text user "License: Apache-2.0" (at -0.932 5.17) (layer "F.Fab") hide
        (effects (font (size 0.7 0.7) (thickness 0.15)) (justify left bottom))
    )
    (fp_rect (start -0.94 -0.47) (end 0.94 0.47)
      (stroke (width 0.05) (type solid)) (fill none) (layer "F.CrtYd"))
    (fp_rect (start -0.499 -0.249) (end 0.499 0.249)
      (stroke (width 0.15) (type solid)) (fill none) (layer "F.Fab"))
    (pad "1" smd roundrect (at -0.484 0) (size 0.59 0.64) (layers "F.Cu" "F.Paste" "F.Mask") (roundrect_rratio 0.25)
      (net 20 "PL_3V3") (pintype "passive"))
    (pad "2" smd roundrect (at 0.484 0) (size 0.59 0.64) (layers "F.Cu" "F.Paste" "F.Mask") (roundrect_rratio 0.25)
      (net 1 "GND") (pintype "passive"))
  )

  (footprint "kria-k26-devboard-footprints:SOT-753" (layer "F.Cu")
    (at 95.514999 145.875 180)
    (property "Author" "Antmicro")
    (property "License" "Apache-2.0")
    (property "MPN" "SN74LVC1G125DBVR")
    (property "Manufacturer" "Texas Instruments")
    (property "Sheetfile" "reset.kicad_sch")
    (property "Sheetname" "Reset logic")
    (property "ki_description" "Buffer, 74LVC1G125, 1.65 V to 5.5 V, SOT-23-5")
    (property "ki_keywords" "SMT, LOGIC, IC, BUFFER, TRANSCEIVER, DRIVER")
    (attr smd)
    (fp_text reference "U35" (at 1.864999 -1.175 270) (layer "F.SilkS")
        (effects (font (size 0.7 0.7) (thickness 0.15)) (justify left bottom))
    )
    (fp_text value "SN74LVC1G125_SOT" (at 0 2.9 180) (layer "F.Fab") hide
        (effects (font (size 0.7 0.7) (thickness 0.15)) (justify left bottom))
    )
    (fp_text user "License: Apache-2.0" (at -1.651 8.425 180) (layer "F.Fab") hide
        (effects (font (size 0.7 0.7) (thickness 0.15)) (justify left bottom))
    )
    (fp_text user "${REFERENCE}" (at -1.651 6.025 180) (layer "F.Fab") hide
        (effects (font (size 0.7 0.7) (thickness 0.15)) (justify left bottom))
    )
    (fp_text user "Author: Antmicro" (at -1.651 7.225 180) (layer "F.Fab") hide
        (effects (font (size 0.7 0.7) (thickness 0.15)) (justify left bottom))
    )
    (fp_line (start -1.651 -1) (end -1.651 -0.701)
      (stroke (width 0.15) (type solid)) (layer "F.SilkS"))
    (fp_line (start -1.648 1) (end -1.648 0.677)
      (stroke (width 0.15) (type solid)) (layer "F.SilkS"))
    (fp_line (start -1.5 -1) (end -1.651 -1)
      (stroke (width 0.15) (type solid)) (layer "F.SilkS"))
    (fp_line (start -1.5 1) (end -1.648 1)
      (stroke (width 0.15) (type solid)) (layer "F.SilkS"))
    (fp_line (start 1.5 -1) (end 1.648 -1)
      (stroke (width 0.15) (type solid)) (layer "F.SilkS"))
    (fp_line (start 1.5 0.998) (end 1.648 0.998)
      (stroke (width 0.15) (type solid)) (layer "F.SilkS"))
    (fp_line (start 1.648 -1) (end 1.648 -0.677)
      (stroke (width 0.15) (type solid)) (layer "F.SilkS"))
    (fp_line (start 1.648 0.998) (end 1.648 0.699)
      (stroke (width 0.15) (type solid)) (layer "F.SilkS"))
    (fp_circle (center -1.5 1.35) (end -1.46 1.4)
      (stroke (width 0.15) (type solid)) (fill solid) (layer "F.SilkS"))
    (fp_rect (start -1.7 -1.901) (end 1.699 1.898)
      (stroke (width 0.05) (type solid)) (fill none) (layer "F.CrtYd"))
    (fp_line (start -1.526 -0.875) (end 1.523 -0.875)
      (stroke (width 0.15) (type solid)) (layer "F.Fab"))
    (fp_line (start -1.526 0.623) (end -1.526 -0.875)
      (stroke (width 0.15) (type solid)) (layer "F.Fab"))
    (fp_line (start -1.526 0.623) (end -1.351 0.873)
      (stroke (width 0.15) (type solid)) (layer "F.Fab"))
    (fp_line (start -1.351 0.873) (end 1.523 0.873)
      (stroke (width 0.15) (type solid)) (layer "F.Fab"))
    (fp_line (start 1.523 -0.875) (end 1.523 0.873)
      (stroke (width 0.15) (type solid)) (layer "F.Fab"))
    (pad "1" smd roundrect (at -0.951 1.35 180) (size 0.6 1.05) (layers "F.Cu" "F.Paste" "F.Mask") (roundrect_rratio 0.25)
      (net 174 "/Reset logic/PL_RST") (pinfunction "~{OE}") (pintype "input"))
    (pad "2" smd roundrect (at 0 1.35 180) (size 0.6 1.05) (layers "F.Cu" "F.Paste" "F.Mask") (roundrect_rratio 0.25)
      (net 129 "/Reset logic/HDA02") (pinfunction "A") (pintype "input"))
    (pad "3" smd roundrect (at 0.949 1.35 180) (size 0.6 1.05) (layers "F.Cu" "F.Paste" "F.Mask") (roundrect_rratio 0.25)
      (net 1 "GND") (pinfunction "GND") (pintype "power_in"))
    (pad "4" smd roundrect (at 0.949 -1.351 180) (size 0.6 1.05) (layers "F.Cu" "F.Paste" "F.Mask") (roundrect_rratio 0.25)
      (net 198 "/Camera interface/CAM0_RST") (pinfunction "Y") (pintype "output"))
    (pad "5" smd roundrect (at -0.951 -1.351 180) (size 0.6 1.05) (layers "F.Cu" "F.Paste" "F.Mask") (roundrect_rratio 0.25)
      (net 20 "PL_3V3") (pinfunction "V_{CC}") (pintype "power_in"))
  )

  (footprint "kria-k26-devboard-footprints:R_0402_1005Metric" (layer "F.Cu")
    (at 127.83 91.56 180)
    (descr "Resistor SMD 0402")
    (tags "resistor SMD 0402")
    (property "Author" "Antmicro")
    (property "License" "Apache-2.0")
    (property "MPN" "CR0402-FX-1202GLF")
    (property "Manufacturer" "Bourns")
    (property "Sheetfile" "usb.kicad_sch")
    (property "Sheetname" "USB")
    (property "Tolerance" "1%")
    (property "Val" "12k")
    (property "ki_description" "12k resistor in 0402 package with 1% tolerance")
    (attr smd)
    (fp_text reference "R52" (at -0.79 -0.57 180) (layer "F.SilkS")
        (effects (font (size 0.7 0.7) (thickness 0.15)) (justify left bottom))
    )
    (fp_text value "R_12k_0402" (at 0 1.4 180) (layer "F.Fab") hide
        (effects (font (size 0.7 0.7) (thickness 0.15)) (justify left bottom))
    )
    (fp_text user "${REFERENCE}" (at -0.95 3.168 180) (layer "F.Fab") hide
        (effects (font (size 0.7 0.7) (thickness 0.15)) (justify left bottom))
    )
    (fp_text user "License: Apache-2.0" (at -0.95 5.169 180) (layer "F.Fab") hide
        (effects (font (size 0.7 0.7) (thickness 0.15)) (justify left bottom))
    )
    (fp_text user "Author: Antmicro" (at -0.95 4.169 180) (layer "F.Fab") hide
        (effects (font (size 0.7 0.7) (thickness 0.15)) (justify left bottom))
    )
    (fp_rect (start -0.93 -0.47) (end 0.93 0.47)
      (stroke (width 0.05) (type solid)) (fill none) (layer "F.CrtYd"))
    (fp_rect (start -0.5 -0.25) (end 0.5 0.25)
      (stroke (width 0.15) (type solid)) (fill none) (layer "F.Fab"))
    (pad "1" smd roundrect (at -0.485 0 180) (size 0.59 0.64) (layers "F.Cu" "F.Paste" "F.Mask") (roundrect_rratio 0.25)
      (net 1 "GND") (pintype "passive"))
    (pad "2" smd roundrect (at 0.485 0 180) (size 0.59 0.64) (layers "F.Cu" "F.Paste" "F.Mask") (roundrect_rratio 0.25)
      (net 655 "Net-(U17-RBIAS)") (pintype "passive"))
  )

  (footprint "kria-k26-devboard-footprints:SOT-416" (layer "F.Cu")
    (at 107.7 136.2 90)
    (descr "SOT-416")
    (tags "SOT-416")
    (property "Author" "Antmicro")
    (property "License" "Apache-2.0")
    (property "MPN" "DTC014TEBTL")
    (property "Manufacturer" "ROHM Semiconductor")
    (property "Sheetfile" "reset.kicad_sch")
    (property "Sheetname" "Reset logic")
    (property "ki_description" "Digital NPN Transistor, 10k/NONE, EMT-3")
    (attr smd)
    (fp_text reference "Q8" (at 1.08 -0.85 180) (layer "F.SilkS")
        (effects (font (size 0.7 0.7) (thickness 0.15)) (justify left bottom))
    )
    (fp_text value "DTC014T_SOT-416" (at 0 2 90) (layer "F.Fab") hide
        (effects (font (size 0.7 0.7) (thickness 0.15)) (justify left bottom))
    )
    (fp_text user "Author: Antmicro" (at -1 4.602 90) (layer "F.Fab") hide
        (effects (font (size 0.7 0.7) (thickness 0.15)) (justify left bottom))
    )
    (fp_text user "${REFERENCE}" (at -1 3.4 90) (layer "F.Fab") hide
        (effects (font (size 0.7 0.7) (thickness 0.15)) (justify left bottom))
    )
    (fp_text user "License: Apache-2.0" (at -1 5.802 90) (layer "F.Fab") hide
        (effects (font (size 0.7 0.7) (thickness 0.15)) (justify left bottom))
    )
    (fp_line (start -0.5 -0.15) (end -0.5 0.15)
      (stroke (width 0.15) (type solid)) (layer "F.SilkS"))
    (fp_line (start 0.5 0.9) (end -0.5 0.9)
      (stroke (width 0.15) (type solid)) (layer "F.SilkS"))
    (fp_line (start 0.5 0.9) (end 0.5 0.7)
      (stroke (width 0.15) (type solid)) (layer "F.SilkS"))
    (fp_line (start 0.508 -0.9) (end -0.5 -0.9)
      (stroke (width 0.15) (type solid)) (layer "F.SilkS"))
    (fp_line (start 0.508 -0.9) (end 0.508 -0.592)
      (stroke (width 0.15) (type solid)) (layer "F.SilkS"))
    (fp_rect (start -1 -1.05) (end 1 1.05)
      (stroke (width 0.05) (type solid)) (fill none) (layer "F.CrtYd"))
    (fp_line (start -0.05 -0.9) (end -0.45 -0.5)
      (stroke (width 0.15) (type solid)) (layer "F.Fab"))
    (fp_rect (start 0.45 0.9) (end -0.45 -0.9)
      (stroke (width 0.15) (type solid)) (fill none) (layer "F.Fab"))
    (pad "1" smd rect (at -0.652 -0.5 90) (size 0.6 0.5) (layers "F.Cu" "F.Paste" "F.Mask")
      (net 161 "/Reset logic/PS_RST") (pinfunction "B") (pintype "input"))
    (pad "2" smd rect (at -0.652 0.498 90) (size 0.6 0.5) (layers "F.Cu" "F.Paste" "F.Mask")
      (net 1 "GND") (pinfunction "E") (pintype "passive"))
    (pad "3" smd rect (at 0.65 0 90) (size 0.6 0.5) (layers "F.Cu" "F.Paste" "F.Mask")
      (net 151 "/Debug and JTAG/~{PS_POR}") (pinfunction "C") (pintype "passive"))
  )

  (footprint "kria-k26-devboard-footprints:SOT-416" (layer "F.Cu")
    (at 111.000001 136.2 90)
    (descr "SOT-416")
    (tags "SOT-416")
    (property "Author" "Antmicro")
    (property "License" "Apache-2.0")
    (property "MPN" "DTC014TEBTL")
    (property "Manufacturer" "ROHM Semiconductor")
    (property "Sheetfile" "reset.kicad_sch")
    (property "Sheetname" "Reset logic")
    (property "ki_description" "Digital NPN Transistor, 10k/NONE, EMT-3")
    (attr smd)
    (fp_text reference "Q9" (at 1.11 -0.800001 180) (layer "F.SilkS")
        (effects (font (size 0.7 0.7) (thickness 0.15)) (justify left bottom))
    )
    (fp_text value "DTC014T_SOT-416" (at 0 2 90) (layer "F.Fab") hide
        (effects (font (size 0.7 0.7) (thickness 0.15)) (justify left bottom))
    )
    (fp_text user "License: Apache-2.0" (at -1 5.802 90) (layer "F.Fab") hide
        (effects (font (size 0.7 0.7) (thickness 0.15)) (justify left bottom))
    )
    (fp_text user "${REFERENCE}" (at -1 3.4 90) (layer "F.Fab") hide
        (effects (font (size 0.7 0.7) (thickness 0.15)) (justify left bottom))
    )
    (fp_text user "Author: Antmicro" (at -1 4.602 90) (layer "F.Fab") hide
        (effects (font (size 0.7 0.7) (thickness 0.15)) (justify left bottom))
    )
    (fp_line (start -0.5 -0.15) (end -0.5 0.15)
      (stroke (width 0.15) (type solid)) (layer "F.SilkS"))
    (fp_line (start 0.5 0.9) (end -0.5 0.9)
      (stroke (width 0.15) (type solid)) (layer "F.SilkS"))
    (fp_line (start 0.5 0.9) (end 0.5 0.7)
      (stroke (width 0.15) (type solid)) (layer "F.SilkS"))
    (fp_line (start 0.508 -0.9) (end -0.5 -0.9)
      (stroke (width 0.15) (type solid)) (layer "F.SilkS"))
    (fp_line (start 0.508 -0.9) (end 0.508 -0.592)
      (stroke (width 0.15) (type solid)) (layer "F.SilkS"))
    (fp_rect (start -1 -1.05) (end 1 1.05)
      (stroke (width 0.05) (type solid)) (fill none) (layer "F.CrtYd"))
    (fp_line (start -0.05 -0.9) (end -0.45 -0.5)
      (stroke (width 0.15) (type solid)) (layer "F.Fab"))
    (fp_rect (start 0.45 0.9) (end -0.45 -0.9)
      (stroke (width 0.15) (type solid)) (fill none) (layer "F.Fab"))
    (pad "1" smd rect (at -0.652 -0.5 90) (size 0.6 0.5) (layers "F.Cu" "F.Paste" "F.Mask")
      (net 161 "/Reset logic/PS_RST") (pinfunction "B") (pintype "input"))
    (pad "2" smd rect (at -0.652 0.498 90) (size 0.6 0.5) (layers "F.Cu" "F.Paste" "F.Mask")
      (net 1 "GND") (pinfunction "E") (pintype "passive"))
    (pad "3" smd rect (at 0.65 0 90) (size 0.6 0.5) (layers "F.Cu" "F.Paste" "F.Mask")
      (net 185 "/Clock distribution/PS_CLK_EN") (pinfunction "C") (pintype "passive"))
  )

  (footprint "kria-k26-devboard-footprints:SOT-416" (layer "F.Cu")
    (at 118.65 120.45 180)
    (descr "SOT-416")
    (tags "SOT-416")
    (property "Author" "Antmicro")
    (property "License" "Apache-2.0")
    (property "MPN" "DTC014TEBTL")
    (property "Manufacturer" "ROHM Semiconductor")
    (property "Sheetfile" "clock.kicad_sch")
    (property "Sheetname" "Clock distribution")
    (property "ki_description" "Digital NPN Transistor, 10k/NONE, EMT-3")
    (attr smd)
    (fp_text reference "Q3" (at -1.19 -0.39 180) (layer "F.SilkS")
        (effects (font (size 0.7 0.7) (thickness 0.15)) (justify left bottom))
    )
    (fp_text value "DTC014T_SOT-416" (at 0 2 180) (layer "F.Fab") hide
        (effects (font (size 0.7 0.7) (thickness 0.15)) (justify left bottom))
    )
    (fp_text user "Author: Antmicro" (at -1 4.602 180) (layer "F.Fab") hide
        (effects (font (size 0.7 0.7) (thickness 0.15)) (justify left bottom))
    )
    (fp_text user "${REFERENCE}" (at -1 3.4 180) (layer "F.Fab") hide
        (effects (font (size 0.7 0.7) (thickness 0.15)) (justify left bottom))
    )
    (fp_text user "License: Apache-2.0" (at -1 5.802 180) (layer "F.Fab") hide
        (effects (font (size 0.7 0.7) (thickness 0.15)) (justify left bottom))
    )
    (fp_line (start -0.5 -0.15) (end -0.5 0.15)
      (stroke (width 0.15) (type solid)) (layer "F.SilkS"))
    (fp_line (start 0.5 0.9) (end -0.5 0.9)
      (stroke (width 0.15) (type solid)) (layer "F.SilkS"))
    (fp_line (start 0.5 0.9) (end 0.5 0.7)
      (stroke (width 0.15) (type solid)) (layer "F.SilkS"))
    (fp_line (start 0.508 -0.9) (end -0.5 -0.9)
      (stroke (width 0.15) (type solid)) (layer "F.SilkS"))
    (fp_line (start 0.508 -0.9) (end 0.508 -0.592)
      (stroke (width 0.15) (type solid)) (layer "F.SilkS"))
    (fp_rect (start -1 -1.05) (end 1 1.05)
      (stroke (width 0.05) (type solid)) (fill none) (layer "F.CrtYd"))
    (fp_line (start -0.05 -0.9) (end -0.45 -0.5)
      (stroke (width 0.15) (type solid)) (layer "F.Fab"))
    (fp_rect (start 0.45 0.9) (end -0.45 -0.9)
      (stroke (width 0.15) (type solid)) (fill none) (layer "F.Fab"))
    (pad "1" smd rect (at -0.652 -0.5 180) (size 0.6 0.5) (layers "F.Cu" "F.Paste" "F.Mask")
      (net 185 "/Clock distribution/PS_CLK_EN") (pinfunction "B") (pintype "input"))
    (pad "2" smd rect (at -0.652 0.498 180) (size 0.6 0.5) (layers "F.Cu" "F.Paste" "F.Mask")
      (net 1 "GND") (pinfunction "E") (pintype "passive"))
    (pad "3" smd rect (at 0.65 0 180) (size 0.6 0.5) (layers "F.Cu" "F.Paste" "F.Mask")
      (net 429 "Net-(Q3-C)") (pinfunction "C") (pintype "passive"))
  )

  (footprint "kria-k26-devboard-footprints:R_0402_1005Metric" (layer "F.Cu")
    (at 143.153411 111.695908 -90)
    (descr "Resistor SMD 0402")
    (tags "resistor SMD 0402")
    (property "Author" "Antmicro")
    (property "License" "Apache-2.0")
    (property "MPN" "CR0402-FX-2201GLF")
    (property "Manufacturer" "Bourns")
    (property "Sheetfile" "debug.kicad_sch")
    (property "Sheetname" "Debug and JTAG")
    (property "Tolerance" "1%")
    (property "Val" "2k2")
    (property "ki_description" "2k2 resistor in 0402 package with 1% tolerance")
    (attr smd)
    (fp_text reference "R107" (at -0.525908 5.803411) (layer "F.SilkS")
        (effects (font (size 0.7 0.7) (thickness 0.15)) (justify left bottom))
    )
    (fp_text value "R_2k2_0402" (at 0 1.4 -90) (layer "F.Fab") hide
        (effects (font (size 0.7 0.7) (thickness 0.15)) (justify left bottom))
    )
    (fp_text user "${REFERENCE}" (at -0.95 3.168 -90) (layer "F.Fab") hide
        (effects (font (size 0.7 0.7) (thickness 0.15)) (justify left bottom))
    )
    (fp_text user "License: Apache-2.0" (at -0.95 5.169 -90) (layer "F.Fab") hide
        (effects (font (size 0.7 0.7) (thickness 0.15)) (justify left bottom))
    )
    (fp_text user "Author: Antmicro" (at -0.95 4.169 -90) (layer "F.Fab") hide
        (effects (font (size 0.7 0.7) (thickness 0.15)) (justify left bottom))
    )
    (fp_rect (start -0.93 -0.47) (end 0.93 0.47)
      (stroke (width 0.05) (type solid)) (fill none) (layer "F.CrtYd"))
    (fp_rect (start -0.5 -0.25) (end 0.5 0.25)
      (stroke (width 0.15) (type solid)) (fill none) (layer "F.Fab"))
    (pad "1" smd roundrect (at -0.485 0 270) (size 0.59 0.64) (layers "F.Cu" "F.Paste" "F.Mask") (roundrect_rratio 0.25)
      (net 682 "Net-(U39-DO)") (pintype "passive"))
    (pad "2" smd roundrect (at 0.485 0 270) (size 0.59 0.64) (layers "F.Cu" "F.Paste" "F.Mask") (roundrect_rratio 0.25)
      (net 230 "/Debug and JTAG/EEDATA") (pintype "passive"))
  )

  (footprint "kria-k26-devboard-footprints:R_0402_1005Metric" (layer "F.Cu")
    (at 141.15 110.31)
    (descr "Resistor SMD 0402")
    (tags "resistor SMD 0402")
    (property "Author" "Antmicro")
    (property "License" "Apache-2.0")
    (property "MPN" "CR0402-FX-1002GLF")
    (property "Manufacturer" "Bourns")
    (property "Sheetfile" "debug.kicad_sch")
    (property "Sheetname" "Debug and JTAG")
    (property "Tolerance" "1%")
    (property "Val" "10k")
    (property "ki_description" "10k resistor in 0402 package with 1% tolerance")
    (attr smd)
    (fp_text reference "R106" (at -1.87 -0.58) (layer "F.SilkS")
        (effects (font (size 0.7 0.7) (thickness 0.15)) (justify left bottom))
    )
    (fp_text value "R_10k_0402" (at 0 1.4) (layer "F.Fab") hide
        (effects (font (size 0.7 0.7) (thickness 0.15)) (justify left bottom))
    )
    (fp_text user "Author: Antmicro" (at -0.95 4.169) (layer "F.Fab") hide
        (effects (font (size 0.7 0.7) (thickness 0.15)) (justify left bottom))
    )
    (fp_text user "${REFERENCE}" (at -0.95 3.168) (layer "F.Fab") hide
        (effects (font (size 0.7 0.7) (thickness 0.15)) (justify left bottom))
    )
    (fp_text user "License: Apache-2.0" (at -0.95 5.169) (layer "F.Fab") hide
        (effects (font (size 0.7 0.7) (thickness 0.15)) (justify left bottom))
    )
    (fp_rect (start -0.93 -0.47) (end 0.93 0.47)
      (stroke (width 0.05) (type solid)) (fill none) (layer "F.CrtYd"))
    (fp_rect (start -0.5 -0.25) (end 0.5 0.25)
      (stroke (width 0.15) (type solid)) (fill none) (layer "F.Fab"))
    (pad "1" smd roundrect (at -0.485 0) (size 0.59 0.64) (layers "F.Cu" "F.Paste" "F.Mask") (roundrect_rratio 0.25)
      (net 138 "/Debug and JTAG/USB_3V3") (pintype "passive"))
    (pad "2" smd roundrect (at 0.485 0) (size 0.59 0.64) (layers "F.Cu" "F.Paste" "F.Mask") (roundrect_rratio 0.25)
      (net 682 "Net-(U39-DO)") (pintype "passive"))
  )

  (footprint "kria-k26-devboard-footprints:R_0402_1005Metric" (layer "F.Cu")
    (at 143.0827 113.605097 90)
    (descr "Resistor SMD 0402")
    (tags "resistor SMD 0402")
    (property "Author" "Antmicro")
    (property "License" "Apache-2.0")
    (property "MPN" "CR0402-FX-1002GLF")
    (property "Manufacturer" "Bourns")
    (property "Sheetfile" "debug.kicad_sch")
    (property "Sheetname" "Debug and JTAG")
    (property "Tolerance" "1%")
    (property "Val" "10k")
    (property "ki_description" "10k resistor in 0402 package with 1% tolerance")
    (attr smd)
    (fp_text reference "R108" (at -0.844903 -7.5827) (layer "F.SilkS")
        (effects (font (size 0.7 0.7) (thickness 0.15)) (justify left bottom))
    )
    (fp_text value "R_10k_0402" (at 0 1.4 90) (layer "F.Fab") hide
        (effects (font (size 0.7 0.7) (thickness 0.15)) (justify left bottom))
    )
    (fp_text user "Author: Antmicro" (at -0.95 4.169 90) (layer "F.Fab") hide
        (effects (font (size 0.7 0.7) (thickness 0.15)) (justify left bottom))
    )
    (fp_text user "${REFERENCE}" (at -0.95 3.168 90) (layer "F.Fab") hide
        (effects (font (size 0.7 0.7) (thickness 0.15)) (justify left bottom))
    )
    (fp_text user "License: Apache-2.0" (at -0.95 5.169 90) (layer "F.Fab") hide
        (effects (font (size 0.7 0.7) (thickness 0.15)) (justify left bottom))
    )
    (fp_rect (start -0.93 -0.47) (end 0.93 0.47)
      (stroke (width 0.05) (type solid)) (fill none) (layer "F.CrtYd"))
    (fp_rect (start -0.5 -0.25) (end 0.5 0.25)
      (stroke (width 0.15) (type solid)) (fill none) (layer "F.Fab"))
    (pad "1" smd roundrect (at -0.485 0 90) (size 0.59 0.64) (layers "F.Cu" "F.Paste" "F.Mask") (roundrect_rratio 0.25)
      (net 138 "/Debug and JTAG/USB_3V3") (pintype "passive"))
    (pad "2" smd roundrect (at 0.485 0 90) (size 0.59 0.64) (layers "F.Cu" "F.Paste" "F.Mask") (roundrect_rratio 0.25)
      (net 231 "/Debug and JTAG/EECLK") (pintype "passive"))
  )

  (footprint "kria-k26-devboard-footprints:R_0402_1005Metric" (layer "F.Cu")
    (at 141.46 115.07)
    (descr "Resistor SMD 0402")
    (tags "resistor SMD 0402")
    (property "Author" "Antmicro")
    (property "License" "Apache-2.0")
    (property "MPN" "CR0402-FX-1002GLF")
    (property "Manufacturer" "Bourns")
    (property "Sheetfile" "debug.kicad_sch")
    (property "Sheetname" "Debug and JTAG")
    (property "Tolerance" "1%")
    (property "Val" "10k")
    (property "ki_description" "10k resistor in 0402 package with 1% tolerance")
    (attr smd)
    (fp_text reference "R110" (at -3.68 0.33) (layer "F.SilkS")
        (effects (font (size 0.7 0.7) (thickness 0.15)) (justify left bottom))
    )
    (fp_text value "R_10k_0402" (at 0 1.4) (layer "F.Fab") hide
        (effects (font (size 0.7 0.7) (thickness 0.15)) (justify left bottom))
    )
    (fp_text user "Author: Antmicro" (at -0.95 4.169) (layer "F.Fab") hide
        (effects (font (size 0.7 0.7) (thickness 0.15)) (justify left bottom))
    )
    (fp_text user "License: Apache-2.0" (at -0.95 5.169) (layer "F.Fab") hide
        (effects (font (size 0.7 0.7) (thickness 0.15)) (justify left bottom))
    )
    (fp_text user "${REFERENCE}" (at -0.95 3.168) (layer "F.Fab") hide
        (effects (font (size 0.7 0.7) (thickness 0.15)) (justify left bottom))
    )
    (fp_rect (start -0.93 -0.47) (end 0.93 0.47)
      (stroke (width 0.05) (type solid)) (fill none) (layer "F.CrtYd"))
    (fp_rect (start -0.5 -0.25) (end 0.5 0.25)
      (stroke (width 0.15) (type solid)) (fill none) (layer "F.Fab"))
    (pad "1" smd roundrect (at -0.485 0) (size 0.59 0.64) (layers "F.Cu" "F.Paste" "F.Mask") (roundrect_rratio 0.25)
      (net 138 "/Debug and JTAG/USB_3V3") (pintype "passive"))
    (pad "2" smd roundrect (at 0.485 0) (size 0.59 0.64) (layers "F.Cu" "F.Paste" "F.Mask") (roundrect_rratio 0.25)
      (net 232 "/Debug and JTAG/EECS") (pintype "passive"))
  )

  (footprint "kria-k26-devboard-footprints:DFN-8-1EP_3x2mm_P0.5mm_EP1.36x1.46mm" (layer "F.Cu")
    (at 140.50176 112.579792 180)
    (property "Author" "Antmicro")
    (property "License" "Apache-2.0")
    (property "MPN" "93LC66BT-I/MC")
    (property "Manufacturer" "Microchip Technology")
    (property "Sheetfile" "debug.kicad_sch")
    (property "Sheetname" "Debug and JTAG")
    (property "ki_description" "EEPROM, 4 Kbit, 256 x 16bit, Serial Microwire, 2 MHz, DFN-EP-8")
    (property "ki_keywords" "SMT, MEMORY, IC, EEPROM")
    (attr smd)
    (fp_text reference "U39" (at 1.96176 1.139792 90) (layer "F.SilkS")
        (effects (font (size 0.7 0.7) (thickness 0.15)) (justify right bottom))
    )
    (fp_text value "93LC66BT_DFN" (at 0 2.2) (layer "F.Fab")
        (effects (font (size 0.7 0.7) (thickness 0.15)) (justify right bottom))
    )
    (fp_text user "${REFERENCE}" (at -2.27 4.052) (layer "F.Fab") hide
        (effects (font (size 0.7 0.7) (thickness 0.15)) (justify right bottom))
    )
    (fp_text user "License: Apache-2.0" (at -2.27 6.453) (layer "F.Fab") hide
        (effects (font (size 0.7 0.7) (thickness 0.15)) (justify right bottom))
    )
    (fp_text user "Author: Antmicro" (at -2.27 5.253) (layer "F.Fab") hide
        (effects (font (size 0.7 0.7) (thickness 0.15)) (justify right bottom))
    )
    (fp_line (start -1.501 1.111) (end 1.518 1.111)
      (stroke (width 0.15) (type solid)) (layer "F.SilkS"))
    (fp_line (start 1.498 -1.12) (end -1.511 -1.12)
      (stroke (width 0.15) (type solid)) (layer "F.SilkS"))
    (fp_circle (center -1.751 -1.05) (end -1.7 -1.05)
      (stroke (width 0.15) (type solid)) (fill solid) (layer "F.SilkS"))
    (fp_line (start -1.901 -1.262) (end 1.889 -1.262)
      (stroke (width 0.05) (type solid)) (layer "F.CrtYd"))
    (fp_line (start -1.901 1.228) (end -1.901 -1.262)
      (stroke (width 0.05) (type solid)) (layer "F.CrtYd"))
    (fp_line (start 1.889 -1.262) (end 1.889 1.228)
      (stroke (width 0.05) (type solid)) (layer "F.CrtYd"))
    (fp_line (start 1.889 1.228) (end -1.901 1.228)
      (stroke (width 0.05) (type solid)) (layer "F.CrtYd"))
    (fp_line (start -1.501 0.99) (end -1.501 -0.989)
      (stroke (width 0.15) (type solid)) (layer "F.Fab"))
    (fp_line (start 1.498 -0.999) (end -1.491 -0.999)
      (stroke (width 0.15) (type solid)) (layer "F.Fab"))
    (fp_line (start 1.498 -0.999) (end 1.498 0.99)
      (stroke (width 0.15) (type solid)) (layer "F.Fab"))
    (fp_line (start 1.498 0.999) (end -1.501 0.999)
      (stroke (width 0.15) (type solid)) (layer "F.Fab"))
    (pad "1" smd rect (at -1.451 -0.749 90) (size 0.3 0.7) (layers "F.Cu" "F.Paste" "F.Mask")
      (net 232 "/Debug and JTAG/EECS") (pinfunction "CS") (pintype "input"))
    (pad "2" smd rect (at -1.451 -0.25 90) (size 0.3 0.7) (layers "F.Cu" "F.Paste" "F.Mask")
      (net 231 "/Debug and JTAG/EECLK") (pinfunction "SCLK") (pintype "input"))
    (pad "3" smd rect (at -1.451 0.249 90) (size 0.3 0.7) (layers "F.Cu" "F.Paste" "F.Mask")
      (net 230 "/Debug and JTAG/EEDATA") (pinfunction "DI") (pintype "input"))
    (pad "4" smd rect (at -1.451 0.75 90) (size 0.3 0.7) (layers "F.Cu" "F.Paste" "F.Mask")
      (net 682 "Net-(U39-DO)") (pinfunction "DO") (pintype "tri_state"))
    (pad "5" smd rect (at 1.448 0.75 90) (size 0.3 0.7) (layers "F.Cu" "F.Paste" "F.Mask")
      (net 1 "GND") (pinfunction "GND") (pintype "power_in"))
    (pad "6" smd rect (at 1.448 0.249 90) (size 0.3 0.7) (layers "F.Cu" "F.Paste" "F.Mask")
      (net 736 "unconnected-(U39-ORG-Pad6)") (pinfunction "ORG") (pintype "input+no_connect"))
    (pad "7" smd rect (at 1.448 -0.25 90) (size 0.3 0.7) (layers "F.Cu" "F.Paste" "F.Mask")
      (net 737 "unconnected-(U39-NC-Pad7)") (pinfunction "NC") (pintype "no_connect"))
    (pad "8" smd rect (at 1.448 -0.749 90) (size 0.3 0.7) (layers "F.Cu" "F.Paste" "F.Mask")
      (net 138 "/Debug and JTAG/USB_3V3") (pinfunction "VCC") (pintype "power_in"))
    (pad "9" smd rect (at 0 0 90) (size 1.5 1.7) (layers "F.Cu" "F.Paste" "F.Mask")
      (net 1 "GND") (pinfunction "EP") (pintype "passive") (solder_paste_margin_ratio -0.1))
  )

  (footprint "kria-k26-devboard-footprints:R_0402_1005Metric" (layer "F.Cu")
    (at 141.578409 128.118647 180)
    (descr "Resistor SMD 0402")
    (tags "resistor SMD 0402")
    (property "Author" "Antmicro")
    (property "License" "Apache-2.0")
    (property "MPN" "CR0402-FX-1002GLF")
    (property "Manufacturer" "Bourns")
    (property "Sheetfile" "debug.kicad_sch")
    (property "Sheetname" "Debug and JTAG")
    (property "Tolerance" "1%")
    (property "Val" "10k")
    (property "ki_description" "10k resistor in 0402 package with 1% tolerance")
    (attr smd)
    (fp_text reference "R113" (at -0.891591 -0.391353 180) (layer "F.SilkS")
        (effects (font (size 0.7 0.7) (thickness 0.15)) (justify left bottom))
    )
    (fp_text value "R_10k_0402" (at 0 1.4 180) (layer "F.Fab") hide
        (effects (font (size 0.7 0.7) (thickness 0.15)) (justify left bottom))
    )
    (fp_text user "License: Apache-2.0" (at -0.95 5.169 180) (layer "F.Fab") hide
        (effects (font (size 0.7 0.7) (thickness 0.15)) (justify left bottom))
    )
    (fp_text user "Author: Antmicro" (at -0.95 4.169 180) (layer "F.Fab") hide
        (effects (font (size 0.7 0.7) (thickness 0.15)) (justify left bottom))
    )
    (fp_text user "${REFERENCE}" (at -0.95 3.168 180) (layer "F.Fab") hide
        (effects (font (size 0.7 0.7) (thickness 0.15)) (justify left bottom))
    )
    (fp_rect (start -0.93 -0.47) (end 0.93 0.47)
      (stroke (width 0.05) (type solid)) (fill none) (layer "F.CrtYd"))
    (fp_rect (start -0.5 -0.25) (end 0.5 0.25)
      (stroke (width 0.15) (type solid)) (fill none) (layer "F.Fab"))
    (pad "1" smd roundrect (at -0.485 0 180) (size 0.59 0.64) (layers "F.Cu" "F.Paste" "F.Mask") (roundrect_rratio 0.25)
      (net 138 "/Debug and JTAG/USB_3V3") (pintype "passive"))
    (pad "2" smd roundrect (at 0.485 0 180) (size 0.59 0.64) (layers "F.Cu" "F.Paste" "F.Mask") (roundrect_rratio 0.25)
      (net 683 "Net-(U44-B_{1})") (pintype "passive"))
  )

  (footprint "kria-k26-devboard-footprints:R_0402_1005Metric" (layer "F.Cu")
    (at 139.109974 128.122183)
    (descr "Resistor SMD 0402")
    (tags "resistor SMD 0402")
    (property "Author" "Antmicro")
    (property "License" "Apache-2.0")
    (property "MPN" "CR0402-FX-1002GLF")
    (property "Manufacturer" "Bourns")
    (property "Sheetfile" "debug.kicad_sch")
    (property "Sheetname" "Debug and JTAG")
    (property "Tolerance" "1%")
    (property "Val" "10k")
    (property "ki_description" "10k resistor in 0402 package with 1% tolerance")
    (attr smd)
    (fp_text reference "R114" (at -0.409974 -0.222183 90) (layer "F.SilkS")
        (effects (font (size 0.7 0.7) (thickness 0.15)) (justify left bottom))
    )
    (fp_text value "R_10k_0402" (at 0 1.4) (layer "F.Fab") hide
        (effects (font (size 0.7 0.7) (thickness 0.15)) (justify left bottom))
    )
    (fp_text user "${REFERENCE}" (at -0.95 3.168) (layer "F.Fab") hide
        (effects (font (size 0.7 0.7) (thickness 0.15)) (justify left bottom))
    )
    (fp_text user "Author: Antmicro" (at -0.95 4.169) (layer "F.Fab") hide
        (effects (font (size 0.7 0.7) (thickness 0.15)) (justify left bottom))
    )
    (fp_text user "License: Apache-2.0" (at -0.95 5.169) (layer "F.Fab") hide
        (effects (font (size 0.7 0.7) (thickness 0.15)) (justify left bottom))
    )
    (fp_rect (start -0.93 -0.47) (end 0.93 0.47)
      (stroke (width 0.05) (type solid)) (fill none) (layer "F.CrtYd"))
    (fp_rect (start -0.5 -0.25) (end 0.5 0.25)
      (stroke (width 0.15) (type solid)) (fill none) (layer "F.Fab"))
    (pad "1" smd roundrect (at -0.485 0) (size 0.59 0.64) (layers "F.Cu" "F.Paste" "F.Mask") (roundrect_rratio 0.25)
      (net 138 "/Debug and JTAG/USB_3V3") (pintype "passive"))
    (pad "2" smd roundrect (at 0.485 0) (size 0.59 0.64) (layers "F.Cu" "F.Paste" "F.Mask") (roundrect_rratio 0.25)
      (net 684 "Net-(U44-B_{2})") (pintype "passive"))
  )

  (footprint "kria-k26-devboard-footprints:UQFN-10_1.4x1.8x0.5mm_P0.4mm" (layer "F.Cu")
    (at 140.371787 126.024767)
    (property "Author" "Antmicro")
    (property "License" "Apache-2.0")
    (property "MPN" "SN74AVC2T245RSWR")
    (property "Manufacturer" "Texas Instruments")
    (property "Sheetfile" "debug.kicad_sch")
    (property "Sheetname" "Debug and JTAG")
    (property "ki_description" "Transceiver Non Inverting, AVC Family, 2 Input, 12 mA, 2.4 ns, 1.2 V to 3.6 V, LFCSP-10")
    (property "ki_keywords" "SMT, LOGIC, IC, LEVEL-SHIFTER, VOLTAGE")
    (attr smd)
    (fp_text reference "U44" (at -0.531787 -1.584767) (layer "F.SilkS")
        (effects (font (size 0.7 0.7) (thickness 0.15)) (justify left bottom))
    )
    (fp_text value "SN74AVC2T245_UQFN" (at 0 2.4) (layer "F.Fab") hide
        (effects (font (size 0.7 0.7) (thickness 0.15)) (justify left bottom))
    )
    (fp_text user "Author: Antmicro" (at -0.657 5.7) (layer "F.Fab") hide
        (effects (font (size 0.7 0.7) (thickness 0.15)) (justify left bottom))
    )
    (fp_text user "${REFERENCE}" (at -0.657 4.498) (layer "F.Fab") hide
        (effects (font (size 0.7 0.7) (thickness 0.15)) (justify left bottom))
    )
    (fp_text user "License: Apache-2.0" (at -0.657 6.9) (layer "F.Fab") hide
        (effects (font (size 0.7 0.7) (thickness 0.15)) (justify left bottom))
    )
    (fp_line (start -0.7305 -0.552) (end -1.2005 -0.552)
      (stroke (width 0.15) (type solid)) (layer "F.SilkS"))
    (fp_line (start -0.7305 -0.552) (end -0.7305 -0.93)
      (stroke (width 0.15) (type solid)) (layer "F.SilkS"))
    (fp_circle (center -1.0515 -1.151) (end -0.9805 -1.151)
      (stroke (width 0.15) (type solid)) (fill none) (layer "F.SilkS"))
    (fp_rect (start -1.3 -1.5) (end 1.3 1.5)
      (stroke (width 0.05) (type solid)) (fill none) (layer "F.CrtYd"))
    (fp_line (start -0.7 -0.4) (end -0.175 -0.925)
      (stroke (width 0.15) (type solid)) (layer "F.Fab"))
    (fp_line (start -0.7 0.93) (end -0.7 -0.4)
      (stroke (width 0.15) (type solid)) (layer "F.Fab"))
    (fp_line (start -0.175 -0.925) (end 0.7295 -0.925)
      (stroke (width 0.15) (type solid)) (layer "F.Fab"))
    (fp_line (start 0.725 0.93) (end -0.7 0.93)
      (stroke (width 0.15) (type solid)) (layer "F.Fab"))
    (fp_line (start 0.7295 -0.925) (end 0.725 0.93)
      (stroke (width 0.15) (type solid)) (layer "F.Fab"))
    (pad "1" smd roundrect (at -0.6445 -0.2) (size 0.81 0.22) (layers "F.Cu" "F.Paste" "F.Mask") (roundrect_rratio 0.25)
      (net 138 "/Debug and JTAG/USB_3V3") (pinfunction "DIR_{2}") (pintype "input"))
    (pad "2" smd roundrect (at -0.6445 0.2) (size 0.81 0.22) (layers "F.Cu" "F.Paste" "F.Mask") (roundrect_rratio 0.25)
      (net 164 "/Debug and JTAG/~{FTDI_PWREN}") (pinfunction "~{OE}") (pintype "input"))
    (pad "3" smd roundrect (at -0.4015 0.844 270) (size 0.81 0.22) (layers "F.Cu" "F.Paste" "F.Mask") (roundrect_rratio 0.25)
      (net 1 "GND") (pinfunction "GND") (pintype "power_in"))
    (pad "4" smd roundrect (at 0.0005 0.844 270) (size 0.81 0.22) (layers "F.Cu" "F.Paste" "F.Mask") (roundrect_rratio 0.25)
      (net 684 "Net-(U44-B_{2})") (pinfunction "B_{2}") (pintype "bidirectional"))
    (pad "5" smd roundrect (at 0.3995 0.844 270) (size 0.81 0.22) (layers "F.Cu" "F.Paste" "F.Mask") (roundrect_rratio 0.25)
      (net 683 "Net-(U44-B_{1})") (pinfunction "B_{1}") (pintype "bidirectional"))
    (pad "6" smd roundrect (at 0.6455 0.2) (size 0.81 0.22) (layers "F.Cu" "F.Paste" "F.Mask") (roundrect_rratio 0.25)
      (net 138 "/Debug and JTAG/USB_3V3") (pinfunction "V_{CCB}") (pintype "power_in"))
    (pad "7" smd roundrect (at 0.6455 -0.2) (size 0.81 0.22) (layers "F.Cu" "F.Paste" "F.Mask") (roundrect_rratio 0.25)
      (net 138 "/Debug and JTAG/USB_3V3") (pinfunction "V_{CCA}") (pintype "power_in"))
    (pad "8" smd roundrect (at 0.3995 -0.847 270) (size 0.81 0.22) (layers "F.Cu" "F.Paste" "F.Mask") (roundrect_rratio 0.25)
      (net 167 "/Debug and JTAG/~{FTDI_PS_SRST}") (pinfunction "A_{1}") (pintype "bidirectional"))
    (pad "9" smd roundrect (at 0.0005 -0.847 270) (size 0.81 0.22) (layers "F.Cu" "F.Paste" "F.Mask") (roundrect_rratio 0.25)
      (net 168 "/Debug and JTAG/~{FTDI_PS_POR}") (pinfunction "A_{2}") (pintype "bidirectional"))
    (pad "10" smd roundrect (at -0.4015 -0.847 270) (size 0.81 0.22) (layers "F.Cu" "F.Paste" "F.Mask") (roundrect_rratio 0.25)
      (net 138 "/Debug and JTAG/USB_3V3") (pinfunction "DIR_{1}") (pintype "input"))
  )

  (footprint "kria-k26-devboard-footprints:SOT-363" (layer "F.Cu")
    (at 140.401076 130.15 -90)
    (property "Author" "Antmicro")
    (property "License" "Apache-2.0")
    (property "MPN" "NC7WZ07P6X")
    (property "Manufacturer" "ON Semiconductor")
    (property "Sheetfile" "debug.kicad_sch")
    (property "Sheetname" "Debug and JTAG")
    (property "ki_description" "Buffer, 1.65 V to 5.5 V, SC-70-6")
    (property "ki_keywords" "SMT, DRIVER, IC, LOGIC")
    (attr smd)
    (fp_text reference "U46" (at 2.19 -1.088924 180) (layer "F.SilkS")
        (effects (font (size 0.7 0.7) (thickness 0.15)) (justify right bottom))
    )
    (fp_text value "NC7WZ07_SC" (at 0 2.2 90) (layer "F.Fab") hide
        (effects (font (size 0.7 0.7) (thickness 0.15)) (justify right bottom))
    )
    (fp_text user "License: Apache-2.0" (at -1.3 5.2 90) (layer "F.Fab") hide
        (effects (font (size 0.7 0.7) (thickness 0.15)) (justify right bottom))
    )
    (fp_text user "Author: Antmicro" (at -1.3 6.4 90) (layer "F.Fab") hide
        (effects (font (size 0.7 0.7) (thickness 0.15)) (justify right bottom))
    )
    (fp_text user "${REFERENCE}" (at -1.3 4 90) (layer "F.Fab") hide
        (effects (font (size 0.7 0.7) (thickness 0.15)) (justify right bottom))
    )
    (fp_line (start -0.8 1.146) (end -0.8 1.223)
      (stroke (width 0.15) (type solid)) (layer "F.SilkS"))
    (fp_line (start -0.8 1.223) (end 0.803 1.223)
      (stroke (width 0.15) (type solid)) (layer "F.SilkS"))
    (fp_line (start -0.72 -1.153) (end -0.72 -1.228)
      (stroke (width 0.15) (type solid)) (layer "F.SilkS"))
    (fp_line (start 0.803 -1.228) (end -0.72 -1.228)
      (stroke (width 0.15) (type solid)) (layer "F.SilkS"))
    (fp_line (start 0.803 -1.153) (end 0.803 -1.228)
      (stroke (width 0.15) (type solid)) (layer "F.SilkS"))
    (fp_line (start 0.803 1.146) (end 0.803 1.223)
      (stroke (width 0.15) (type solid)) (layer "F.SilkS"))
    (fp_circle (center -0.978102 -1.2) (end -0.928102 -1.2)
      (stroke (width 0.15) (type solid)) (fill solid) (layer "F.SilkS"))
    (fp_rect (start 1.3 -1.3) (end -1.3 1.3)
      (stroke (width 0.05) (type solid)) (fill none) (layer "F.CrtYd"))
    (fp_line (start -0.1 -1.1) (end -0.68 -0.52)
      (stroke (width 0.15) (type solid)) (layer "F.Fab"))
    (fp_rect (start 0.68 1.1) (end -0.68 -1.1)
      (stroke (width 0.15) (type solid)) (fill none) (layer "F.Fab"))
    (pad "1" smd custom (at -0.948 -0.752 180) (size 0.6 0.6) (layers "F.Cu" "F.Paste" "F.Mask")
      (net 683 "Net-(U44-B_{1})") (pintype "input") (zone_connect 0)
      (options (clearance outline) (anchor rect))
      (primitives
      ))
    (pad "2" smd rect (at -0.948 -0.002 180) (size 0.4 0.6) (layers "F.Cu" "F.Paste" "F.Mask")
      (net 1 "GND") (pinfunction "GND") (pintype "power_in"))
    (pad "3" smd custom (at -0.948 0.745 180) (size 0.6 0.6) (layers "F.Cu" "F.Paste" "F.Mask")
      (net 684 "Net-(U44-B_{2})") (pintype "input") (zone_connect 0)
      (options (clearance outline) (anchor rect))
      (primitives
      ))
    (pad "4" smd custom (at 0.951 0.745 180) (size 0.6 0.6) (layers "F.Cu" "F.Paste" "F.Mask")
      (net 151 "/Debug and JTAG/~{PS_POR}") (pintype "output") (zone_connect 0)
      (options (clearance outline) (anchor rect))
      (primitives
      ))
    (pad "5" smd rect (at 0.951 -0.002 180) (size 0.4 0.6) (layers "F.Cu" "F.Paste" "F.Mask")
      (net 138 "/Debug and JTAG/USB_3V3") (pinfunction "VCC") (pintype "power_in"))
    (pad "6" smd custom (at 0.951 -0.752 180) (size 0.6 0.6) (layers "F.Cu" "F.Paste" "F.Mask")
      (net 140 "/Debug and JTAG/~{PS_SRST_C2M}") (pintype "output") (zone_connect 0)
      (options (clearance outline) (anchor rect))
      (primitives
      ))
  )

  (footprint "kria-k26-devboard-footprints:MSOP-8-1EP_3x3x1.1mm_P0.65mm" (layer "F.Cu")
    (at 83.38 122.05 180)
    (property "Author" "Antmicro")
    (property "License" "Apache-2.0")
    (property "MPN" "PI4MSD5V9540BUEX")
    (property "Manufacturer" "Diodes Incorporated")
    (property "Sheetfile" "camera.kicad_sch")
    (property "Sheetname" "Camera interface")
    (property "ki_description" "Multiplexer, 2 Channels, 1:2, 1.65 V to 5.5 V, MSOP-8")
    (property "ki_keywords" "SMT, MUX, IC, I2C")
    (attr smd)
    (fp_text reference "U10" (at 1.739822 -2.55) (layer "F.SilkS")
        (effects (font (size 0.7 0.7) (thickness 0.15)) (justify left bottom))
    )
    (fp_text value "PI4MSD5V9540B_MSOP" (at 0 2.7) (layer "F.Fab") hide
        (effects (font (size 0.7 0.7) (thickness 0.15)) (justify left bottom))
    )
    (fp_text user "License: Apache-2.0" (at -5.576 10.98) (layer "F.Fab") hide
        (effects (font (size 0.7 0.7) (thickness 0.15)) (justify right bottom))
    )
    (fp_text user "Author: Antmicro" (at -5.576 9.779) (layer "F.Fab") hide
        (effects (font (size 0.7 0.7) (thickness 0.15)) (justify right bottom))
    )
    (fp_text user "REF**" (at -5.576 7.379) (layer "F.Fab") hide
        (effects (font (size 0.7 0.7) (thickness 0.15)) (justify right bottom))
    )
    (fp_text user "${REFERENCE}" (at -5.576 8.579) (layer "F.Fab") hide
        (effects (font (size 0.7 0.7) (thickness 0.15)) (justify right bottom))
    )
    (fp_line (start -1.6 1.6) (end -1.6 1.298)
      (stroke (width 0.15) (type solid)) (layer "F.SilkS"))
    (fp_line (start -1.299 -1.601) (end -1.6 -1.302)
      (stroke (width 0.15) (type solid)) (layer "F.SilkS"))
    (fp_line (start -1.299 1.6) (end -1.6 1.6)
      (stroke (width 0.15) (type solid)) (layer "F.SilkS"))
    (fp_line (start 1.3 -1.601) (end 1.601 -1.601)
      (stroke (width 0.15) (type solid)) (layer "F.SilkS"))
    (fp_line (start 1.601 -1.601) (end 1.601 -1.302)
      (stroke (width 0.15) (type solid)) (layer "F.SilkS"))
    (fp_line (start 1.601 1.298) (end 1.601 1.6)
      (stroke (width 0.15) (type solid)) (layer "F.SilkS"))
    (fp_line (start 1.601 1.6) (end 1.3 1.6)
      (stroke (width 0.15) (type solid)) (layer "F.SilkS"))
    (fp_circle (center -2.1 -1.5) (end -2.05 -1.55)
      (stroke (width 0.15) (type solid)) (fill solid) (layer "F.SilkS"))
    (fp_line (start -3.179 -1.747) (end 3.171 -1.747)
      (stroke (width 0.05) (type solid)) (layer "F.CrtYd"))
    (fp_line (start -3.179 1.753) (end -3.179 -1.747)
      (stroke (width 0.05) (type solid)) (layer "F.CrtYd"))
    (fp_line (start 3.171 1.753) (end -3.179 1.753)
      (stroke (width 0.05) (type solid)) (layer "F.CrtYd"))
    (fp_line (start 3.171 1.753) (end 3.171 -1.747)
      (stroke (width 0.05) (type solid)) (layer "F.CrtYd"))
    (fp_line (start -1.45 -1.101) (end -1.45 1.449)
      (stroke (width 0.15) (type solid)) (layer "F.Fab"))
    (fp_line (start -1.099 -1.451) (end -1.45 -1.101)
      (stroke (width 0.15) (type solid)) (layer "F.Fab"))
    (fp_line (start 1.45 -1.451) (end -1.099 -1.451)
      (stroke (width 0.15) (type solid)) (layer "F.Fab"))
    (fp_line (start 1.45 -1.451) (end 1.45 1.449)
      (stroke (width 0.15) (type solid)) (layer "F.Fab"))
    (fp_line (start 1.45 1.449) (end -1.45 1.449)
      (stroke (width 0.15) (type solid)) (layer "F.Fab"))
    (pad "1" smd roundrect (at -2.199 -0.977 90) (size 0.45 1.45) (layers "F.Cu" "F.Paste" "F.Mask") (roundrect_rratio 0.25)
      (net 410 "/Camera interface/HDA00_CC") (pinfunction "SCL") (pintype "bidirectional"))
    (pad "2" smd roundrect (at -2.199 -0.326 90) (size 0.45 1.45) (layers "F.Cu" "F.Paste" "F.Mask") (roundrect_rratio 0.25)
      (net 225 "/Camera interface/HDA01") (pinfunction "SDA") (pintype "bidirectional"))
    (pad "3" smd roundrect (at -2.199 0.324 90) (size 0.45 1.45) (layers "F.Cu" "F.Paste" "F.Mask") (roundrect_rratio 0.25)
      (net 20 "PL_3V3") (pinfunction "VCC") (pintype "bidirectional"))
    (pad "4" smd roundrect (at -2.199 0.973 90) (size 0.45 1.45) (layers "F.Cu" "F.Paste" "F.Mask") (roundrect_rratio 0.25)
      (net 196 "/Camera interface/CCI0_I2C_SDA_3V3") (pinfunction "SDA_{0}") (pintype "bidirectional"))
    (pad "5" smd roundrect (at 2.201 0.973 90) (size 0.45 1.45) (layers "F.Cu" "F.Paste" "F.Mask") (roundrect_rratio 0.25)
      (net 195 "/Camera interface/CCI0_I2C_SCL_3V3") (pinfunction "SCL_{0}") (pintype "bidirectional"))
    (pad "6" smd roundrect (at 2.201 0.324 90) (size 0.45 1.45) (layers "F.Cu" "F.Paste" "F.Mask") (roundrect_rratio 0.25)
      (net 1 "GND") (pinfunction "GND") (pintype "bidirectional"))
    (pad "7" smd roundrect (at 2.201 -0.326 90) (size 0.45 1.45) (layers "F.Cu" "F.Paste" "F.Mask") (roundrect_rratio 0.25)
      (net 194 "/Camera interface/CCI1_I2C_SDA_3V3") (pinfunction "SDA_{1}") (pintype "bidirectional"))
    (pad "8" smd roundrect (at 2.201 -0.977 90) (size 0.45 1.45) (layers "F.Cu" "F.Paste" "F.Mask") (roundrect_rratio 0.25)
      (net 193 "/Camera interface/CCI1_I2C_SCL_3V3") (pinfunction "SCL_{1}") (pintype "bidirectional"))
  )

  (footprint "kria-k26-devboard-footprints:C_0402_1005Metric" (layer "F.Cu")
    (at 123.85 74.52 -90)
    (descr "Capacitor SMD 0402")
    (tags "capacitor SMD 0402")
    (property "Author" "Antmicro")
    (property "Dielectric" "X5R")
    (property "License" "Apache-2.0")
    (property "MPN" "GRM155R61H104KE14D")
    (property "Manufacturer" "Murata")
    (property "Sheetfile" "usb.kicad_sch")
    (property "Sheetname" "USB")
    (property "Val" "100n")
    (property "Voltage" "50V")
    (property "ki_description" " ")
    (attr smd)
    (fp_text reference "C64" (at 1.08 -1.315 -90) (layer "F.SilkS")
        (effects (font (size 0.7 0.7) (thickness 0.15)) (justify left bottom))
    )
    (fp_text value "C_100n_0402" (at 0 1.4 -90) (layer "F.Fab") hide
        (effects (font (size 0.7 0.7) (thickness 0.15)) (justify left bottom))
    )
    (fp_text user "License: Apache-2.0" (at -0.932 5.17 -90) (layer "F.Fab") hide
        (effects (font (size 0.7 0.7) (thickness 0.15)) (justify left bottom))
    )
    (fp_text user "${REFERENCE}" (at -0.932 3.168 -90) (layer "F.Fab") hide
        (effects (font (size 0.7 0.7) (thickness 0.15)) (justify left bottom))
    )
    (fp_text user "Author: Antmicro" (at -0.932 4.17 -90) (layer "F.Fab") hide
        (effects (font (size 0.7 0.7) (thickness 0.15)) (justify left bottom))
    )
    (fp_rect (start -0.94 -0.47) (end 0.94 0.47)
      (stroke (width 0.05) (type solid)) (fill none) (layer "F.CrtYd"))
    (fp_rect (start -0.499 -0.249) (end 0.499 0.249)
      (stroke (width 0.15) (type solid)) (fill none) (layer "F.Fab"))
    (pad "1" smd roundrect (at -0.484 0 270) (size 0.59 0.64) (layers "F.Cu" "F.Paste" "F.Mask") (roundrect_rratio 0.25)
      (net 306 "USB_5V") (pintype "passive"))
    (pad "2" smd roundrect (at 0.484 0 270) (size 0.59 0.64) (layers "F.Cu" "F.Paste" "F.Mask") (roundrect_rratio 0.25)
      (net 1 "GND") (pintype "passive"))
  )

  (footprint "kria-k26-devboard-footprints:Spacer_Drill4.45mm_H5mm_9774050960R" (layer "F.Cu")
    (at 89.556999 90.7935)
    (property "Author" "Antmicro")
    (property "License" "Apache-2.0")
    (property "MPN" "9774050960R")
    (property "Manufacturer" "Würth Elektronik")
    (property "Sheetfile" "k26_som.kicad_sch")
    (property "Sheetname" "Xilinx K26 SOM")
    (property "ki_description" "Spacer, SMT, Non Stop, Steel, Swage Round, 6 mm x 5 mm, 3.3 mm Internal, WA-SMST Series")
    (property "ki_keywords" "SPACER")
    (clearance 0.6)
    (attr smd)
    (fp_text reference "SP4" (at 0 -3.4) (layer "F.SilkS")
        (effects (font (size 0.7 0.7) (thickness 0.15)) (justify left bottom))
    )
    (fp_text value "Spacer_Drill4.45mm_H5mm_9774050960R" (at 0 4.2) (layer "F.Fab")
        (effects (font (size 0.7 0.7) (thickness 0.15)) (justify left bottom))
    )
    (fp_text user "Author: Antmicro" (at -3.25 8.6) (layer "F.Fab") hide
        (effects (font (size 0.7 0.7) (thickness 0.15)) (justify left bottom))
    )
    (fp_text user "${REFERENCE}" (at -3.25 7.4) (layer "F.Fab") hide
        (effects (font (size 0.7 0.7) (thickness 0.15)) (justify left bottom))
    )
    (fp_text user "License: Apache-2.0" (at -3.25 6.2) (layer "F.Fab") hide
        (effects (font (size 0.7 0.7) (thickness 0.15)) (justify left bottom))
    )
    (fp_circle (center 0 0) (end 3.25 0)
      (stroke (width 0.05) (type solid)) (fill none) (layer "F.CrtYd"))
    (fp_circle (center 0 0) (end 2.564 0)
      (stroke (width 0.15) (type solid)) (fill none) (layer "F.Fab"))
    (pad "1" thru_hole circle (at 0 0) (size 6 6) (drill 4.45) (layers "*.Cu" "*.Mask" "F.Paste")
      (net 1 "GND") (pintype "passive") (solder_paste_margin_ratio -0.05))
  )

  (footprint "kria-k26-devboard-footprints:FB_0402_1005Metric" (layer "F.Cu")
    (at 145.2 112.3)
    (descr "Ferrite Bead SMD 0402")
    (tags "ferrite bead SMD 0402")
    (property "Author" "Antmicro")
    (property "License" "Apache-2.0")
    (property "MPN" "BLM15PD121SN1D")
    (property "Manufacturer" "Murata")
    (property "Sheetfile" "debug.kicad_sch")
    (property "Sheetname" "Debug and JTAG")
    (attr smd)
    (fp_text reference "FB3" (at -1.12 1.21) (layer "F.SilkS")
        (effects (font (size 0.7 0.7) (thickness 0.15)) (justify left bottom))
    )
    (fp_text value "FB_120Z_1.3A_0402" (at 0 1.4) (layer "F.Fab") hide
        (effects (font (size 0.7 0.7) (thickness 0.15)) (justify left bottom))
    )
    (fp_text user "${REFERENCE}" (at -0.95 3.168) (layer "F.Fab") hide
        (effects (font (size 0.7 0.7) (thickness 0.15)) (justify left bottom))
    )
    (fp_text user "License: Apache-2.0" (at -0.95 5.169) (layer "F.Fab") hide
        (effects (font (size 0.7 0.7) (thickness 0.15)) (justify left bottom))
    )
    (fp_text user "Author: Antmicro" (at -0.95 4.169) (layer "F.Fab") hide
        (effects (font (size 0.7 0.7) (thickness 0.15)) (justify left bottom))
    )
    (fp_rect (start -0.95 -0.48) (end 0.95 0.48)
      (stroke (width 0.05) (type solid)) (fill none) (layer "F.CrtYd"))
    (fp_rect (start -0.5 -0.25) (end 0.5 0.25)
      (stroke (width 0.15) (type solid)) (fill none) (layer "F.Fab"))
    (pad "1" smd roundrect (at -0.485 0) (size 0.59 0.64) (layers "F.Cu" "F.Paste" "F.Mask") (roundrect_rratio 0.25)
      (net 187 "/Debug and JTAG/PD_3V3") (pintype "passive"))
    (pad "2" smd roundrect (at 0.485 0) (size 0.59 0.64) (layers "F.Cu" "F.Paste" "F.Mask") (roundrect_rratio 0.25)
      (net 133 "/Debug and JTAG/VCC_PD") (pintype "passive"))
  )

  (footprint "kria-k26-devboard-footprints:R_0402_1005Metric" (layer "F.Cu")
    (at 147.225 110 -90)
    (descr "Resistor SMD 0402")
    (tags "resistor SMD 0402")
    (property "Author" "Antmicro")
    (property "Current" "1A")
    (property "DNP" "DNP")
    (property "License" "Apache-2.0")
    (property "MPN" "ERJ2GE0R00X")
    (property "Manufacturer" "Panasonic")
    (property "Sheetfile" "debug.kicad_sch")
    (property "Sheetname" "Debug and JTAG")
    (property "Tolerance" "")
    (property "Val" "0R")
    (property "dnp" "")
    (property "exclude_from_bom" "")
    (property "ki_description" "0R resistor in 0402 package with unspecified tolerance")
    (attr exclude_from_pos_files exclude_from_bom)
    (fp_text reference "R100" (at -3.22 -0.365 -90) (layer "F.SilkS")
        (effects (font (size 0.7 0.7) (thickness 0.15)) (justify left bottom))
    )
    (fp_text value "R_0R_0402" (at 0 1.4 -90) (layer "F.Fab") hide
        (effects (font (size 0.7 0.7) (thickness 0.15)) (justify left bottom))
    )
    (fp_text user "License: Apache-2.0" (at -0.95 5.169 -90) (layer "F.Fab") hide
        (effects (font (size 0.7 0.7) (thickness 0.15)) (justify left bottom))
    )
    (fp_text user "Author: Antmicro" (at -0.95 4.169 -90) (layer "F.Fab") hide
        (effects (font (size 0.7 0.7) (thickness 0.15)) (justify left bottom))
    )
    (fp_text user "${REFERENCE}" (at -0.95 3.168 -90) (layer "F.Fab") hide
        (effects (font (size 0.7 0.7) (thickness 0.15)) (justify left bottom))
    )
    (fp_rect (start -0.93 -0.47) (end 0.93 0.47)
      (stroke (width 0.05) (type solid)) (fill none) (layer "F.CrtYd"))
    (fp_rect (start -0.5 -0.25) (end 0.5 0.25)
      (stroke (width 0.15) (type solid)) (fill none) (layer "F.Fab"))
    (pad "1" smd roundrect (at -0.485 0 270) (size 0.59 0.64) (layers "F.Cu" "F.Paste" "F.Mask") (roundrect_rratio 0.25)
      (net 233 "/Debug and JTAG/USB_P") (pintype "passive"))
    (pad "2" smd roundrect (at 0.485 0 270) (size 0.59 0.64) (layers "F.Cu" "F.Paste" "F.Mask") (roundrect_rratio 0.25)
      (net 222 "/Debug and JTAG/USBB_P") (pintype "passive"))
  )

  (footprint "kria-k26-devboard-footprints:R_0402_1005Metric" (layer "F.Cu")
    (at 147.225 107.6 -90)
    (descr "Resistor SMD 0402")
    (tags "resistor SMD 0402")
    (property "Author" "Antmicro")
    (property "Current" "1A")
    (property "License" "Apache-2.0")
    (property "MPN" "ERJ2GE0R00X")
    (property "Manufacturer" "Panasonic")
    (property "Sheetfile" "debug.kicad_sch")
    (property "Sheetname" "Debug and JTAG")
    (property "Tolerance" "")
    (property "Val" "0R")
    (property "ki_description" "0R resistor in 0402 package with unspecified tolerance")
    (attr smd)
    (fp_text reference "R97" (at -3.74 -0.395 -90) (layer "F.SilkS")
        (effects (font (size 0.7 0.7) (thickness 0.15)) (justify left bottom))
    )
    (fp_text value "R_0R_0402" (at 0 1.4 -90) (layer "F.Fab") hide
        (effects (font (size 0.7 0.7) (thickness 0.15)) (justify left bottom))
    )
    (fp_text user "${REFERENCE}" (at -0.95 3.168 -90) (layer "F.Fab") hide
        (effects (font (size 0.7 0.7) (thickness 0.15)) (justify left bottom))
    )
    (fp_text user "License: Apache-2.0" (at -0.95 5.169 -90) (layer "F.Fab") hide
        (effects (font (size 0.7 0.7) (thickness 0.15)) (justify left bottom))
    )
    (fp_text user "Author: Antmicro" (at -0.95 4.169 -90) (layer "F.Fab") hide
        (effects (font (size 0.7 0.7) (thickness 0.15)) (justify left bottom))
    )
    (fp_rect (start -0.93 -0.47) (end 0.93 0.47)
      (stroke (width 0.05) (type solid)) (fill none) (layer "F.CrtYd"))
    (fp_rect (start -0.5 -0.25) (end 0.5 0.25)
      (stroke (width 0.15) (type solid)) (fill none) (layer "F.Fab"))
    (pad "1" smd roundrect (at -0.485 0 270) (size 0.59 0.64) (layers "F.Cu" "F.Paste" "F.Mask") (roundrect_rratio 0.25)
      (net 188 "/Debug and JTAG/USBC_P") (pintype "passive"))
    (pad "2" smd roundrect (at 0.485 0 270) (size 0.59 0.64) (layers "F.Cu" "F.Paste" "F.Mask") (roundrect_rratio 0.25)
      (net 233 "/Debug and JTAG/USB_P") (pintype "passive"))
  )

  (footprint "kria-k26-devboard-footprints:R_0402_1005Metric" (layer "F.Cu")
    (at 148.225 107.6 -90)
    (descr "Resistor SMD 0402")
    (tags "resistor SMD 0402")
    (property "Author" "Antmicro")
    (property "Current" "1A")
    (property "License" "Apache-2.0")
    (property "MPN" "ERJ2GE0R00X")
    (property "Manufacturer" "Panasonic")
    (property "Sheetfile" "debug.kicad_sch")
    (property "Sheetname" "Debug and JTAG")
    (property "Tolerance" "")
    (property "Val" "0R")
    (property "ki_description" "0R resistor in 0402 package with unspecified tolerance")
    (attr smd)
    (fp_text reference "R98" (at -3.74 -0.395 -90) (layer "F.SilkS")
        (effects (font (size 0.7 0.7) (thickness 0.15)) (justify left bottom))
    )
    (fp_text value "R_0R_0402" (at 0 1.4 -90) (layer "F.Fab") hide
        (effects (font (size 0.7 0.7) (thickness 0.15)) (justify left bottom))
    )
    (fp_text user "License: Apache-2.0" (at -0.95 5.169 -90) (layer "F.Fab") hide
        (effects (font (size 0.7 0.7) (thickness 0.15)) (justify left bottom))
    )
    (fp_text user "${REFERENCE}" (at -0.95 3.168 -90) (layer "F.Fab") hide
        (effects (font (size 0.7 0.7) (thickness 0.15)) (justify left bottom))
    )
    (fp_text user "Author: Antmicro" (at -0.95 4.169 -90) (layer "F.Fab") hide
        (effects (font (size 0.7 0.7) (thickness 0.15)) (justify left bottom))
    )
    (fp_rect (start -0.93 -0.47) (end 0.93 0.47)
      (stroke (width 0.05) (type solid)) (fill none) (layer "F.CrtYd"))
    (fp_rect (start -0.5 -0.25) (end 0.5 0.25)
      (stroke (width 0.15) (type solid)) (fill none) (layer "F.Fab"))
    (pad "1" smd roundrect (at -0.485 0 270) (size 0.59 0.64) (layers "F.Cu" "F.Paste" "F.Mask") (roundrect_rratio 0.25)
      (net 189 "/Debug and JTAG/USBC_N") (pintype "passive"))
    (pad "2" smd roundrect (at 0.485 0 270) (size 0.59 0.64) (layers "F.Cu" "F.Paste" "F.Mask") (roundrect_rratio 0.25)
      (net 234 "/Debug and JTAG/USB_N") (pintype "passive"))
  )

  (footprint "kria-k26-devboard-footprints:C_0402_1005Metric" (layer "F.Cu")
    (at 152.925 124.99 -90)
    (descr "Capacitor SMD 0402")
    (tags "capacitor SMD 0402")
    (property "Author" "Antmicro")
    (property "Dielectric" "")
    (property "License" "Apache-2.0")
    (property "MPN" "MC0402N180J500CT")
    (property "Manufacturer" "Multicomp")
    (property "Sheetfile" "debug.kicad_sch")
    (property "Sheetname" "Debug and JTAG")
    (property "Val" "18p")
    (property "Voltage" "")
    (property "ki_description" " ")
    (attr smd)
    (fp_text reference "C156" (at 3.74 -0.415 -90) (layer "F.SilkS")
        (effects (font (size 0.7 0.7) (thickness 0.15)) (justify left bottom))
    )
    (fp_text value "C_18p_0402" (at 0 1.4 -90) (layer "F.Fab") hide
        (effects (font (size 0.7 0.7) (thickness 0.15)) (justify left bottom))
    )
    (fp_text user "License: Apache-2.0" (at -0.932 5.17 -90) (layer "F.Fab") hide
        (effects (font (size 0.7 0.7) (thickness 0.15)) (justify left bottom))
    )
    (fp_text user "Author: Antmicro" (at -0.932 4.17 -90) (layer "F.Fab") hide
        (effects (font (size 0.7 0.7) (thickness 0.15)) (justify left bottom))
    )
    (fp_text user "${REFERENCE}" (at -0.932 3.168 -90) (layer "F.Fab") hide
        (effects (font (size 0.7 0.7) (thickness 0.15)) (justify left bottom))
    )
    (fp_rect (start -0.94 -0.47) (end 0.94 0.47)
      (stroke (width 0.05) (type solid)) (fill none) (layer "F.CrtYd"))
    (fp_rect (start -0.499 -0.249) (end 0.499 0.249)
      (stroke (width 0.15) (type solid)) (fill none) (layer "F.Fab"))
    (pad "1" smd roundrect (at -0.484 0 270) (size 0.59 0.64) (layers "F.Cu" "F.Paste" "F.Mask") (roundrect_rratio 0.25)
      (net 139 "/Debug and JTAG/XOUT") (pintype "passive"))
    (pad "2" smd roundrect (at 0.484 0 270) (size 0.59 0.64) (layers "F.Cu" "F.Paste" "F.Mask") (roundrect_rratio 0.25)
      (net 1 "GND") (pintype "passive"))
  )

  (footprint "kria-k26-devboard-footprints:UQFN-16-1.8x2.6mm_P0.4mm_Texas_RSV0016A" (layer "F.Cu")
    (at 139.225 116.925 90)
    (descr "https://www.ti.com/lit/ds/symlink/sn74avch4t245-ep.pdf?ts=1679484181203&ref_url=https%253A%252F%252Fwww.ti.com%252Fproduct%252FSN74AVCH4T245-EP%253Futm_source%253Dgoogle%2526utm_medium%253Dcpc%2526utm_campaign%253Dasc-int-null-prodfolderdynamic-cpc-pf-google-wwe_int%2526utm_content%253Dprodfolddynamic%2526ds_k%253DDYNAMIC%2BSEARCH%2BADS%2526DCM%253Dyes%2526gclid%253DCjwKCAjwzuqgBhAcEiwAdj5dRvR_WgyvqqhLxMx8zfbFv2a6tg33JIMv01Bn4M1kA4JzW1nDDW7OzhoCRbkQAvD_BwE%2526gclsrc%253Daw.ds")
    (property "Author" "Antmicro")
    (property "License" "Apache-2.0")
    (property "MPN" "74AVC4T245RSVRG4")
    (property "Manufacturer" "Texas Instruments")
    (property "Sheetfile" "debug.kicad_sch")
    (property "Sheetname" "Debug and JTAG")
    (property "ki_description" "Logic translator/level shifter")
    (property "ki_keywords" "SMT, LOGIC, IC, LEVEL-SHIFTER")
    (attr smd)
    (fp_text reference "U42" (at -2.035 -1.855 180) (layer "F.SilkS")
        (effects (font (size 0.7 0.7) (thickness 0.15)) (justify left bottom))
    )
    (fp_text value "74AVC4T245_UQFN" (at -1.25 2.5 90) (layer "F.Fab") hide
        (effects (font (size 0.7 0.7) (thickness 0.15)) (justify left bottom))
    )
    (fp_text user "." (at -1.315 -0.775 90) (layer "F.SilkS")
        (effects (font (size 0.7 0.7) (thickness 0.15)) (justify left bottom))
    )
    (fp_text user "Author: Antmicro" (at -1.25 5 90) (layer "F.Fab") hide
        (effects (font (size 0.7 0.7) (thickness 0.15)) (justify left bottom))
    )
    (fp_text user "${REFERENCE}" (at -1.25 3.75 90) (layer "F.Fab") hide
        (effects (font (size 0.7 0.7) (thickness 0.15)) (justify left bottom))
    )
    (fp_text user "License: Apache-2.0" (at -1.25 6.25 90) (layer "F.Fab") hide
        (effects (font (size 0.7 0.7) (thickness 0.15)) (justify left bottom))
    )
    (fp_line (start -0.9 1.2995) (end -0.9 0.8)
      (stroke (width 0.15) (type solid)) (layer "F.SilkS"))
    (fp_line (start -0.8 -1.3) (end -0.9 -1.3)
      (stroke (width 0.15) (type solid)) (layer "F.SilkS"))
    (fp_line (start -0.8 1.2995) (end -0.9 1.2995)
      (stroke (width 0.15) (type solid)) (layer "F.SilkS"))
    (fp_line (start 0.8 -1.3) (end 0.9 -1.3)
      (stroke (width 0.15) (type solid)) (layer "F.SilkS"))
    (fp_line (start 0.8 1.3) (end 0.899 1.3)
      (stroke (width 0.15) (type solid)) (layer "F.SilkS"))
    (fp_line (start 0.9 -1.3) (end 0.9 -0.8005)
      (stroke (width 0.15) (type solid)) (layer "F.SilkS"))
    (fp_line (start 0.9 0.8) (end 0.899 1.3)
      (stroke (width 0.15) (type solid)) (layer "F.SilkS"))
    (fp_rect (start -1.25 -1.65) (end 1.25 1.65)
      (stroke (width 0.05) (type solid)) (fill none) (layer "F.CrtYd"))
    (fp_line (start -0.902 1.3) (end -0.902 -1.301)
      (stroke (width 0.15) (type solid)) (layer "F.Fab"))
    (fp_line (start 0.9 -1.301) (end -0.902 -1.301)
      (stroke (width 0.15) (type solid)) (layer "F.Fab"))
    (fp_line (start 0.9 1.3) (end -0.902 1.3)
      (stroke (width 0.15) (type solid)) (layer "F.Fab"))
    (fp_line (start 0.9 1.3) (end 0.9 -1.301)
      (stroke (width 0.15) (type solid)) (layer "F.Fab"))
    (pad "1" smd roundrect (at -0.75 -0.6 90) (size 0.7 0.2) (layers "F.Cu" "F.Paste" "F.Mask") (roundrect_rratio 0.2272727273)
      (net 160 "/Debug and JTAG/~{LS_OE}") (pinfunction "1~{OE}") (pintype "input"))
    (pad "2" smd roundrect (at -0.802 -0.202 90) (size 0.6 0.2) (layers "F.Cu" "F.Paste" "F.Mask") (roundrect_rratio 0.2272727273)
      (net 17 "PS_1V8") (pinfunction "VCCB") (pintype "power_in"))
    (pad "3" smd roundrect (at -0.802 0.2 90) (size 0.6 0.2) (layers "F.Cu" "F.Paste" "F.Mask") (roundrect_rratio 0.2272727273)
      (net 138 "/Debug and JTAG/USB_3V3") (pinfunction "VCCA") (pintype "power_in"))
    (pad "4" smd roundrect (at -0.802 0.598 90) (size 0.6 0.2) (layers "F.Cu" "F.Paste" "F.Mask") (roundrect_rratio 0.2272727273)
      (net 138 "/Debug and JTAG/USB_3V3") (pinfunction "1DIR") (pintype "input"))
    (pad "5" smd roundrect (at -0.6 1.199 180) (size 0.6 0.2) (layers "F.Cu" "F.Paste" "F.Mask") (roundrect_rratio 0.2272727273)
      (net 138 "/Debug and JTAG/USB_3V3") (pinfunction "2DIR") (pintype "input"))
    (pad "6" smd roundrect (at -0.202 1.199 180) (size 0.6 0.2) (layers "F.Cu" "F.Paste" "F.Mask") (roundrect_rratio 0.2272727273)
      (net 170 "/Debug and JTAG/FTDI_TMS") (pinfunction "1A1") (pintype "bidirectional"))
    (pad "7" smd roundrect (at 0.2 1.199 180) (size 0.6 0.2) (layers "F.Cu" "F.Paste" "F.Mask") (roundrect_rratio 0.2272727273)
      (net 173 "/Debug and JTAG/FTDI_TCK") (pinfunction "1A2") (pintype "bidirectional"))
    (pad "8" smd roundrect (at 0.598 1.199 180) (size 0.6 0.2) (layers "F.Cu" "F.Paste" "F.Mask") (roundrect_rratio 0.2272727273)
      (net 172 "/Debug and JTAG/FTDI_TDI") (pinfunction "2A1") (pintype "bidirectional"))
    (pad "9" smd roundrect (at 0.8 0.598 90) (size 0.6 0.2) (layers "F.Cu" "F.Paste" "F.Mask") (roundrect_rratio 0.2272727273)
      (net 1 "GND") (pinfunction "2A2") (pintype "bidirectional"))
    (pad "10" smd roundrect (at 0.8 0.2 90) (size 0.6 0.2) (layers "F.Cu" "F.Paste" "F.Mask") (roundrect_rratio 0.2272727273)
      (net 1 "GND") (pinfunction "GND") (pintype "power_in"))
    (pad "11" smd roundrect (at 0.8 -0.202 90) (size 0.6 0.2) (layers "F.Cu" "F.Paste" "F.Mask") (roundrect_rratio 0.2272727273)
      (net 1 "GND") (pinfunction "GND") (pintype "passive"))
    (pad "12" smd roundrect (at 0.8 -0.6 90) (size 0.6 0.2) (layers "F.Cu" "F.Paste" "F.Mask") (roundrect_rratio 0.2272727273)
      (net 776 "unconnected-(U42-2B2-Pad12)") (pinfunction "2B2") (pintype "bidirectional+no_connect"))
    (pad "13" smd roundrect (at 0.598 -1.2 180) (size 0.6 0.2) (layers "F.Cu" "F.Paste" "F.Mask") (roundrect_rratio 0.2272727273)
      (net 141 "/Debug and JTAG/JTAG_TDI_C2M") (pinfunction "2B1") (pintype "bidirectional"))
    (pad "14" smd roundrect (at 0.2 -1.2 180) (size 0.6 0.2) (layers "F.Cu" "F.Paste" "F.Mask") (roundrect_rratio 0.2272727273)
      (net 143 "/Debug and JTAG/JTAG_TCK_C2M") (pinfunction "1B2") (pintype "bidirectional"))
    (pad "15" smd roundrect (at -0.202 -1.2 180) (size 0.6 0.2) (layers "F.Cu" "F.Paste" "F.Mask") (roundrect_rratio 0.2272727273)
      (net 145 "/Debug and JTAG/JTAG_TMS_C2M") (pinfunction "1B1") (pintype "bidirectional"))
    (pad "16" smd roundrect (at -0.6 -1.2 180) (size 0.6 0.2) (layers "F.Cu" "F.Paste" "F.Mask") (roundrect_rratio 0.2272727273)
      (net 160 "/Debug and JTAG/~{LS_OE}") (pinfunction "2~{OE}") (pintype "input"))
  )

  (footprint "kria-k26-devboard-footprints:R_0402_1005Metric" (layer "F.Cu")
    (at 142.8 116.2)
    (descr "Resistor SMD 0402")
    (tags "resistor SMD 0402")
    (property "Author" "Antmicro")
    (property "License" "Apache-2.0")
    (property "MPN" "CR0402-FX-1002GLF")
    (property "Manufacturer" "Bourns")
    (property "Sheetfile" "debug.kicad_sch")
    (property "Sheetname" "Debug and JTAG")
    (property "Tolerance" "1%")
    (property "Val" "10k")
    (property "ki_description" "10k resistor in 0402 package with 1% tolerance")
    (attr smd)
    (fp_text reference "R103" (at -1.68 1.33) (layer "F.SilkS")
        (effects (font (size 0.7 0.7) (thickness 0.15)) (justify left bottom))
    )
    (fp_text value "R_10k_0402" (at 0 1.4) (layer "F.Fab") hide
        (effects (font (size 0.7 0.7) (thickness 0.15)) (justify left bottom))
    )
    (fp_text user "License: Apache-2.0" (at -0.95 5.169) (layer "F.Fab") hide
        (effects (font (size 0.7 0.7) (thickness 0.15)) (justify left bottom))
    )
    (fp_text user "Author: Antmicro" (at -0.95 4.169) (layer "F.Fab") hide
        (effects (font (size 0.7 0.7) (thickness 0.15)) (justify left bottom))
    )
    (fp_text user "${REFERENCE}" (at -0.95 3.168) (layer "F.Fab") hide
        (effects (font (size 0.7 0.7) (thickness 0.15)) (justify left bottom))
    )
    (fp_rect (start -0.93 -0.47) (end 0.93 0.47)
      (stroke (width 0.05) (type solid)) (fill none) (layer "F.CrtYd"))
    (fp_rect (start -0.5 -0.25) (end 0.5 0.25)
      (stroke (width 0.15) (type solid)) (fill none) (layer "F.Fab"))
    (pad "1" smd roundrect (at -0.485 0) (size 0.59 0.64) (layers "F.Cu" "F.Paste" "F.Mask") (roundrect_rratio 0.25)
      (net 138 "/Debug and JTAG/USB_3V3") (pintype "passive"))
    (pad "2" smd roundrect (at 0.485 0) (size 0.59 0.64) (layers "F.Cu" "F.Paste" "F.Mask") (roundrect_rratio 0.25)
      (net 681 "Net-(U40-~{RESET})") (pintype "passive"))
  )

  (footprint "kria-k26-devboard-footprints:R_0402_1005Metric" (layer "F.Cu")
    (at 142.825 120.26)
    (descr "Resistor SMD 0402")
    (tags "resistor SMD 0402")
    (property "Author" "Antmicro")
    (property "License" "Apache-2.0")
    (property "MPN" "CR0402-FX-1002GLF")
    (property "Manufacturer" "Bourns")
    (property "Sheetfile" "debug.kicad_sch")
    (property "Sheetname" "Debug and JTAG")
    (property "Tolerance" "1%")
    (property "Val" "10k")
    (property "ki_description" "10k resistor in 0402 package with 1% tolerance")
    (attr smd)
    (fp_text reference "R109" (at -1.785 -0.49) (layer "F.SilkS")
        (effects (font (size 0.7 0.7) (thickness 0.15)) (justify left bottom))
    )
    (fp_text value "R_10k_0402" (at 0 1.4) (layer "F.Fab") hide
        (effects (font (size 0.7 0.7) (thickness 0.15)) (justify left bottom))
    )
    (fp_text user "Author: Antmicro" (at -0.95 4.169) (layer "F.Fab") hide
        (effects (font (size 0.7 0.7) (thickness 0.15)) (justify left bottom))
    )
    (fp_text user "${REFERENCE}" (at -0.95 3.168) (layer "F.Fab") hide
        (effects (font (size 0.7 0.7) (thickness 0.15)) (justify left bottom))
    )
    (fp_text user "License: Apache-2.0" (at -0.95 5.169) (layer "F.Fab") hide
        (effects (font (size 0.7 0.7) (thickness 0.15)) (justify left bottom))
    )
    (fp_rect (start -0.93 -0.47) (end 0.93 0.47)
      (stroke (width 0.05) (type solid)) (fill none) (layer "F.CrtYd"))
    (fp_rect (start -0.5 -0.25) (end 0.5 0.25)
      (stroke (width 0.15) (type solid)) (fill none) (layer "F.Fab"))
    (pad "1" smd roundrect (at -0.485 0) (size 0.59 0.64) (layers "F.Cu" "F.Paste" "F.Mask") (roundrect_rratio 0.25)
      (net 138 "/Debug and JTAG/USB_3V3") (pintype "passive"))
    (pad "2" smd roundrect (at 0.485 0) (size 0.59 0.64) (layers "F.Cu" "F.Paste" "F.Mask") (roundrect_rratio 0.25)
      (net 159 "/Debug and JTAG/~{FTDI_LS_OE}") (pintype "passive"))
  )

  (footprint "kria-k26-devboard-footprints:QFN-68-1EP_8x8mm_P0.4mm" (layer "F.Cu")
    (at 148.26 118.3)
    (property "Author" "Antmicro")
    (property "License" "Apache-2.0")
    (property "MPN" "FT4232HPQ-TRAY")
    (property "Manufacturer" "FTDI Chip")
    (property "Sheetfile" "debug.kicad_sch")
    (property "Sheetname" "Debug and JTAG")
    (property "ki_description" "Interface Bridges, USB to UART, MPSSE, 1.62 V, 1.98 V, LQFP, 64 Pins, -40 °C")
    (property "ki_keywords" "SMT, INTERFACE, IC, CONTROLLER, USB, UART, I2C, SPI")
    (attr smd)
    (fp_text reference "U40" (at 5.17 -1.72 90) (layer "F.SilkS")
        (effects (font (size 0.7 0.7) (thickness 0.15)) (justify left bottom))
    )
    (fp_text value "FT4232HP_QFN" (at 0 5.2) (layer "F.Fab") hide
        (effects (font (size 0.7 0.7) (thickness 0.15)) (justify left bottom))
    )
    (fp_text user "${REFERENCE}" (at -4.425 7.2) (layer "F.Fab") hide
        (effects (font (size 0.7 0.7) (thickness 0.15)) (justify left bottom))
    )
    (fp_text user "Author: Antmicro" (at -4.425 8.4) (layer "F.Fab") hide
        (effects (font (size 0.7 0.7) (thickness 0.15)) (justify left bottom))
    )
    (fp_text user "License: Apache-2.0" (at -4.425 9.6) (layer "F.Fab") hide
        (effects (font (size 0.7 0.7) (thickness 0.15)) (justify left bottom))
    )
    (fp_line (start -4.1 4.1) (end -4.1 3.55)
      (stroke (width 0.15) (type solid)) (layer "F.SilkS"))
    (fp_line (start -4.0995 -3.501) (end -4.0995 -4.1)
      (stroke (width 0.15) (type solid)) (layer "F.SilkS"))
    (fp_line (start -3.55 4.1) (end -4.1 4.1)
      (stroke (width 0.15) (type solid)) (layer "F.SilkS"))
    (fp_line (start -3.5005 -4.1) (end -4.0995 -4.1)
      (stroke (width 0.15) (type solid)) (layer "F.SilkS"))
    (fp_line (start 3.5 -4.1) (end 4.1 -4.1)
      (stroke (width 0.15) (type solid)) (layer "F.SilkS"))
    (fp_line (start 3.55 4.1) (end 4.1 4.1)
      (stroke (width 0.15) (type solid)) (layer "F.SilkS"))
    (fp_line (start 4.1 -4.1) (end 4.1 -3.55)
      (stroke (width 0.15) (type solid)) (layer "F.SilkS"))
    (fp_line (start 4.1 4.1) (end 4.1 3.55)
      (stroke (width 0.15) (type solid)) (layer "F.SilkS"))
    (fp_circle (center -4.375 -3.5) (end -4.325 -3.5)
      (stroke (width 0.15) (type solid)) (fill solid) (layer "F.SilkS"))
    (fp_rect (start -4.25 -4.25) (end 4.25 4.25)
      (stroke (width 0.05) (type solid)) (fill none) (layer "F.CrtYd"))
    (fp_line (start -3.45 -4) (end -4 -3.45)
      (stroke (width 0.15) (type solid)) (layer "F.Fab"))
    (fp_rect (start -4 -4) (end 4 4)
      (stroke (width 0.15) (type solid)) (fill none) (layer "F.Fab"))
    (pad "" smd rect (at -1.7 -1.7) (size 1.5 1.5) (layers "F.Paste"))
    (pad "" smd rect (at -1.7 0) (size 1.5 1.5) (layers "F.Paste"))
    (pad "" smd rect (at -1.7 1.7) (size 1.5 1.5) (layers "F.Paste"))
    (pad "" smd rect (at 0 -1.7) (size 1.5 1.5) (layers "F.Paste"))
    (pad "" smd rect (at 0 0) (size 1.5 1.5) (layers "F.Paste"))
    (pad "" smd rect (at 0 1.7) (size 1.5 1.5) (layers "F.Paste"))
    (pad "" smd rect (at 1.7 -1.7) (size 1.5 1.5) (layers "F.Paste"))
    (pad "" smd rect (at 1.7 0) (size 1.5 1.5) (layers "F.Paste"))
    (pad "" smd rect (at 1.7 1.7) (size 1.5 1.5) (layers "F.Paste"))
    (pad "1" smd oval (at -3.95 -3.202 90) (size 0.25 0.6) (layers "F.Cu" "F.Paste" "F.Mask")
      (net 231 "/Debug and JTAG/EECLK") (pinfunction "EECLK") (pintype "output"))
    (pad "2" smd oval (at -3.95 -2.801 90) (size 0.25 0.6) (layers "F.Cu" "F.Paste" "F.Mask")
      (net 230 "/Debug and JTAG/EEDATA") (pinfunction "EEDATA") (pintype "bidirectional"))
    (pad "3" smd oval (at -3.95 -2.4 90) (size 0.25 0.6) (layers "F.Cu" "F.Paste" "F.Mask")
      (net 1 "GND") (pinfunction "TEST") (pintype "input"))
    (pad "4" smd oval (at -3.95 -2 90) (size 0.25 0.6) (layers "F.Cu" "F.Paste" "F.Mask")
      (net 681 "Net-(U40-~{RESET})") (pinfunction "~{RESET}") (pintype "input"))
    (pad "5" smd oval (at -3.95 -1.601 90) (size 0.25 0.6) (layers "F.Cu" "F.Paste" "F.Mask")
      (net 738 "unconnected-(U40-GPIO3-Pad5)") (pinfunction "GPIO3") (pintype "bidirectional+no_connect"))
    (pad "6" smd oval (at -3.95 -1.2 90) (size 0.25 0.6) (layers "F.Cu" "F.Paste" "F.Mask")
      (net 173 "/Debug and JTAG/FTDI_TCK") (pinfunction "ADBUS0") (pintype "bidirectional"))
    (pad "7" smd oval (at -3.95 -0.802 90) (size 0.25 0.6) (layers "F.Cu" "F.Paste" "F.Mask")
      (net 172 "/Debug and JTAG/FTDI_TDI") (pinfunction "ADBUS1") (pintype "bidirectional"))
    (pad "8" smd oval (at -3.95 -0.402 90) (size 0.25 0.6) (layers "F.Cu" "F.Paste" "F.Mask")
      (net 132 "/Debug and JTAG/USB_1V2") (pinfunction "V_{CORE}") (pintype "passive"))
    (pad "9" smd oval (at -3.95 0 90) (size 0.25 0.6) (layers "F.Cu" "F.Paste" "F.Mask")
      (net 1 "GND") (pinfunction "GND") (pintype "passive"))
    (pad "10" smd oval (at -3.95 0.4 90) (size 0.25 0.6) (layers "F.Cu" "F.Paste" "F.Mask")
      (net 138 "/Debug and JTAG/USB_3V3") (pinfunction "V_{CCIO}") (pintype "power_in"))
    (pad "11" smd oval (at -3.95 0.8 90) (size 0.25 0.6) (layers "F.Cu" "F.Paste" "F.Mask")
      (net 171 "/Debug and JTAG/FTDI_TDO") (pinfunction "ADBUS2") (pintype "bidirectional"))
    (pad "12" smd oval (at -3.95 1.199 90) (size 0.25 0.6) (layers "F.Cu" "F.Paste" "F.Mask")
      (net 170 "/Debug and JTAG/FTDI_TMS") (pinfunction "ADBUS3") (pintype "bidirectional"))
    (pad "13" smd oval (at -3.95 1.6 90) (size 0.25 0.6) (layers "F.Cu" "F.Paste" "F.Mask")
      (net 169 "/Debug and JTAG/JTAG_VCCO_ON") (pinfunction "ADBUS4") (pintype "bidirectional"))
    (pad "14" smd oval (at -3.95 1.999 90) (size 0.25 0.6) (layers "F.Cu" "F.Paste" "F.Mask")
      (net 159 "/Debug and JTAG/~{FTDI_LS_OE}") (pinfunction "ADBUS5") (pintype "bidirectional"))
    (pad "15" smd oval (at -3.95 2.398 90) (size 0.25 0.6) (layers "F.Cu" "F.Paste" "F.Mask")
      (net 168 "/Debug and JTAG/~{FTDI_PS_POR}") (pinfunction "ADBUS6") (pintype "bidirectional"))
    (pad "16" smd oval (at -3.95 2.798 90) (size 0.25 0.6) (layers "F.Cu" "F.Paste" "F.Mask")
      (net 167 "/Debug and JTAG/~{FTDI_PS_SRST}") (pinfunction "ADBUS7") (pintype "bidirectional"))
    (pad "17" smd oval (at -3.95 3.2 90) (size 0.25 0.6) (layers "F.Cu" "F.Paste" "F.Mask")
      (net 166 "/Debug and JTAG/FTDI_UARTB_TXD") (pinfunction "BDBUS0") (pintype "bidirectional"))
    (pad "18" smd oval (at -3.202 3.95) (size 0.25 0.6) (layers "F.Cu" "F.Paste" "F.Mask")
      (net 165 "/Debug and JTAG/FTDI_UARTB_RXD") (pinfunction "BDBUS1") (pintype "bidirectional"))
    (pad "19" smd oval (at -2.801 3.95) (size 0.25 0.6) (layers "F.Cu" "F.Paste" "F.Mask")
      (net 739 "unconnected-(U40-BDBUS2-Pad19)") (pinfunction "BDBUS2") (pintype "bidirectional+no_connect"))
    (pad "20" smd oval (at -2.4 3.95) (size 0.25 0.6) (layers "F.Cu" "F.Paste" "F.Mask")
      (net 740 "unconnected-(U40-BDBUS3-Pad20)") (pinfunction "BDBUS3") (pintype "bidirectional+no_connect"))
    (pad "21" smd oval (at -2 3.95) (size 0.25 0.6) (layers "F.Cu" "F.Paste" "F.Mask")
      (net 741 "unconnected-(U40-BDBUS4-Pad21)") (pinfunction "BDBUS4") (pintype "bidirectional+no_connect"))
    (pad "22" smd oval (at -1.601 3.95) (size 0.25 0.6) (layers "F.Cu" "F.Paste" "F.Mask")
      (net 742 "unconnected-(U40-BDBUS5-Pad22)") (pinfunction "BDBUS5") (pintype "bidirectional+no_connect"))
    (pad "23" smd oval (at -1.2 3.95) (size 0.25 0.6) (layers "F.Cu" "F.Paste" "F.Mask")
      (net 743 "unconnected-(U40-BDBUS6-Pad23)") (pinfunction "BDBUS6") (pintype "bidirectional+no_connect"))
    (pad "24" smd oval (at -0.802 3.95) (size 0.25 0.6) (layers "F.Cu" "F.Paste" "F.Mask")
      (net 744 "unconnected-(U40-BDBUS7-Pad24)") (pinfunction "BDBUS7") (pintype "bidirectional+no_connect"))
    (pad "25" smd oval (at -0.402 3.95) (size 0.25 0.6) (layers "F.Cu" "F.Paste" "F.Mask")
      (net 132 "/Debug and JTAG/USB_1V2") (pinfunction "V_{CORE}") (pintype "power_in"))
    (pad "26" smd oval (at 0 3.95) (size 0.25 0.6) (layers "F.Cu" "F.Paste" "F.Mask")
      (net 138 "/Debug and JTAG/USB_3V3") (pinfunction "V_{CCIO}") (pintype "passive"))
    (pad "27" smd oval (at 0.4 3.95) (size 0.25 0.6) (layers "F.Cu" "F.Paste" "F.Mask")
      (net 137 "/Debug and JTAG/XIN") (pinfunction "OSCI") (pintype "input"))
    (pad "28" smd oval (at 0.8 3.95) (size 0.25 0.6) (layers "F.Cu" "F.Paste" "F.Mask")
      (net 139 "/Debug and JTAG/XOUT") (pinfunction "OSCO") (pintype "output"))
    (pad "29" smd oval (at 1.199 3.95) (size 0.25 0.6) (layers "F.Cu" "F.Paste" "F.Mask")
      (net 1 "GND") (pinfunction "GND") (pintype "power_in"))
    (pad "30" smd oval (at 1.6 3.95) (size 0.25 0.6) (layers "F.Cu" "F.Paste" "F.Mask")
      (net 134 "/Debug and JTAG/VREGIN") (pinfunction "V_{REGIN}") (pintype "power_in"))
    (pad "31" smd oval (at 1.999 3.95) (size 0.25 0.6) (layers "F.Cu" "F.Paste" "F.Mask")
      (net 132 "/Debug and JTAG/USB_1V2") (pinfunction "V_{REGOUT}") (pintype "power_out"))
    (pad "32" smd oval (at 2.398 3.95) (size 0.25 0.6) (layers "F.Cu" "F.Paste" "F.Mask")
      (net 745 "unconnected-(U40-F_{SOURCE}-Pad32)") (pinfunction "F_{SOURCE}") (pintype "input+no_connect"))
    (pad "33" smd oval (at 2.798 3.95) (size 0.25 0.6) (layers "F.Cu" "F.Paste" "F.Mask")
      (net 746 "unconnected-(U40-V_{PP}-Pad33)") (pinfunction "V_{PP}") (pintype "power_in+no_connect"))
    (pad "34" smd oval (at 3.2 3.95) (size 0.25 0.6) (layers "F.Cu" "F.Paste" "F.Mask")
      (net 699 "Net-(U40-CDBUS0)") (pinfunction "CDBUS0") (pintype "bidirectional"))
    (pad "35" smd oval (at 3.95 3.2 90) (size 0.25 0.6) (layers "F.Cu" "F.Paste" "F.Mask")
      (net 700 "Net-(U40-CDBUS1)") (pinfunction "CDBUS1") (pintype "bidirectional"))
    (pad "36" smd oval (at 3.95 2.798 90) (size 0.25 0.6) (layers "F.Cu" "F.Paste" "F.Mask")
      (net 747 "unconnected-(U40-CDBUS2-Pad36)") (pinfunction "CDBUS2") (pintype "bidirectional+no_connect"))
    (pad "37" smd oval (at 3.95 2.398 90) (size 0.25 0.6) (layers "F.Cu" "F.Paste" "F.Mask")
      (net 748 "unconnected-(U40-CDBUS3-Pad37)") (pinfunction "CDBUS3") (pintype "bidirectional+no_connect"))
    (pad "38" smd oval (at 3.95 1.999 90) (size 0.25 0.6) (layers "F.Cu" "F.Paste" "F.Mask")
      (net 749 "unconnected-(U40-CDBUS4-Pad38)") (pinfunction "CDBUS4") (pintype "bidirectional+no_connect"))
    (pad "39" smd oval (at 3.95 1.6 90) (size 0.25 0.6) (layers "F.Cu" "F.Paste" "F.Mask")
      (net 138 "/Debug and JTAG/USB_3V3") (pinfunction "V_{CCIO}") (pintype "passive"))
    (pad "40" smd oval (at 3.95 1.199 90) (size 0.25 0.6) (layers "F.Cu" "F.Paste" "F.Mask")
      (net 750 "unconnected-(U40-CDBUS5-Pad40)") (pinfunction "CDBUS5") (pintype "bidirectional+no_connect"))
    (pad "41" smd oval (at 3.95 0.8 90) (size 0.25 0.6) (layers "F.Cu" "F.Paste" "F.Mask")
      (net 751 "unconnected-(U40-CDBUS6-Pad41)") (pinfunction "CDBUS6") (pintype "bidirectional+no_connect"))
    (pad "42" smd oval (at 3.95 0.4 90) (size 0.25 0.6) (layers "F.Cu" "F.Paste" "F.Mask")
      (net 752 "unconnected-(U40-CDBUS7-Pad42)") (pinfunction "CDBUS7") (pintype "bidirectional+no_connect"))
    (pad "43" smd oval (at 3.95 0 90) (size 0.25 0.6) (layers "F.Cu" "F.Paste" "F.Mask")
      (net 753 "unconnected-(U40-~{SUSPEND}-Pad43)") (pinfunction "~{SUSPEND}") (pintype "output+no_connect"))
    (pad "44" smd oval (at 3.95 -0.402 90) (size 0.25 0.6) (layers "F.Cu" "F.Paste" "F.Mask")
      (net 132 "/Debug and JTAG/USB_1V2") (pinfunction "V_{CORE}") (pintype "passive"))
    (pad "45" smd oval (at 3.95 -0.802 90) (size 0.25 0.6) (layers "F.Cu" "F.Paste" "F.Mask")
      (net 754 "unconnected-(U40-DDBUS0-Pad45)") (pinfunction "DDBUS0") (pintype "bidirectional+no_connect"))
    (pad "46" smd oval (at 3.95 -1.2 90) (size 0.25 0.6) (layers "F.Cu" "F.Paste" "F.Mask")
      (net 158 "/Debug and JTAG/FTDI_EEPROM_WC") (pinfunction "DDBUS1") (pintype "bidirectional"))
    (pad "47" smd oval (at 3.95 -1.601 90) (size 0.25 0.6) (layers "F.Cu" "F.Paste" "F.Mask")
      (net 755 "unconnected-(U40-DDBUS2-Pad47)") (pinfunction "DDBUS2") (pintype "bidirectional+no_connect"))
    (pad "48" smd oval (at 3.95 -2 90) (size 0.25 0.6) (layers "F.Cu" "F.Paste" "F.Mask")
      (net 758 "unconnected-(U40-DDBUS3-Pad48)") (pinfunction "DDBUS3") (pintype "bidirectional+no_connect"))
    (pad "49" smd oval (at 3.95 -2.4 90) (size 0.25 0.6) (layers "F.Cu" "F.Paste" "F.Mask")
      (net 759 "unconnected-(U40-DDBUS4-Pad49)") (pinfunction "DDBUS4") (pintype "bidirectional+no_connect"))
    (pad "50" smd oval (at 3.95 -2.801 90) (size 0.25 0.6) (layers "F.Cu" "F.Paste" "F.Mask")
      (net 760 "unconnected-(U40-DDBUS5-Pad50)") (pinfunction "DDBUS5") (pintype "bidirectional+no_connect"))
    (pad "51" smd oval (at 3.95 -3.202 90) (size 0.25 0.6) (layers "F.Cu" "F.Paste" "F.Mask")
      (net 138 "/Debug and JTAG/USB_3V3") (pinfunction "V_{CCIO}") (pintype "passive"))
    (pad "52" smd oval (at 3.2 -3.95) (size 0.25 0.6) (layers "F.Cu" "F.Paste" "F.Mask")
      (net 761 "unconnected-(U40-DDBUS6-Pad52)") (pinfunction "DDBUS6") (pintype "bidirectional+no_connect"))
    (pad "53" smd oval (at 2.798 -3.95) (size 0.25 0.6) (layers "F.Cu" "F.Paste" "F.Mask")
      (net 762 "unconnected-(U40-DDBUS7-Pad53)") (pinfunction "DDBUS7") (pintype "bidirectional+no_connect"))
    (pad "54" smd oval (at 2.398 -3.95) (size 0.25 0.6) (layers "F.Cu" "F.Paste" "F.Mask")
      (net 229 "/Debug and JTAG/PD_EN") (pinfunction "GPIO2") (pintype "bidirectional"))
    (pad "55" smd oval (at 1.999 -3.95) (size 0.25 0.6) (layers "F.Cu" "F.Paste" "F.Mask")
      (net 764 "unconnected-(U40-GPIO1-Pad55)") (pinfunction "GPIO1") (pintype "bidirectional+no_connect"))
    (pad "56" smd oval (at 1.6 -3.95) (size 0.25 0.6) (layers "F.Cu" "F.Paste" "F.Mask")
      (net 775 "unconnected-(U40-GPIO0-Pad56)") (pinfunction "GPIO0") (pintype "bidirectional+no_connect"))
    (pad "57" smd oval (at 1.199 -3.95) (size 0.25 0.6) (layers "F.Cu" "F.Paste" "F.Mask")
      (net 135 "/Debug and JTAG/VCC_USB") (pinfunction "V_{CC_USB}") (pintype "power_in"))
    (pad "58" smd oval (at 0.8 -3.95) (size 0.25 0.6) (layers "F.Cu" "F.Paste" "F.Mask")
      (net 234 "/Debug and JTAG/USB_N") (pinfunction "D-") (pintype "bidirectional"))
    (pad "59" smd oval (at 0.4 -3.95) (size 0.25 0.6) (layers "F.Cu" "F.Paste" "F.Mask")
      (net 233 "/Debug and JTAG/USB_P") (pinfunction "D+") (pintype "bidirectional"))
    (pad "60" smd oval (at 0 -3.95) (size 0.25 0.6) (layers "F.Cu" "F.Paste" "F.Mask")
      (net 680 "Net-(U40-REF)") (pinfunction "REF") (pintype "input"))
    (pad "61" smd oval (at -0.402 -3.95) (size 0.25 0.6) (layers "F.Cu" "F.Paste" "F.Mask")
      (net 133 "/Debug and JTAG/VCC_PD") (pinfunction "V_{CC_PD}") (pintype "power_in"))
    (pad "62" smd oval (at -0.802 -3.95) (size 0.25 0.6) (layers "F.Cu" "F.Paste" "F.Mask")
      (net 308 "/Debug and JTAG/USBC_CC2") (pinfunction "PD1_{CC2}") (pintype "bidirectional"))
    (pad "63" smd oval (at -1.2 -3.95) (size 0.25 0.6) (layers "F.Cu" "F.Paste" "F.Mask")
      (net 136 "/Debug and JTAG/PD1_SVBUS") (pinfunction "PD1_{SVBUS}") (pintype "input"))
    (pad "64" smd oval (at -1.601 -3.95) (size 0.25 0.6) (layers "F.Cu" "F.Paste" "F.Mask")
      (net 133 "/Debug and JTAG/VCC_PD") (pinfunction "PD1_{VCONN}") (pintype "power_in"))
    (pad "65" smd oval (at -2 -3.95) (size 0.25 0.6) (layers "F.Cu" "F.Paste" "F.Mask")
      (net 307 "/Debug and JTAG/USBC_CC1") (pinfunction "PD1_{CC1}") (pintype "bidirectional"))
    (pad "66" smd oval (at -2.4 -3.95) (size 0.25 0.6) (layers "F.Cu" "F.Paste" "F.Mask")
      (net 132 "/Debug and JTAG/USB_1V2") (pinfunction "V_{CORE}") (pintype "passive"))
    (pad "67" smd oval (at -2.801 -3.95) (size 0.25 0.6) (layers "F.Cu" "F.Paste" "F.Mask")
      (net 164 "/Debug and JTAG/~{FTDI_PWREN}") (pinfunction "~{PWREN}") (pintype "output"))
    (pad "68" smd oval (at -3.202 -3.95) (size 0.25 0.6) (layers "F.Cu" "F.Paste" "F.Mask")
      (net 232 "/Debug and JTAG/EECS") (pinfunction "EECS") (pintype "bidirectional"))
    (pad "EP" smd rect (at 0 0) (size 5.2 5.2) (layers "F.Cu" "F.Mask")
      (net 1 "GND") (pinfunction "EP") (pintype "passive"))
  )

  (footprint "kria-k26-devboard-footprints:UQFN-16-1.8x2.6mm_P0.4mm_Texas_RSV0016A" (layer "F.Cu")
    (at 139.425 121.2 90)
    (descr "https://www.ti.com/lit/ds/symlink/sn74avch4t245-ep.pdf?ts=1679484181203&ref_url=https%253A%252F%252Fwww.ti.com%252Fproduct%252FSN74AVCH4T245-EP%253Futm_source%253Dgoogle%2526utm_medium%253Dcpc%2526utm_campaign%253Dasc-int-null-prodfolderdynamic-cpc-pf-google-wwe_int%2526utm_content%253Dprodfolddynamic%2526ds_k%253DDYNAMIC%2BSEARCH%2BADS%2526DCM%253Dyes%2526gclid%253DCjwKCAjwzuqgBhAcEiwAdj5dRvR_WgyvqqhLxMx8zfbFv2a6tg33JIMv01Bn4M1kA4JzW1nDDW7OzhoCRbkQAvD_BwE%2526gclsrc%253Daw.ds")
    (property "Author" "Antmicro")
    (property "License" "Apache-2.0")
    (property "MPN" "74AVC4T245RSVRG4")
    (property "Manufacturer" "Texas Instruments")
    (property "Sheetfile" "debug.kicad_sch")
    (property "Sheetname" "Debug and JTAG")
    (property "ki_description" "Logic translator/level shifter")
    (property "ki_keywords" "SMT, LOGIC, IC, LEVEL-SHIFTER")
    (attr smd)
    (fp_text reference "U43" (at 1.37 -2.055 180) (layer "F.SilkS")
        (effects (font (size 0.7 0.7) (thickness 0.15)) (justify left bottom))
    )
    (fp_text value "74AVC4T245_UQFN" (at -1.25 2.5 90) (layer "F.Fab") hide
        (effects (font (size 0.7 0.7) (thickness 0.15)) (justify left bottom))
    )
    (fp_text user "." (at -1.45 -0.75 90) (layer "F.SilkS")
        (effects (font (size 0.7 0.7) (thickness 0.15)) (justify left bottom))
    )
    (fp_text user "License: Apache-2.0" (at -1.25 6.25 90) (layer "F.Fab") hide
        (effects (font (size 0.7 0.7) (thickness 0.15)) (justify left bottom))
    )
    (fp_text user "Author: Antmicro" (at -1.25 5 90) (layer "F.Fab") hide
        (effects (font (size 0.7 0.7) (thickness 0.15)) (justify left bottom))
    )
    (fp_text user "${REFERENCE}" (at -1.25 3.75 90) (layer "F.Fab") hide
        (effects (font (size 0.7 0.7) (thickness 0.15)) (justify left bottom))
    )
    (fp_line (start -0.9 1.2995) (end -0.9 0.8)
      (stroke (width 0.15) (type solid)) (layer "F.SilkS"))
    (fp_line (start -0.8 -1.3) (end -0.9 -1.3)
      (stroke (width 0.15) (type solid)) (layer "F.SilkS"))
    (fp_line (start -0.8 1.2995) (end -0.9 1.2995)
      (stroke (width 0.15) (type solid)) (layer "F.SilkS"))
    (fp_line (start 0.8 -1.3) (end 0.9 -1.3)
      (stroke (width 0.15) (type solid)) (layer "F.SilkS"))
    (fp_line (start 0.8 1.3) (end 0.899 1.3)
      (stroke (width 0.15) (type solid)) (layer "F.SilkS"))
    (fp_line (start 0.9 -1.3) (end 0.9 -0.8005)
      (stroke (width 0.15) (type solid)) (layer "F.SilkS"))
    (fp_line (start 0.9 0.8) (end 0.899 1.3)
      (stroke (width 0.15) (type solid)) (layer "F.SilkS"))
    (fp_rect (start -1.25 -1.65) (end 1.25 1.65)
      (stroke (width 0.05) (type solid)) (fill none) (layer "F.CrtYd"))
    (fp_line (start -0.902 1.3) (end -0.902 -1.301)
      (stroke (width 0.15) (type solid)) (layer "F.Fab"))
    (fp_line (start 0.9 -1.301) (end -0.902 -1.301)
      (stroke (width 0.15) (type solid)) (layer "F.Fab"))
    (fp_line (start 0.9 1.3) (end -0.902 1.3)
      (stroke (width 0.15) (type solid)) (layer "F.Fab"))
    (fp_line (start 0.9 1.3) (end 0.9 -1.301)
      (stroke (width 0.15) (type solid)) (layer "F.Fab"))
    (pad "1" smd roundrect (at -0.75 -0.6 90) (size 0.7 0.2) (layers "F.Cu" "F.Paste" "F.Mask") (roundrect_rratio 0.2272727273)
      (net 160 "/Debug and JTAG/~{LS_OE}") (pinfunction "1~{OE}") (pintype "input"))
    (pad "2" smd roundrect (at -0.802 -0.202 90) (size 0.6 0.2) (layers "F.Cu" "F.Paste" "F.Mask") (roundrect_rratio 0.2272727273)
      (net 17 "PS_1V8") (pinfunction "VCCB") (pintype "power_in"))
    (pad "3" smd roundrect (at -0.802 0.2 90) (size 0.6 0.2) (layers "F.Cu" "F.Paste" "F.Mask") (roundrect_rratio 0.2272727273)
      (net 138 "/Debug and JTAG/USB_3V3") (pinfunction "VCCA") (pintype "power_in"))
    (pad "4" smd roundrect (at -0.802 0.598 90) (size 0.6 0.2) (layers "F.Cu" "F.Paste" "F.Mask") (roundrect_rratio 0.2272727273)
      (net 1 "GND") (pinfunction "1DIR") (pintype "input"))
    (pad "5" smd roundrect (at -0.6 1.199 180) (size 0.6 0.2) (layers "F.Cu" "F.Paste" "F.Mask") (roundrect_rratio 0.2272727273)
      (net 1 "GND") (pinfunction "2DIR") (pintype "input"))
    (pad "6" smd roundrect (at -0.202 1.199 180) (size 0.6 0.2) (layers "F.Cu" "F.Paste" "F.Mask") (roundrect_rratio 0.2272727273)
      (net 171 "/Debug and JTAG/FTDI_TDO") (pinfunction "1A1") (pintype "bidirectional"))
    (pad "7" smd roundrect (at 0.2 1.199 180) (size 0.6 0.2) (layers "F.Cu" "F.Paste" "F.Mask") (roundrect_rratio 0.2272727273)
      (net 777 "unconnected-(U43-1A2-Pad7)") (pinfunction "1A2") (pintype "bidirectional+no_connect"))
    (pad "8" smd roundrect (at 0.598 1.199 180) (size 0.6 0.2) (layers "F.Cu" "F.Paste" "F.Mask") (roundrect_rratio 0.2272727273)
      (net 169 "/Debug and JTAG/JTAG_VCCO_ON") (pinfunction "2A1") (pintype "bidirectional"))
    (pad "9" smd roundrect (at 0.8 0.598 90) (size 0.6 0.2) (layers "F.Cu" "F.Paste" "F.Mask") (roundrect_rratio 0.2272727273)
      (net 778 "unconnected-(U43-2A2-Pad9)") (pinfunction "2A2") (pintype "bidirectional+no_connect"))
    (pad "10" smd roundrect (at 0.8 0.2 90) (size 0.6 0.2) (layers "F.Cu" "F.Paste" "F.Mask") (roundrect_rratio 0.2272727273)
      (net 1 "GND") (pinfunction "GND") (pintype "power_in"))
    (pad "11" smd roundrect (at 0.8 -0.202 90) (size 0.6 0.2) (layers "F.Cu" "F.Paste" "F.Mask") (roundrect_rratio 0.2272727273)
      (net 1 "GND") (pinfunction "GND") (pintype "passive"))
    (pad "12" smd roundrect (at 0.8 -0.6 90) (size 0.6 0.2) (layers "F.Cu" "F.Paste" "F.Mask") (roundrect_rratio 0.2272727273)
      (net 1 "GND") (pinfunction "2B2") (pintype "bidirectional"))
    (pad "13" smd roundrect (at 0.598 -1.2 180) (size 0.6 0.2) (layers "F.Cu" "F.Paste" "F.Mask") (roundrect_rratio 0.2272727273)
      (net 17 "PS_1V8") (pinfunction "2B1") (pintype "bidirectional"))
    (pad "14" smd roundrect (at 0.2 -1.2 180) (size 0.6 0.2) (layers "F.Cu" "F.Paste" "F.Mask") (roundrect_rratio 0.2272727273)
      (net 1 "GND") (pinfunction "1B2") (pintype "bidirectional"))
    (pad "15" smd roundrect (at -0.202 -1.2 180) (size 0.6 0.2) (layers "F.Cu" "F.Paste" "F.Mask") (roundrect_rratio 0.2272727273)
      (net 142 "/Debug and JTAG/JTAG_TDO_M2C") (pinfunction "1B1") (pintype "bidirectional"))
    (pad "16" smd roundrect (at -0.6 -1.2 180) (size 0.6 0.2) (layers "F.Cu" "F.Paste" "F.Mask") (roundrect_rratio 0.2272727273)
      (net 1 "GND") (pinfunction "2~{OE}") (pintype "input"))
  )

  (footprint "kria-k26-devboard-footprints:C_0402_1005Metric" (layer "F.Cu")
    (at 147.83 125.86 -90)
    (descr "Capacitor SMD 0402")
    (tags "capacitor SMD 0402")
    (property "Author" "Antmicro")
    (property "Dielectric" "")
    (property "License" "Apache-2.0")
    (property "MPN" "MC0402N180J500CT")
    (property "Manufacturer" "Multicomp")
    (property "Sheetfile" "debug.kicad_sch")
    (property "Sheetname" "Debug and JTAG")
    (property "Val" "18p")
    (property "Voltage" "")
    (property "ki_description" " ")
    (attr smd)
    (fp_text reference "C154" (at 1.42 0.52 -90) (layer "F.SilkS")
        (effects (font (size 0.7 0.7) (thickness 0.15)) (justify left bottom))
    )
    (fp_text value "C_18p_0402" (at 0 1.4 -90) (layer "F.Fab") hide
        (effects (font (size 0.7 0.7) (thickness 0.15)) (justify left bottom))
    )
    (fp_text user "Author: Antmicro" (at -0.932 4.17 -90) (layer "F.Fab") hide
        (effects (font (size 0.7 0.7) (thickness 0.15)) (justify left bottom))
    )
    (fp_text user "${REFERENCE}" (at -0.932 3.168 -90) (layer "F.Fab") hide
        (effects (font (size 0.7 0.7) (thickness 0.15)) (justify left bottom))
    )
    (fp_text user "License: Apache-2.0" (at -0.932 5.17 -90) (layer "F.Fab") hide
        (effects (font (size 0.7 0.7) (thickness 0.15)) (justify left bottom))
    )
    (fp_rect (start -0.94 -0.47) (end 0.94 0.47)
      (stroke (width 0.05) (type solid)) (fill none) (layer "F.CrtYd"))
    (fp_rect (start -0.499 -0.249) (end 0.499 0.249)
      (stroke (width 0.15) (type solid)) (fill none) (layer "F.Fab"))
    (pad "1" smd roundrect (at -0.484 0 270) (size 0.59 0.64) (layers "F.Cu" "F.Paste" "F.Mask") (roundrect_rratio 0.25)
      (net 137 "/Debug and JTAG/XIN") (pintype "passive"))
    (pad "2" smd roundrect (at 0.484 0 270) (size 0.59 0.64) (layers "F.Cu" "F.Paste" "F.Mask") (roundrect_rratio 0.25)
      (net 1 "GND") (pintype "passive"))
  )

  (footprint "kria-k26-devboard-footprints:LED_0603_1608Metric_G" (layer "F.Cu")
    (at 139.45 94.4 -90)
    (descr "LED SMD 0603 Green")
    (tags "LED SMD 0603 Green")
    (property "Author" "Antmicro")
    (property "Color" "Green")
    (property "License" "Apache-2.0")
    (property "MPN" "LG L29K-G2J1-24-Z")
    (property "Manufacturer" "OSRAM")
    (property "Sheetfile" "dc-dc-conventers.kicad_sch")
    (property "Sheetname" "DC/DC conventers")
    (property "ki_description" "LED, Green, SMT, 0603, 20 mA, 2.1 V, 570 nm")
    (property "ki_keywords" "0603, SMT, DIODE, SEMICONDUCTOR, UNICOLOR")
    (attr smd)
    (fp_text reference "D18" (at -0.97 -1.31 90) (layer "F.SilkS")
        (effects (font (size 0.7 0.7) (thickness 0.15)) (justify right bottom))
    )
    (fp_text value "LED_G_0603_LG_L29K-G2J1-24-Z" (at 0 1.6 90) (layer "F.Fab") hide
        (effects (font (size 0.7 0.7) (thickness 0.15)) (justify right bottom))
    )
    (fp_text user "License: Apache-2.0" (at -1.31 5.769 90) (layer "F.Fab") hide
        (effects (font (size 0.7 0.7) (thickness 0.15)) (justify right bottom))
    )
    (fp_text user "Author: Antmicro" (at -1.31 4.769 90) (layer "F.Fab") hide
        (effects (font (size 0.7 0.7) (thickness 0.15)) (justify right bottom))
    )
    (fp_text user "${REFERENCE}" (at -1.31 3.769 90) (layer "F.Fab") hide
        (effects (font (size 0.7 0.7) (thickness 0.15)) (justify right bottom))
    )
    (fp_line (start -0.27 -0.35) (end 0.27 -0.35)
      (stroke (width 0.15) (type solid)) (layer "F.SilkS"))
    (fp_line (start -0.27 0.351) (end 0.27 0.351)
      (stroke (width 0.15) (type solid)) (layer "F.SilkS"))
    (fp_line (start -0.106328 -0.200008) (end -0.106328 0.199992)
      (stroke (width 0.1) (type solid)) (layer "F.SilkS"))
    (fp_line (start -0.106328 -0.200008) (end 0.093672 -0.000008)
      (stroke (width 0.1) (type solid)) (layer "F.SilkS"))
    (fp_line (start -0.106328 -0.000008) (end -0.29 0)
      (stroke (width 0.1) (type solid)) (layer "F.SilkS"))
    (fp_line (start 0.093672 -0.200008) (end 0.093672 0.199992)
      (stroke (width 0.1) (type solid)) (layer "F.SilkS"))
    (fp_line (start 0.093672 -0.000008) (end -0.106328 0.199992)
      (stroke (width 0.1) (type solid)) (layer "F.SilkS"))
    (fp_line (start 0.093672 -0.000008) (end 0.293672 -0.000008)
      (stroke (width 0.1) (type solid)) (layer "F.SilkS"))
    (fp_line (start 1.25 0.32) (end 1.25 -0.32)
      (stroke (width 0.15) (type solid)) (layer "F.SilkS"))
    (fp_rect (start 1.26 0.65) (end -1.26 -0.65)
      (stroke (width 0.05) (type solid)) (fill none) (layer "F.CrtYd"))
    (fp_line (start -0.599 0) (end -0.201 0)
      (stroke (width 0.15) (type solid)) (layer "F.Fab"))
    (fp_line (start -0.201 -0.2) (end -0.201 0)
      (stroke (width 0.15) (type solid)) (layer "F.Fab"))
    (fp_line (start -0.201 0) (end -0.201 0.202)
      (stroke (width 0.15) (type solid)) (layer "F.Fab"))
    (fp_line (start -0.201 0.202) (end 0.101 0)
      (stroke (width 0.15) (type solid)) (layer "F.Fab"))
    (fp_line (start 0.101 0) (end -0.201 -0.2)
      (stroke (width 0.15) (type solid)) (layer "F.Fab"))
    (fp_line (start 0.199 -0.2) (end 0.199 -0.1)
      (stroke (width 0.15) (type solid)) (layer "F.Fab"))
    (fp_line (start 0.199 0) (end 0.597 0)
      (stroke (width 0.15) (type solid)) (layer "F.Fab"))
    (fp_line (start 0.199 0.202) (end 0.199 -0.1)
      (stroke (width 0.15) (type solid)) (layer "F.Fab"))
    (fp_rect (start -0.848 -0.4) (end 0.85 0.402)
      (stroke (width 0.15) (type solid)) (fill none) (layer "F.Fab"))
    (pad "1" smd rect (at -0.75 0 90) (size 0.8 0.8) (layers "F.Cu" "F.Paste" "F.Mask")
      (net 190 "Net-(D18-Pad1)") (pintype "passive"))
    (pad "2" smd rect (at 0.75 0 90) (size 0.8 0.8) (layers "F.Cu" "F.Paste" "F.Mask")
      (net 339 "Net-(Q14-C)") (pinfunction "2") (pintype "passive"))
  )

  (footprint "kria-k26-devboard-footprints:SOT-416" (layer "F.Cu")
    (at 149.382843 129.183096 -90)
    (descr "SOT-416")
    (tags "SOT-416")
    (property "Author" "Antmicro")
    (property "License" "Apache-2.0")
    (property "MPN" "DTC014TEBTL")
    (property "Manufacturer" "ROHM Semiconductor")
    (property "Sheetfile" "debug.kicad_sch")
    (property "Sheetname" "Debug and JTAG")
    (property "ki_description" "Digital NPN Transistor, 10k/NONE, EMT-3")
    (attr smd)
    (fp_text reference "Q12" (at 1.796904 1.162843) (layer "F.SilkS")
        (effects (font (size 0.7 0.7) (thickness 0.15)) (justify left bottom))
    )
    (fp_text value "DTC014T_SOT-416" (at 0 2 -90) (layer "F.Fab") hide
        (effects (font (size 0.7 0.7) (thickness 0.15)) (justify left bottom))
    )
    (fp_text user "Author: Antmicro" (at -1 4.602 -90) (layer "F.Fab") hide
        (effects (font (size 0.7 0.7) (thickness 0.15)) (justify left bottom))
    )
    (fp_text user "${REFERENCE}" (at -1 3.4 -90) (layer "F.Fab") hide
        (effects (font (size 0.7 0.7) (thickness 0.15)) (justify left bottom))
    )
    (fp_text user "License: Apache-2.0" (at -1 5.802 -90) (layer "F.Fab") hide
        (effects (font (size 0.7 0.7) (thickness 0.15)) (justify left bottom))
    )
    (fp_line (start -0.5 -0.15) (end -0.5 0.15)
      (stroke (width 0.15) (type solid)) (layer "F.SilkS"))
    (fp_line (start 0.5 0.9) (end -0.5 0.9)
      (stroke (width 0.15) (type solid)) (layer "F.SilkS"))
    (fp_line (start 0.5 0.9) (end 0.5 0.7)
      (stroke (width 0.15) (type solid)) (layer "F.SilkS"))
    (fp_line (start 0.508 -0.9) (end -0.5 -0.9)
      (stroke (width 0.15) (type solid)) (layer "F.SilkS"))
    (fp_line (start 0.508 -0.9) (end 0.508 -0.592)
      (stroke (width 0.15) (type solid)) (layer "F.SilkS"))
    (fp_rect (start -1 -1.05) (end 1 1.05)
      (stroke (width 0.05) (type solid)) (fill none) (layer "F.CrtYd"))
    (fp_line (start -0.05 -0.9) (end -0.45 -0.5)
      (stroke (width 0.15) (type solid)) (layer "F.Fab"))
    (fp_rect (start 0.45 0.9) (end -0.45 -0.9)
      (stroke (width 0.15) (type solid)) (fill none) (layer "F.Fab"))
    (pad "1" smd rect (at -0.652 -0.5 270) (size 0.6 0.5) (layers "F.Cu" "F.Paste" "F.Mask")
      (net 158 "/Debug and JTAG/FTDI_EEPROM_WC") (pinfunction "B") (pintype "input"))
    (pad "2" smd rect (at -0.652 0.498 270) (size 0.6 0.5) (layers "F.Cu" "F.Paste" "F.Mask")
      (net 1 "GND") (pinfunction "E") (pintype "passive"))
    (pad "3" smd rect (at 0.65 0 270) (size 0.6 0.5) (layers "F.Cu" "F.Paste" "F.Mask")
      (net 186 "/Debug and JTAG/~{EEPROM_WC}") (pinfunction "C") (pintype "passive"))
  )

  (footprint "kria-k26-devboard-footprints:R_0402_1005Metric" (layer "F.Cu")
    (at 148.225 110 -90)
    (descr "Resistor SMD 0402")
    (tags "resistor SMD 0402")
    (property "Author" "Antmicro")
    (property "Current" "1A")
    (property "DNP" "DNP")
    (property "License" "Apache-2.0")
    (property "MPN" "ERJ2GE0R00X")
    (property "Manufacturer" "Panasonic")
    (property "Sheetfile" "debug.kicad_sch")
    (property "Sheetname" "Debug and JTAG")
    (property "Tolerance" "")
    (property "Val" "0R")
    (property "dnp" "")
    (property "exclude_from_bom" "")
    (property "ki_description" "0R resistor in 0402 package with unspecified tolerance")
    (attr exclude_from_pos_files exclude_from_bom)
    (fp_text reference "R101" (at -3.22 -0.365 -90) (layer "F.SilkS")
        (effects (font (size 0.7 0.7) (thickness 0.15)) (justify left bottom))
    )
    (fp_text value "R_0R_0402" (at 0 1.4 -90) (layer "F.Fab") hide
        (effects (font (size 0.7 0.7) (thickness 0.15)) (justify left bottom))
    )
    (fp_text user "License: Apache-2.0" (at -0.95 5.169 -90) (layer "F.Fab") hide
        (effects (font (size 0.7 0.7) (thickness 0.15)) (justify left bottom))
    )
    (fp_text user "${REFERENCE}" (at -0.95 3.168 -90) (layer "F.Fab") hide
        (effects (font (size 0.7 0.7) (thickness 0.15)) (justify left bottom))
    )
    (fp_text user "Author: Antmicro" (at -0.95 4.169 -90) (layer "F.Fab") hide
        (effects (font (size 0.7 0.7) (thickness 0.15)) (justify left bottom))
    )
    (fp_rect (start -0.93 -0.47) (end 0.93 0.47)
      (stroke (width 0.05) (type solid)) (fill none) (layer "F.CrtYd"))
    (fp_rect (start -0.5 -0.25) (end 0.5 0.25)
      (stroke (width 0.15) (type solid)) (fill none) (layer "F.Fab"))
    (pad "1" smd roundrect (at -0.485 0 270) (size 0.59 0.64) (layers "F.Cu" "F.Paste" "F.Mask") (roundrect_rratio 0.25)
      (net 234 "/Debug and JTAG/USB_N") (pintype "passive"))
    (pad "2" smd roundrect (at 0.485 0 270) (size 0.59 0.64) (layers "F.Cu" "F.Paste" "F.Mask") (roundrect_rratio 0.25)
      (net 223 "/Debug and JTAG/USBB_N") (pintype "passive"))
  )

  (footprint "kria-k26-devboard-footprints:VQFN-16-1EP_3x3mm_P0.5mm_EP1.68x1.68mm" (layer "F.Cu")
    (at 114.9 121.3)
    (property "Author" "Antmicro")
    (property "License" "Apache-2.0")
    (property "MPN" "NB3L202KMNTXG")
    (property "Manufacturer" "ON Semiconductor")
    (property "Sheetfile" "clock.kicad_sch")
    (property "Sheetname" "Clock distribution")
    (property "ki_description" "Fanout Buffer, 2 Outputs, 2.97V to 3.63 V, QFN-16, -40°C to 85°C")
    (property "ki_keywords" "SMT, CLOCK, IC")
    (attr smd)
    (fp_text reference "U7" (at -1.31 -1.96) (layer "F.SilkS")
        (effects (font (size 0.7 0.7) (thickness 0.15)) (justify left bottom))
    )
    (fp_text value "NB3L202KMN" (at 0 2.999) (layer "F.Fab") hide
        (effects (font (size 0.7 0.7) (thickness 0.15)) (justify left bottom))
    )
    (fp_text user "License: Apache-2.0" (at -1.901 7.4) (layer "F.Fab") hide
        (effects (font (size 0.7 0.7) (thickness 0.15)) (justify left bottom))
    )
    (fp_text user "${REFERENCE}" (at -1.901 4.998) (layer "F.Fab") hide
        (effects (font (size 0.7 0.7) (thickness 0.15)) (justify left bottom))
    )
    (fp_text user "Author: Antmicro" (at -1.901 6.2) (layer "F.Fab") hide
        (effects (font (size 0.7 0.7) (thickness 0.15)) (justify left bottom))
    )
    (fp_line (start -1.5 -1.5) (end -1.5 -0.951)
      (stroke (width 0.15) (type solid)) (layer "F.SilkS"))
    (fp_line (start -1.5 1.499) (end -1.5 0.95)
      (stroke (width 0.15) (type solid)) (layer "F.SilkS"))
    (fp_line (start -1.5 1.499) (end -0.951 1.499)
      (stroke (width 0.15) (type solid)) (layer "F.SilkS"))
    (fp_line (start -0.95 -1.501) (end -1.5 -1.5)
      (stroke (width 0.15) (type solid)) (layer "F.SilkS"))
    (fp_line (start 0.95 1.499) (end 1.499 1.499)
      (stroke (width 0.15) (type solid)) (layer "F.SilkS"))
    (fp_line (start 1.499 -1.5) (end 0.95 -1.5)
      (stroke (width 0.15) (type solid)) (layer "F.SilkS"))
    (fp_line (start 1.499 0.95) (end 1.499 1.499)
      (stroke (width 0.15) (type solid)) (layer "F.SilkS"))
    (fp_line (start 1.5 -0.95) (end 1.499 -1.5)
      (stroke (width 0.15) (type solid)) (layer "F.SilkS"))
    (fp_circle (center -1.75 -1.07071) (end -1.7 -1.02071)
      (stroke (width 0.15) (type solid)) (fill solid) (layer "F.SilkS"))
    (fp_rect (start -1.75 -1.75) (end 1.75 1.75)
      (stroke (width 0.05) (type solid)) (fill none) (layer "F.CrtYd"))
    (fp_line (start -1.5 -1.2) (end -1.5 1.499)
      (stroke (width 0.15) (type solid)) (layer "F.Fab"))
    (fp_line (start -1.5 -1.2) (end -1.2 -1.5)
      (stroke (width 0.15) (type solid)) (layer "F.Fab"))
    (fp_line (start -1.2 -1.5) (end 1.499 -1.5)
      (stroke (width 0.15) (type solid)) (layer "F.Fab"))
    (fp_line (start 1.499 1.499) (end -1.5 1.499)
      (stroke (width 0.15) (type solid)) (layer "F.Fab"))
    (fp_line (start 1.499 1.499) (end 1.499 -1.5)
      (stroke (width 0.15) (type solid)) (layer "F.Fab"))
    (pad "1" smd roundrect (at -1.401 -0.75) (size 0.6 0.25) (layers "F.Cu" "F.Paste" "F.Mask") (roundrect_rratio 0.2)
      (net 1 "GND") (pinfunction "GND") (pintype "power_in"))
    (pad "2" smd roundrect (at -1.401 -0.25) (size 0.6 0.25) (layers "F.Cu" "F.Paste" "F.Mask") (roundrect_rratio 0.2)
      (net 297 "/Clock distribution/CLK_100M_N") (pinfunction "CLK_{IN}+") (pintype "input"))
    (pad "3" smd roundrect (at -1.401 0.248) (size 0.6 0.25) (layers "F.Cu" "F.Paste" "F.Mask") (roundrect_rratio 0.2)
      (net 296 "/Clock distribution/CLK_100M_P") (pinfunction "CLK_{IN}-") (pintype "input"))
    (pad "4" smd roundrect (at -1.401 0.748) (size 0.6 0.25) (layers "F.Cu" "F.Paste" "F.Mask") (roundrect_rratio 0.2)
      (net 15 "PS_3V3") (pinfunction "VDD") (pintype "power_in"))
    (pad "5" smd roundrect (at -0.75 1.398 90) (size 0.6 0.25) (layers "F.Cu" "F.Paste" "F.Mask") (roundrect_rratio 0.2)
      (net 1 "GND") (pinfunction "GND_O") (pintype "passive"))
    (pad "6" smd roundrect (at -0.25 1.398 90) (size 0.6 0.25) (layers "F.Cu" "F.Paste" "F.Mask") (roundrect_rratio 0.2)
      (net 121 "/Clock distribution/GTR_REFCLK3_N") (pinfunction "DIF_{1}-") (pintype "output"))
    (pad "7" smd roundrect (at 0.248 1.398 90) (size 0.6 0.25) (layers "F.Cu" "F.Paste" "F.Mask") (roundrect_rratio 0.2)
      (net 122 "/Clock distribution/GTR_REFCLK3_P") (pinfunction "DIF_{1}+") (pintype "output"))
    (pad "8" smd roundrect (at 0.748 1.398 90) (size 0.6 0.25) (layers "F.Cu" "F.Paste" "F.Mask") (roundrect_rratio 0.2)
      (net 15 "PS_3V3") (pinfunction "VDD_O") (pintype "passive"))
    (pad "9" smd roundrect (at 1.398 0.748 180) (size 0.6 0.25) (layers "F.Cu" "F.Paste" "F.Mask") (roundrect_rratio 0.2)
      (net 1 "GND") (pinfunction "GND") (pintype "passive"))
    (pad "10" smd roundrect (at 1.398 0.248 180) (size 0.6 0.25) (layers "F.Cu" "F.Paste" "F.Mask") (roundrect_rratio 0.2)
      (net 642 "Net-(U7-I_{REF})") (pinfunction "I_{REF}") (pintype "input"))
    (pad "11" smd roundrect (at 1.398 -0.25 180) (size 0.6 0.25) (layers "F.Cu" "F.Paste" "F.Mask") (roundrect_rratio 0.2)
      (net 429 "Net-(Q3-C)") (pinfunction "~{OE0}") (pintype "input"))
    (pad "12" smd roundrect (at 1.398 -0.75 180) (size 0.6 0.25) (layers "F.Cu" "F.Paste" "F.Mask") (roundrect_rratio 0.2)
      (net 226 "/Clock distribution/~{M2_CLKREQ}") (pinfunction "~{OE1}") (pintype "input"))
    (pad "13" smd roundrect (at 0.748 -1.401 270) (size 0.6 0.25) (layers "F.Cu" "F.Paste" "F.Mask") (roundrect_rratio 0.2)
      (net 15 "PS_3V3") (pinfunction "VDD_O") (pintype "power_in"))
    (pad "14" smd roundrect (at 0.248 -1.401 270) (size 0.6 0.25) (layers "F.Cu" "F.Paste" "F.Mask") (roundrect_rratio 0.2)
      (net 107 "/Clock distribution/GTR_REFCLK3_C2M_P") (pinfunction "DIF_{0}+") (pintype "output"))
    (pad "15" smd roundrect (at -0.25 -1.401 270) (size 0.6 0.25) (layers "F.Cu" "F.Paste" "F.Mask") (roundrect_rratio 0.2)
      (net 108 "/Clock distribution/GTR_REFCLK3_C2M_N") (pinfunction "DIF_{0}-") (pintype "output"))
    (pad "16" smd roundrect (at -0.75 -1.401 270) (size 0.6 0.25) (layers "F.Cu" "F.Paste" "F.Mask") (roundrect_rratio 0.2)
      (net 1 "GND") (pinfunction "GND_O") (pintype "power_in"))
    (pad "17" smd roundrect (at 0 0) (size 1.55 1.55) (layers "F.Cu" "F.Paste" "F.Mask") (roundrect_rratio 0.2)
      (net 1 "GND") (pinfunction "EPAD") (pintype "power_in"))
  )

  (footprint "kria-k26-devboard-footprints:R_0402_1005Metric" (layer "F.Cu")
    (at 111.08 122.25 90)
    (descr "Resistor SMD 0402")
    (tags "resistor SMD 0402")
    (property "Author" "Antmicro")
    (property "License" "Apache-2.0")
    (property "MPN" "CR0402-FX-49R9GLF")
    (property "Manufacturer" "Bourns")
    (property "Sheetfile" "clock.kicad_sch")
    (property "Sheetname" "Clock distribution")
    (property "Tolerance" "1%")
    (property "Val" "49R9")
    (property "ki_description" "49R9 resistor in 0402 package with 1% tolerance")
    (attr smd)
    (fp_text reference "R20" (at -2.99 0.33 90) (layer "F.SilkS")
        (effects (font (size 0.7 0.7) (thickness 0.15)) (justify left bottom))
    )
    (fp_text value "R_49R9_0402" (at 0 1.4 90) (layer "F.Fab") hide
        (effects (font (size 0.7 0.7) (thickness 0.15)) (justify left bottom))
    )
    (fp_text user "License: Apache-2.0" (at -0.95 5.169 90) (layer "F.Fab") hide
        (effects (font (size 0.7 0.7) (thickness 0.15)) (justify left bottom))
    )
    (fp_text user "Author: Antmicro" (at -0.95 4.169 90) (layer "F.Fab") hide
        (effects (font (size 0.7 0.7) (thickness 0.15)) (justify left bottom))
    )
    (fp_text user "${REFERENCE}" (at -0.95 3.168 90) (layer "F.Fab") hide
        (effects (font (size 0.7 0.7) (thickness 0.15)) (justify left bottom))
    )
    (fp_rect (start -0.93 -0.47) (end 0.93 0.47)
      (stroke (width 0.05) (type solid)) (fill none) (layer "F.CrtYd"))
    (fp_rect (start -0.5 -0.25) (end 0.5 0.25)
      (stroke (width 0.15) (type solid)) (fill none) (layer "F.Fab"))
    (pad "1" smd roundrect (at -0.485 0 90) (size 0.59 0.64) (layers "F.Cu" "F.Paste" "F.Mask") (roundrect_rratio 0.25)
      (net 1 "GND") (pintype "passive"))
    (pad "2" smd roundrect (at 0.485 0 90) (size 0.59 0.64) (layers "F.Cu" "F.Paste" "F.Mask") (roundrect_rratio 0.25)
      (net 296 "/Clock distribution/CLK_100M_P") (pintype "passive"))
  )

  (footprint "kria-k26-devboard-footprints:R_0402_1005Metric" (layer "F.Cu")
    (at 111.08 120.35 -90)
    (descr "Resistor SMD 0402")
    (tags "resistor SMD 0402")
    (property "Author" "Antmicro")
    (property "License" "Apache-2.0")
    (property "MPN" "CR0402-FX-49R9GLF")
    (property "Manufacturer" "Bourns")
    (property "Sheetfile" "clock.kicad_sch")
    (property "Sheetname" "Clock distribution")
    (property "Tolerance" "1%")
    (property "Val" "49R9")
    (property "ki_description" "49R9 resistor in 0402 package with 1% tolerance")
    (attr smd)
    (fp_text reference "R21" (at 0.95 -1.28 -90) (layer "F.SilkS")
        (effects (font (size 0.7 0.7) (thickness 0.15)) (justify left bottom))
    )
    (fp_text value "R_49R9_0402" (at 0 1.4 -90) (layer "F.Fab") hide
        (effects (font (size 0.7 0.7) (thickness 0.15)) (justify left bottom))
    )
    (fp_text user "Author: Antmicro" (at -0.95 4.169 -90) (layer "F.Fab") hide
        (effects (font (size 0.7 0.7) (thickness 0.15)) (justify left bottom))
    )
    (fp_text user "${REFERENCE}" (at -0.95 3.168 -90) (layer "F.Fab") hide
        (effects (font (size 0.7 0.7) (thickness 0.15)) (justify left bottom))
    )
    (fp_text user "License: Apache-2.0" (at -0.95 5.169 -90) (layer "F.Fab") hide
        (effects (font (size 0.7 0.7) (thickness 0.15)) (justify left bottom))
    )
    (fp_rect (start -0.93 -0.47) (end 0.93 0.47)
      (stroke (width 0.05) (type solid)) (fill none) (layer "F.CrtYd"))
    (fp_rect (start -0.5 -0.25) (end 0.5 0.25)
      (stroke (width 0.15) (type solid)) (fill none) (layer "F.Fab"))
    (pad "1" smd roundrect (at -0.485 0 270) (size 0.59 0.64) (layers "F.Cu" "F.Paste" "F.Mask") (roundrect_rratio 0.25)
      (net 1 "GND") (pintype "passive"))
    (pad "2" smd roundrect (at 0.485 0 270) (size 0.59 0.64) (layers "F.Cu" "F.Paste" "F.Mask") (roundrect_rratio 0.25)
      (net 297 "/Clock distribution/CLK_100M_N") (pintype "passive"))
  )

  (footprint "kria-k26-devboard-footprints:Oscillator_SMD_Abracon_AX3_3.2x2.5x1mm" (layer "F.Cu")
    (at 109 120.7)
    (property "Author" "Antmicro")
    (property "License" "Apache-2.0")
    (property "MPN" "NX3241E0100.000000")
    (property "Manufacturer" "Diodes Incorporated")
    (property "Sheetfile" "clock.kicad_sch")
    (property "Sheetname" "Clock distribution")
    (property "Val" "100 MHz")
    (property "ki_description" "100 MHz XO (Standard) HCSL Oscillator 3.3V Enable/Disable 6-SMD, No Lead")
    (property "ki_keywords" "OSCILLATOR")
    (attr smd)
    (fp_text reference "Y1" (at 0.8 2.73) (layer "F.SilkS")
        (effects (font (size 0.7 0.7) (thickness 0.15)) (justify right bottom))
    )
    (fp_text value "Oscillator_100MHz_NX324" (at 0 2.8) (layer "F.Fab") hide
        (effects (font (size 0.7 0.7) (thickness 0.15)) (justify left bottom))
    )
    (fp_text user "Author: Antmicro" (at -1.6 5.3) (layer "F.Fab") hide
        (effects (font (size 0.7 0.7) (thickness 0.15)) (justify left bottom))
    )
    (fp_text user "${REFERENCE}" (at -1.6 4.1) (layer "F.Fab") hide
        (effects (font (size 0.7 0.7) (thickness 0.15)) (justify left bottom))
    )
    (fp_text user "License: Apache-2.0" (at -1.6 6.499) (layer "F.Fab") hide
        (effects (font (size 0.7 0.7) (thickness 0.15)) (justify left bottom))
    )
    (fp_line (start -1.5 -1.8) (end -1.5 -1.5)
      (stroke (width 0.12) (type solid)) (layer "F.SilkS"))
    (fp_line (start -1.5 1.5) (end -1.5 1.8)
      (stroke (width 0.12) (type solid)) (layer "F.SilkS"))
    (fp_line (start -1.5 1.8) (end 1.5 1.8)
      (stroke (width 0.12) (type solid)) (layer "F.SilkS"))
    (fp_line (start 1.5 -1.8) (end -1.5 -1.8)
      (stroke (width 0.12) (type solid)) (layer "F.SilkS"))
    (fp_line (start 1.5 -1.5) (end 1.5 -1.8)
      (stroke (width 0.12) (type solid)) (layer "F.SilkS"))
    (fp_line (start 1.5 1.8) (end 1.5 1.5)
      (stroke (width 0.12) (type solid)) (layer "F.SilkS"))
    (fp_circle (center -1.7 -1.9) (end -1.7 -1.85)
      (stroke (width 0.15) (type solid)) (fill solid) (layer "F.SilkS"))
    (fp_rect (start 1.6 -1.9) (end -1.6 1.9)
      (stroke (width 0.05) (type solid)) (fill none) (layer "F.CrtYd"))
    (fp_line (start -0.6 -1.6) (end -1.3 -0.9)
      (stroke (width 0.15) (type solid)) (layer "F.Fab"))
    (fp_rect (start 1.3 -1.601) (end -1.3 1.599)
      (stroke (width 0.15) (type solid)) (fill none) (layer "F.Fab"))
    (pad "1" smd rect (at -0.8 -1.199 270) (size 0.9 1.1) (layers "F.Cu" "F.Paste" "F.Mask")
      (net 185 "/Clock distribution/PS_CLK_EN") (pinfunction "EN") (pintype "input"))
    (pad "2" smd rect (at -0.8 0 270) (size 0.9 1.1) (layers "F.Cu" "F.Paste" "F.Mask")
      (net 796 "unconnected-(Y1-NC-Pad2)") (pinfunction "NC") (pintype "no_connect"))
    (pad "3" smd rect (at -0.8 1.199 270) (size 0.9 1.1) (layers "F.Cu" "F.Paste" "F.Mask")
      (net 1 "GND") (pinfunction "GND") (pintype "power_in"))
    (pad "4" smd rect (at 0.801 1.199 270) (size 0.9 1.1) (layers "F.Cu" "F.Paste" "F.Mask")
      (net 296 "/Clock distribution/CLK_100M_P") (pinfunction "OUT+") (pintype "output"))
    (pad "5" smd rect (at 0.801 0 270) (size 0.9 1.1) (layers "F.Cu" "F.Paste" "F.Mask")
      (net 297 "/Clock distribution/CLK_100M_N") (pinfunction "OUT-") (pintype "output"))
    (pad "6" smd rect (at 0.801 -1.199 270) (size 0.9 1.1) (layers "F.Cu" "F.Paste" "F.Mask")
      (net 15 "PS_3V3") (pinfunction "VCC") (pintype "power_in"))
  )

  (footprint "kria-k26-devboard-footprints:C_0402_1005Metric" (layer "F.Cu")
    (at 109.6 118.32 180)
    (descr "Capacitor SMD 0402")
    (tags "capacitor SMD 0402")
    (property "Author" "Antmicro")
    (property "Dielectric" "X5R")
    (property "License" "Apache-2.0")
    (property "MPN" "GRM155R61H104KE14D")
    (property "Manufacturer" "Murata")
    (property "Sheetfile" "clock.kicad_sch")
    (property "Sheetname" "Clock distribution")
    (property "Val" "100n")
    (property "Voltage" "50V")
    (property "ki_description" " ")
    (attr smd)
    (fp_text reference "C21" (at 1.13 0.88 180) (layer "F.SilkS")
        (effects (font (size 0.7 0.7) (thickness 0.15)) (justify left bottom))
    )
    (fp_text value "C_100n_0402" (at 0 1.4 180) (layer "F.Fab") hide
        (effects (font (size 0.7 0.7) (thickness 0.15)) (justify left bottom))
    )
    (fp_text user "Author: Antmicro" (at -0.932 4.17 180) (layer "F.Fab") hide
        (effects (font (size 0.7 0.7) (thickness 0.15)) (justify left bottom))
    )
    (fp_text user "${REFERENCE}" (at -0.932 3.168 180) (layer "F.Fab") hide
        (effects (font (size 0.7 0.7) (thickness 0.15)) (justify left bottom))
    )
    (fp_text user "License: Apache-2.0" (at -0.932 5.17 180) (layer "F.Fab") hide
        (effects (font (size 0.7 0.7) (thickness 0.15)) (justify left bottom))
    )
    (fp_rect (start -0.94 -0.47) (end 0.94 0.47)
      (stroke (width 0.05) (type solid)) (fill none) (layer "F.CrtYd"))
    (fp_rect (start -0.499 -0.249) (end 0.499 0.249)
      (stroke (width 0.15) (type solid)) (fill none) (layer "F.Fab"))
    (pad "1" smd roundrect (at -0.484 0 180) (size 0.59 0.64) (layers "F.Cu" "F.Paste" "F.Mask") (roundrect_rratio 0.25)
      (net 15 "PS_3V3") (pintype "passive"))
    (pad "2" smd roundrect (at 0.484 0 180) (size 0.59 0.64) (layers "F.Cu" "F.Paste" "F.Mask") (roundrect_rratio 0.25)
      (net 1 "GND") (pintype "passive"))
  )

  (footprint "kria-k26-devboard-footprints:C_0402_1005Metric" (layer "F.Cu")
    (at 116.9 118.8)
    (descr "Capacitor SMD 0402")
    (tags "capacitor SMD 0402")
    (property "Author" "Antmicro")
    (property "Dielectric" "X5R")
    (property "License" "Apache-2.0")
    (property "MPN" "GRM155R61H104KE14D")
    (property "Manufacturer" "Murata")
    (property "Sheetfile" "clock.kicad_sch")
    (property "Sheetname" "Clock distribution")
    (property "Val" "100n")
    (property "Voltage" "50V")
    (property "ki_description" " ")
    (attr smd)
    (fp_text reference "C26" (at -1.29 -0.57) (layer "F.SilkS")
        (effects (font (size 0.7 0.7) (thickness 0.15)) (justify left bottom))
    )
    (fp_text value "C_100n_0402" (at 0 1.4) (layer "F.Fab") hide
        (effects (font (size 0.7 0.7) (thickness 0.15)) (justify left bottom))
    )
    (fp_text user "License: Apache-2.0" (at -0.932 5.17) (layer "F.Fab") hide
        (effects (font (size 0.7 0.7) (thickness 0.15)) (justify left bottom))
    )
    (fp_text user "${REFERENCE}" (at -0.932 3.168) (layer "F.Fab") hide
        (effects (font (size 0.7 0.7) (thickness 0.15)) (justify left bottom))
    )
    (fp_text user "Author: Antmicro" (at -0.932 4.17) (layer "F.Fab") hide
        (effects (font (size 0.7 0.7) (thickness 0.15)) (justify left bottom))
    )
    (fp_rect (start -0.94 -0.47) (end 0.94 0.47)
      (stroke (width 0.05) (type solid)) (fill none) (layer "F.CrtYd"))
    (fp_rect (start -0.499 -0.249) (end 0.499 0.249)
      (stroke (width 0.15) (type solid)) (fill none) (layer "F.Fab"))
    (pad "1" smd roundrect (at -0.484 0) (size 0.59 0.64) (layers "F.Cu" "F.Paste" "F.Mask") (roundrect_rratio 0.25)
      (net 15 "PS_3V3") (pintype "passive"))
    (pad "2" smd roundrect (at 0.484 0) (size 0.59 0.64) (layers "F.Cu" "F.Paste" "F.Mask") (roundrect_rratio 0.25)
      (net 1 "GND") (pintype "passive"))
  )

  (footprint "kria-k26-devboard-footprints:C_0402_1005Metric" (layer "F.Cu")
    (at 112.61 123.05 -90)
    (descr "Capacitor SMD 0402")
    (tags "capacitor SMD 0402")
    (property "Author" "Antmicro")
    (property "Dielectric" "X5R")
    (property "License" "Apache-2.0")
    (property "MPN" "GRM155R61H104KE14D")
    (property "Manufacturer" "Murata")
    (property "Sheetfile" "clock.kicad_sch")
    (property "Sheetname" "Clock distribution")
    (property "Val" "100n")
    (property "Voltage" "50V")
    (property "ki_description" " ")
    (attr smd)
    (fp_text reference "C23" (at 3.01 -0.39 -90) (layer "F.SilkS")
        (effects (font (size 0.7 0.7) (thickness 0.15)) (justify left bottom))
    )
    (fp_text value "C_100n_0402" (at 0 1.4 -90) (layer "F.Fab") hide
        (effects (font (size 0.7 0.7) (thickness 0.15)) (justify left bottom))
    )
    (fp_text user "License: Apache-2.0" (at -0.932 5.17 -90) (layer "F.Fab") hide
        (effects (font (size 0.7 0.7) (thickness 0.15)) (justify left bottom))
    )
    (fp_text user "Author: Antmicro" (at -0.932 4.17 -90) (layer "F.Fab") hide
        (effects (font (size 0.7 0.7) (thickness 0.15)) (justify left bottom))
    )
    (fp_text user "${REFERENCE}" (at -0.932 3.168 -90) (layer "F.Fab") hide
        (effects (font (size 0.7 0.7) (thickness 0.15)) (justify left bottom))
    )
    (fp_rect (start -0.94 -0.47) (end 0.94 0.47)
      (stroke (width 0.05) (type solid)) (fill none) (layer "F.CrtYd"))
    (fp_rect (start -0.499 -0.249) (end 0.499 0.249)
      (stroke (width 0.15) (type solid)) (fill none) (layer "F.Fab"))
    (pad "1" smd roundrect (at -0.484 0 270) (size 0.59 0.64) (layers "F.Cu" "F.Paste" "F.Mask") (roundrect_rratio 0.25)
      (net 15 "PS_3V3") (pintype "passive"))
    (pad "2" smd roundrect (at 0.484 0 270) (size 0.59 0.64) (layers "F.Cu" "F.Paste" "F.Mask") (roundrect_rratio 0.25)
      (net 1 "GND") (pintype "passive"))
  )

  (footprint "kria-k26-devboard-footprints:C_0402_1005Metric" (layer "F.Cu")
    (at 116.9 123.55)
    (descr "Capacitor SMD 0402")
    (tags "capacitor SMD 0402")
    (property "Author" "Antmicro")
    (property "Dielectric" "X5R")
    (property "License" "Apache-2.0")
    (property "MPN" "GRM155R61H104KE14D")
    (property "Manufacturer" "Murata")
    (property "Sheetfile" "clock.kicad_sch")
    (property "Sheetname" "Clock distribution")
    (property "Val" "100n")
    (property "Voltage" "50V")
    (property "ki_description" " ")
    (attr smd)
    (fp_text reference "C24" (at -1 1.19) (layer "F.SilkS")
        (effects (font (size 0.7 0.7) (thickness 0.15)) (justify left bottom))
    )
    (fp_text value "C_100n_0402" (at 0 1.4) (layer "F.Fab") hide
        (effects (font (size 0.7 0.7) (thickness 0.15)) (justify left bottom))
    )
    (fp_text user "License: Apache-2.0" (at -0.932 5.17) (layer "F.Fab") hide
        (effects (font (size 0.7 0.7) (thickness 0.15)) (justify left bottom))
    )
    (fp_text user "Author: Antmicro" (at -0.932 4.17) (layer "F.Fab") hide
        (effects (font (size 0.7 0.7) (thickness 0.15)) (justify left bottom))
    )
    (fp_text user "${REFERENCE}" (at -0.932 3.168) (layer "F.Fab") hide
        (effects (font (size 0.7 0.7) (thickness 0.15)) (justify left bottom))
    )
    (fp_rect (start -0.94 -0.47) (end 0.94 0.47)
      (stroke (width 0.05) (type solid)) (fill none) (layer "F.CrtYd"))
    (fp_rect (start -0.499 -0.249) (end 0.499 0.249)
      (stroke (width 0.15) (type solid)) (fill none) (layer "F.Fab"))
    (pad "1" smd roundrect (at -0.484 0) (size 0.59 0.64) (layers "F.Cu" "F.Paste" "F.Mask") (roundrect_rratio 0.25)
      (net 15 "PS_3V3") (pintype "passive"))
    (pad "2" smd roundrect (at 0.484 0) (size 0.59 0.64) (layers "F.Cu" "F.Paste" "F.Mask") (roundrect_rratio 0.25)
      (net 1 "GND") (pintype "passive"))
  )

  (footprint "kria-k26-devboard-footprints:C_0402_1005Metric" (layer "F.Cu")
    (at 129.95 79.8)
    (descr "Capacitor SMD 0402")
    (tags "capacitor SMD 0402")
    (property "Author" "Antmicro")
    (property "Dielectric" "X5R")
    (property "License" "Apache-2.0")
    (property "MPN" "GRM155R61H104KE14D")
    (property "Manufacturer" "Murata")
    (property "Sheetfile" "usb.kicad_sch")
    (property "Sheetname" "USB")
    (property "Val" "100n")
    (property "Voltage" "50V")
    (property "ki_description" " ")
    (attr smd)
    (fp_text reference "C56" (at 0.84 0.37) (layer "F.SilkS")
        (effects (font (size 0.7 0.7) (thickness 0.15)) (justify left bottom))
    )
    (fp_text value "C_100n_0402" (at 0 1.4) (layer "F.Fab") hide
        (effects (font (size 0.7 0.7) (thickness 0.15)) (justify left bottom))
    )
    (fp_text user "License: Apache-2.0" (at -0.932 5.17) (layer "F.Fab") hide
        (effects (font (size 0.7 0.7) (thickness 0.15)) (justify left bottom))
    )
    (fp_text user "Author: Antmicro" (at -0.932 4.17) (layer "F.Fab") hide
        (effects (font (size 0.7 0.7) (thickness 0.15)) (justify left bottom))
    )
    (fp_text user "${REFERENCE}" (at -0.932 3.168) (layer "F.Fab") hide
        (effects (font (size 0.7 0.7) (thickness 0.15)) (justify left bottom))
    )
    (fp_rect (start -0.94 -0.47) (end 0.94 0.47)
      (stroke (width 0.05) (type solid)) (fill none) (layer "F.CrtYd"))
    (fp_rect (start -0.499 -0.249) (end 0.499 0.249)
      (stroke (width 0.15) (type solid)) (fill none) (layer "F.Fab"))
    (pad "1" smd roundrect (at -0.484 0) (size 0.59 0.64) (layers "F.Cu" "F.Paste" "F.Mask") (roundrect_rratio 0.25)
      (net 18 "PS_1V2") (pintype "passive"))
    (pad "2" smd roundrect (at 0.484 0) (size 0.59 0.64) (layers "F.Cu" "F.Paste" "F.Mask") (roundrect_rratio 0.25)
      (net 1 "GND") (pintype "passive"))
  )

  (footprint "kria-k26-devboard-footprints:C_0402_1005Metric" (layer "F.Cu")
    (at 130.975 75.11 -90)
    (descr "Capacitor SMD 0402")
    (tags "capacitor SMD 0402")
    (property "Author" "Antmicro")
    (property "Dielectric" "X5R")
    (property "License" "Apache-2.0")
    (property "MPN" "GRM155R61H104KE14D")
    (property "Manufacturer" "Murata")
    (property "Sheetfile" "usb.kicad_sch")
    (property "Sheetname" "USB")
    (property "Val" "100n")
    (property "Voltage" "50V")
    (property "ki_description" " ")
    (attr smd)
    (fp_text reference "C69" (at 3.07 -0.405 -90) (layer "F.SilkS")
        (effects (font (size 0.7 0.7) (thickness 0.15)) (justify left bottom))
    )
    (fp_text value "C_100n_0402" (at 0 1.4 -90) (layer "F.Fab") hide
        (effects (font (size 0.7 0.7) (thickness 0.15)) (justify left bottom))
    )
    (fp_text user "${REFERENCE}" (at -0.932 3.168 -90) (layer "F.Fab") hide
        (effects (font (size 0.7 0.7) (thickness 0.15)) (justify left bottom))
    )
    (fp_text user "Author: Antmicro" (at -0.932 4.17 -90) (layer "F.Fab") hide
        (effects (font (size 0.7 0.7) (thickness 0.15)) (justify left bottom))
    )
    (fp_text user "License: Apache-2.0" (at -0.932 5.17 -90) (layer "F.Fab") hide
        (effects (font (size 0.7 0.7) (thickness 0.15)) (justify left bottom))
    )
    (fp_rect (start -0.94 -0.47) (end 0.94 0.47)
      (stroke (width 0.05) (type solid)) (fill none) (layer "F.CrtYd"))
    (fp_rect (start -0.499 -0.249) (end 0.499 0.249)
      (stroke (width 0.15) (type solid)) (fill none) (layer "F.Fab"))
    (pad "1" smd roundrect (at -0.484 0 270) (size 0.59 0.64) (layers "F.Cu" "F.Paste" "F.Mask") (roundrect_rratio 0.25)
      (net 281 "/USB/USB2_TX_C_P") (pintype "passive"))
    (pad "2" smd roundrect (at 0.484 0 270) (size 0.59 0.64) (layers "F.Cu" "F.Paste" "F.Mask") (roundrect_rratio 0.25)
      (net 63 "/USB/USB2_TX_P") (pintype "passive"))
  )

  (footprint "kria-k26-devboard-footprints:QFN-24-1EP_4x4mm_P0.5mm_EP2.6x2.6mm" (layer "F.Cu")
    (at 121.149 98.729 -90)
    (descr "QFN, 24 Pin (http://ww1.microchip.com/downloads/en/PackagingSpec/00000049BQ.pdf#page=278), generated with kicad-footprint-generator ipc_noLead_generator.py")
    (tags "QFN NoLead")
    (property "Author" "Antmicro")
    (property "License" "Apache-2.0")
    (property "MPN" "USB3310C-CP")
    (property "Manufacturer" "Microchip Technology")
    (property "Sheetfile" "usb.kicad_sch")
    (property "Sheetname" "USB")
    (property "ki_description" "USB interface")
    (property "ki_keywords" "SMT, IC")
    (attr smd)
    (fp_text reference "U23" (at -2.619 2.839) (layer "F.SilkS")
        (effects (font (size 0.7 0.7) (thickness 0.15)) (justify left bottom))
    )
    (fp_text value "USB3310C-CP" (at 0 3.4 -90) (layer "F.Fab") hide
        (effects (font (size 0.7 0.7) (thickness 0.15)) (justify left bottom))
    )
    (fp_text user "License: Apache-2.0" (at -2.503 6.6 -90) (layer "F.Fab") hide
        (effects (font (size 0.7 0.7) (thickness 0.15)) (justify left bottom))
    )
    (fp_text user "Author: Antmicro" (at -2.503 7.8 -90) (layer "F.Fab") hide
        (effects (font (size 0.7 0.7) (thickness 0.15)) (justify left bottom))
    )
    (fp_text user "${REFERENCE}" (at -2.503 5.4 -90) (layer "F.Fab") hide
        (effects (font (size 0.7 0.7) (thickness 0.15)) (justify left bottom))
    )
    (fp_line (start -2.11 -1.636) (end -2.11 -2.11)
      (stroke (width 0.15) (type solid)) (layer "F.SilkS"))
    (fp_line (start -2.11 2.108) (end -2.11 1.634)
      (stroke (width 0.15) (type solid)) (layer "F.SilkS"))
    (fp_line (start -1.635 -2.11) (end -2.11 -2.11)
      (stroke (width 0.15) (type solid)) (layer "F.SilkS"))
    (fp_line (start -1.635 2.108) (end -2.11 2.108)
      (stroke (width 0.15) (type solid)) (layer "F.SilkS"))
    (fp_line (start 1.634 -2.11) (end 2.108 -2.11)
      (stroke (width 0.15) (type solid)) (layer "F.SilkS"))
    (fp_line (start 1.634 2.108) (end 2.108 2.108)
      (stroke (width 0.15) (type solid)) (layer "F.SilkS"))
    (fp_line (start 2.108 -2.11) (end 2.108 -1.635)
      (stroke (width 0.15) (type solid)) (layer "F.SilkS"))
    (fp_line (start 2.108 2.108) (end 2.108 1.634)
      (stroke (width 0.15) (type solid)) (layer "F.SilkS"))
    (fp_circle (center -2.3 -2.3) (end -2.25 -2.3)
      (stroke (width 0.15) (type solid)) (fill solid) (layer "F.SilkS"))
    (fp_rect (start -2.503 -2.503) (end 2.5 2.5)
      (stroke (width 0.05) (type solid)) (fill none) (layer "F.CrtYd"))
    (fp_line (start -2 -1) (end -1 -2)
      (stroke (width 0.15) (type solid)) (layer "F.Fab"))
    (fp_line (start -2 1.999) (end -2 -1)
      (stroke (width 0.15) (type solid)) (layer "F.Fab"))
    (fp_line (start -1 -2) (end 1.999 -2)
      (stroke (width 0.15) (type solid)) (layer "F.Fab"))
    (fp_line (start 1.999 -2) (end 1.999 1.999)
      (stroke (width 0.15) (type solid)) (layer "F.Fab"))
    (fp_line (start 1.999 1.999) (end -2 1.999)
      (stroke (width 0.15) (type solid)) (layer "F.Fab"))
    (pad "" smd roundrect (at -0.652 -0.652 270) (size 1.05 1.05) (layers "F.Paste") (roundrect_rratio 0.238095))
    (pad "" smd roundrect (at -0.652 0.65 270) (size 1.05 1.05) (layers "F.Paste") (roundrect_rratio 0.238095))
    (pad "" smd roundrect (at 0.65 -0.652 270) (size 1.05 1.05) (layers "F.Paste") (roundrect_rratio 0.238095))
    (pad "" smd roundrect (at 0.65 0.65 270) (size 1.05 1.05) (layers "F.Paste") (roundrect_rratio 0.238095))
    (pad "1" smd roundrect (at -1.938 -1.25 270) (size 0.825 0.25) (layers "F.Cu" "F.Paste" "F.Mask") (roundrect_rratio 0.25)
      (net 1 "GND") (pinfunction "ID") (pintype "input"))
    (pad "2" smd roundrect (at -1.938 -0.75 270) (size 0.825 0.25) (layers "F.Cu" "F.Paste" "F.Mask") (roundrect_rratio 0.25)
      (net 669 "Net-(U23-VBUS)") (pinfunction "VBUS") (pintype "bidirectional"))
    (pad "3" smd roundrect (at -1.938 -0.25 270) (size 0.825 0.25) (layers "F.Cu" "F.Paste" "F.Mask") (roundrect_rratio 0.25)
      (net 8 "SOM_5V0") (pinfunction "VBAT") (pintype "power_in"))
    (pad "4" smd roundrect (at -1.938 0.248 270) (size 0.825 0.25) (layers "F.Cu" "F.Paste" "F.Mask") (roundrect_rratio 0.25)
      (net 154 "Net-(U23-VDD_3V3)") (pinfunction "VDD_3V3") (pintype "power_in"))
    (pad "5" smd roundrect (at -1.938 0.748 270) (size 0.825 0.25) (layers "F.Cu" "F.Paste" "F.Mask") (roundrect_rratio 0.25)
      (net 54 "/USB/USB2_PHY_N") (pinfunction "DM") (pintype "bidirectional"))
    (pad "6" smd roundrect (at -1.938 1.249 270) (size 0.825 0.25) (layers "F.Cu" "F.Paste" "F.Mask") (roundrect_rratio 0.25)
      (net 55 "/USB/USB2_PHY_P") (pinfunction "DP") (pintype "bidirectional"))
    (pad "7" smd roundrect (at -1.25 1.937 270) (size 0.25 0.825) (layers "F.Cu" "F.Paste" "F.Mask") (roundrect_rratio 0.25)
      (net 39 "/USB/MIO63") (pinfunction "DATA7") (pintype "bidirectional"))
    (pad "8" smd roundrect (at -0.75 1.937 270) (size 0.25 0.825) (layers "F.Cu" "F.Paste" "F.Mask") (roundrect_rratio 0.25)
      (net 38 "/USB/MIO62") (pinfunction "DATA6") (pintype "bidirectional"))
    (pad "9" smd roundrect (at -0.25 1.937 270) (size 0.25 0.825) (layers "F.Cu" "F.Paste" "F.Mask") (roundrect_rratio 0.25)
      (net 37 "/USB/MIO61") (pinfunction "DATA5") (pintype "bidirectional"))
    (pad "10" smd roundrect (at 0.248 1.937 270) (size 0.25 0.825) (layers "F.Cu" "F.Paste" "F.Mask") (roundrect_rratio 0.25)
      (net 42 "/USB/MIO60") (pinfunction "DATA4") (pintype "bidirectional"))
    (pad "11" smd roundrect (at 0.748 1.937 270) (size 0.25 0.825) (layers "F.Cu" "F.Paste" "F.Mask") (roundrect_rratio 0.25)
      (net 46 "/USB/MIO52") (pinfunction "CLKOUT") (pintype "output"))
    (pad "12" smd roundrect (at 1.249 1.937 270) (size 0.25 0.825) (layers "F.Cu" "F.Paste" "F.Mask") (roundrect_rratio 0.25)
      (net 41 "/USB/MIO59") (pinfunction "DATA3") (pintype "bidirectional"))
    (pad "13" smd roundrect (at 1.937 1.249 270) (size 0.825 0.25) (layers "F.Cu" "F.Paste" "F.Mask") (roundrect_rratio 0.25)
      (net 48 "/USB/MIO54") (pinfunction "DATA2") (pintype "bidirectional"))
    (pad "14" smd roundrect (at 1.937 0.748 270) (size 0.825 0.25) (layers "F.Cu" "F.Paste" "F.Mask") (roundrect_rratio 0.25)
      (net 17 "PS_1V8") (pinfunction "REFSEL1") (pintype "input"))
    (pad "15" smd roundrect (at 1.937 0.248 270) (size 0.825 0.25) (layers "F.Cu" "F.Paste" "F.Mask") (roundrect_rratio 0.25)
      (net 17 "PS_1V8") (pinfunction "REFSEL0") (pintype "input"))
    (pad "16" smd roundrect (at 1.937 -0.25 270) (size 0.825 0.25) (layers "F.Cu" "F.Paste" "F.Mask") (roundrect_rratio 0.25)
      (net 45 "/USB/MIO57") (pinfunction "DATA1") (pintype "bidirectional"))
    (pad "17" smd roundrect (at 1.937 -0.75 270) (size 0.825 0.25) (layers "F.Cu" "F.Paste" "F.Mask") (roundrect_rratio 0.25)
      (net 44 "/USB/MIO56") (pinfunction "DATA0") (pintype "bidirectional"))
    (pad "18" smd roundrect (at 1.937 -1.25 270) (size 0.825 0.25) (layers "F.Cu" "F.Paste" "F.Mask") (roundrect_rratio 0.25)
      (net 43 "/USB/MIO55") (pinfunction "NXT") (pintype "output"))
    (pad "19" smd roundrect (at 1.249 -1.938 270) (size 0.25 0.825) (layers "F.Cu" "F.Paste" "F.Mask") (roundrect_rratio 0.25)
      (net 47 "/USB/MIO53") (pinfunction "DIR") (pintype "output"))
    (pad "20" smd roundrect (at 0.748 -1.938 270) (size 0.25 0.825) (layers "F.Cu" "F.Paste" "F.Mask") (roundrect_rratio 0.25)
      (net 40 "/USB/MIO58") (pinfunction "STP") (pintype "input"))
    (pad "21" smd roundrect (at 0.248 -1.938 270) (size 0.25 0.825) (layers "F.Cu" "F.Paste" "F.Mask") (roundrect_rratio 0.25)
      (net 17 "PS_1V8") (pinfunction "VDD_1V8") (pintype "power_in"))
    (pad "22" smd roundrect (at -0.25 -1.938 270) (size 0.25 0.825) (layers "F.Cu" "F.Paste" "F.Mask") (roundrect_rratio 0.25)
      (net 178 "/Reset logic/~{USB_PHY_RESET}") (pinfunction "RESETB") (pintype "input"))
    (pad "23" smd roundrect (at -0.75 -1.938 270) (size 0.25 0.825) (layers "F.Cu" "F.Paste" "F.Mask") (roundrect_rratio 0.25)
      (net 277 "/USB/USB2_REFCLK") (pinfunction "REFCLK") (pintype "input"))
    (pad "24" smd roundrect (at -1.25 -1.938 270) (size 0.25 0.825) (layers "F.Cu" "F.Paste" "F.Mask") (roundrect_rratio 0.25)
      (net 668 "Net-(U23-RBIAS)") (pinfunction "RBIAS") (pintype "passive"))
    (pad "25" smd rect (at 0 0 270) (size 2.6 2.6) (layers "F.Cu" "F.Mask")
      (net 1 "GND") (pinfunction "GND") (pintype "power_in"))
  )

  (footprint "kria-k26-devboard-footprints:R_0402_1005Metric" (layer "F.Cu")
    (at 142.27 142.56 180)
    (descr "Resistor SMD 0402")
    (tags "resistor SMD 0402")
    (property "Author" "Antmicro")
    (property "License" "Apache-2.0")
    (property "MPN" "CR0402-FX-5111GLF")
    (property "Manufacturer" "Bourns")
    (property "Sheetfile" "debug.kicad_sch")
    (property "Sheetname" "Debug and JTAG")
    (property "Tolerance" "1%")
    (property "Val" "5k11")
    (property "ki_description" "5k11 resistor in 0402 package with 1% tolerance")
    (attr smd)
    (fp_text reference "R99" (at 1.18 0.59 180) (layer "F.SilkS")
        (effects (font (size 0.7 0.7) (thickness 0.15)) (justify left bottom))
    )
    (fp_text value "R_5k11_0402" (at 0 1.4 180) (layer "F.Fab") hide
        (effects (font (size 0.7 0.7) (thickness 0.15)) (justify left bottom))
    )
    (fp_text user "Author: Antmicro" (at -0.95 4.169 180) (layer "F.Fab") hide
        (effects (font (size 0.7 0.7) (thickness 0.15)) (justify left bottom))
    )
    (fp_text user "${REFERENCE}" (at -0.95 3.168 180) (layer "F.Fab") hide
        (effects (font (size 0.7 0.7) (thickness 0.15)) (justify left bottom))
    )
    (fp_text user "License: Apache-2.0" (at -0.95 5.169 180) (layer "F.Fab") hide
        (effects (font (size 0.7 0.7) (thickness 0.15)) (justify left bottom))
    )
    (fp_rect (start -0.93 -0.47) (end 0.93 0.47)
      (stroke (width 0.05) (type solid)) (fill none) (layer "F.CrtYd"))
    (fp_rect (start -0.5 -0.25) (end 0.5 0.25)
      (stroke (width 0.15) (type solid)) (fill none) (layer "F.Fab"))
    (pad "1" smd roundrect (at -0.485 0 180) (size 0.59 0.64) (layers "F.Cu" "F.Paste" "F.Mask") (roundrect_rratio 0.25)
      (net 354 "Net-(J8-CC_{1})") (pintype "passive"))
    (pad "2" smd roundrect (at 0.485 0 180) (size 0.59 0.64) (layers "F.Cu" "F.Paste" "F.Mask") (roundrect_rratio 0.25)
      (net 1 "GND") (pintype "passive"))
  )

  (footprint "kria-k26-devboard-footprints:C_0402_1005Metric" (layer "F.Cu")
    (at 130.025 75.11 -90)
    (descr "Capacitor SMD 0402")
    (tags "capacitor SMD 0402")
    (property "Author" "Antmicro")
    (property "Dielectric" "X5R")
    (property "License" "Apache-2.0")
    (property "MPN" "GRM155R61H104KE14D")
    (property "Manufacturer" "Murata")
    (property "Sheetfile" "usb.kicad_sch")
    (property "Sheetname" "USB")
    (property "Val" "100n")
    (property "Voltage" "50V")
    (property "ki_description" " ")
    (attr smd)
    (fp_text reference "C68" (at 3.07 -0.405 -90) (layer "F.SilkS")
        (effects (font (size 0.7 0.7) (thickness 0.15)) (justify left bottom))
    )
    (fp_text value "C_100n_0402" (at 0 1.4 -90) (layer "F.Fab") hide
        (effects (font (size 0.7 0.7) (thickness 0.15)) (justify left bottom))
    )
    (fp_text user "Author: Antmicro" (at -0.932 4.17 -90) (layer "F.Fab") hide
        (effects (font (size 0.7 0.7) (thickness 0.15)) (justify left bottom))
    )
    (fp_text user "${REFERENCE}" (at -0.932 3.168 -90) (layer "F.Fab") hide
        (effects (font (size 0.7 0.7) (thickness 0.15)) (justify left bottom))
    )
    (fp_text user "License: Apache-2.0" (at -0.932 5.17 -90) (layer "F.Fab") hide
        (effects (font (size 0.7 0.7) (thickness 0.15)) (justify left bottom))
    )
    (fp_rect (start -0.94 -0.47) (end 0.94 0.47)
      (stroke (width 0.05) (type solid)) (fill none) (layer "F.CrtYd"))
    (fp_rect (start -0.499 -0.249) (end 0.499 0.249)
      (stroke (width 0.15) (type solid)) (fill none) (layer "F.Fab"))
    (pad "1" smd roundrect (at -0.484 0 270) (size 0.59 0.64) (layers "F.Cu" "F.Paste" "F.Mask") (roundrect_rratio 0.25)
      (net 280 "/USB/USB2_TX_C_N") (pintype "passive"))
    (pad "2" smd roundrect (at 0.484 0 270) (size 0.59 0.64) (layers "F.Cu" "F.Paste" "F.Mask") (roundrect_rratio 0.25)
      (net 62 "/USB/USB2_TX_N") (pintype "passive"))
  )

  (footprint "kria-k26-devboard-footprints:LED_0603_1608Metric_G" (layer "F.Cu")
    (at 143.2 83.149999 90)
    (descr "LED SMD 0603 Green")
    (tags "LED SMD 0603 Green")
    (property "Author" "Antmicro")
    (property "Color" "Green")
    (property "License" "Apache-2.0")
    (property "MPN" "LG L29K-G2J1-24-Z")
    (property "Manufacturer" "OSRAM")
    (property "Sheetfile" "dc-dc-conventers.kicad_sch")
    (property "Sheetname" "DC/DC conventers")
    (property "ki_description" "LED, Green, SMT, 0603, 20 mA, 2.1 V, 570 nm")
    (property "ki_keywords" "0603, SMT, DIODE, SEMICONDUCTOR, UNICOLOR")
    (attr smd)
    (fp_text reference "D15" (at 1.559999 0.26 90) (layer "F.SilkS")
        (effects (font (size 0.7 0.7) (thickness 0.15)) (justify left bottom))
    )
    (fp_text value "LED_G_0603_LG_L29K-G2J1-24-Z" (at 0 1.6 90) (layer "F.Fab") hide
        (effects (font (size 0.7 0.7) (thickness 0.15)) (justify left bottom))
    )
    (fp_text user "License: Apache-2.0" (at -1.31 5.769 90) (layer "F.Fab") hide
        (effects (font (size 0.7 0.7) (thickness 0.15)) (justify left bottom))
    )
    (fp_text user "Author: Antmicro" (at -1.31 4.769 90) (layer "F.Fab") hide
        (effects (font (size 0.7 0.7) (thickness 0.15)) (justify left bottom))
    )
    (fp_text user "${REFERENCE}" (at -1.31 3.769 90) (layer "F.Fab") hide
        (effects (font (size 0.7 0.7) (thickness 0.15)) (justify left bottom))
    )
    (fp_line (start -0.27 -0.35) (end 0.27 -0.35)
      (stroke (width 0.15) (type solid)) (layer "F.SilkS"))
    (fp_line (start -0.27 0.351) (end 0.27 0.351)
      (stroke (width 0.15) (type solid)) (layer "F.SilkS"))
    (fp_line (start -0.106328 -0.200008) (end -0.106328 0.199992)
      (stroke (width 0.1) (type solid)) (layer "F.SilkS"))
    (fp_line (start -0.106328 -0.200008) (end 0.093672 -0.000008)
      (stroke (width 0.1) (type solid)) (layer "F.SilkS"))
    (fp_line (start -0.106328 -0.000008) (end -0.29 0)
      (stroke (width 0.1) (type solid)) (layer "F.SilkS"))
    (fp_line (start 0.093672 -0.200008) (end 0.093672 0.199992)
      (stroke (width 0.1) (type solid)) (layer "F.SilkS"))
    (fp_line (start 0.093672 -0.000008) (end -0.106328 0.199992)
      (stroke (width 0.1) (type solid)) (layer "F.SilkS"))
    (fp_line (start 0.093672 -0.000008) (end 0.293672 -0.000008)
      (stroke (width 0.1) (type solid)) (layer "F.SilkS"))
    (fp_line (start 1.25 0.32) (end 1.25 -0.32)
      (stroke (width 0.15) (type solid)) (layer "F.SilkS"))
    (fp_rect (start 1.26 0.65) (end -1.26 -0.65)
      (stroke (width 0.05) (type solid)) (fill none) (layer "F.CrtYd"))
    (fp_line (start -0.599 0) (end -0.201 0)
      (stroke (width 0.15) (type solid)) (layer "F.Fab"))
    (fp_line (start -0.201 -0.2) (end -0.201 0)
      (stroke (width 0.15) (type solid)) (layer "F.Fab"))
    (fp_line (start -0.201 0) (end -0.201 0.202)
      (stroke (width 0.15) (type solid)) (layer "F.Fab"))
    (fp_line (start -0.201 0.202) (end 0.101 0)
      (stroke (width 0.15) (type solid)) (layer "F.Fab"))
    (fp_line (start 0.101 0) (end -0.201 -0.2)
      (stroke (width 0.15) (type solid)) (layer "F.Fab"))
    (fp_line (start 0.199 -0.2) (end 0.199 -0.1)
      (stroke (width 0.15) (type solid)) (layer "F.Fab"))
    (fp_line (start 0.199 0) (end 0.597 0)
      (stroke (width 0.15) (type solid)) (layer "F.Fab"))
    (fp_line (start 0.199 0.202) (end 0.199 -0.1)
      (stroke (width 0.15) (type solid)) (layer "F.Fab"))
    (fp_rect (start -0.848 -0.4) (end 0.85 0.402)
      (stroke (width 0.15) (type solid)) (fill none) (layer "F.Fab"))
    (pad "1" smd rect (at -0.75 0 270) (size 0.8 0.8) (layers "F.Cu" "F.Paste" "F.Mask")
      (net 240 "Net-(D15-Pad1)") (pintype "passive"))
    (pad "2" smd rect (at 0.75 0 270) (size 0.8 0.8) (layers "F.Cu" "F.Paste" "F.Mask")
      (net 1 "GND") (pinfunction "2") (pintype "passive"))
  )

  (footprint "kria-k26-devboard-footprints:DFN1210-6" (layer "F.Cu")
    (at 92.1 68.5 -90)
    (property "Author" "Antmicro")
    (property "License" "Apache-2.0")
    (property "MPN" "824012823")
    (property "Manufacturer" "Würth Elektronik")
    (property "Sheetfile" "dp.kicad_sch")
    (property "Sheetname" "Display Port")
    (property "ki_description" "Low Capacitance TVS Diode Array, 2 Channels, DFN1210-6L")
    (property "ki_keywords" "ESD Protection TVS USB 3.1 Gen1&2 (5Gb/s, 10Gb/s), USB 3.1 Type C, Display Port (1.1, 1.2, 1.3, 1.4), HDMI 2.0")
    (attr smd)
    (fp_text reference "U4" (at 1.25 0.78) (layer "F.SilkS")
        (effects (font (size 0.697684 0.697684) (thickness 0.15)) (justify left))
    )
    (fp_text value "824012823" (at 6.127 1.4 -90) (layer "F.Fab")
        (effects (font (size 0.7 0.7) (thickness 0.15)) (justify left bottom))
    )
    (fp_text user "License: Apache-2.0" (at -1.01 5.4 -90) (layer "F.Fab") hide
        (effects (font (size 0.7 0.7) (thickness 0.15)) (justify left bottom))
    )
    (fp_text user "Author: Antmicro" (at -1.01 4.4 -90) (layer "F.Fab") hide
        (effects (font (size 0.7 0.7) (thickness 0.15)) (justify left bottom))
    )
    (fp_text user "${REFERENCE}" (at -1.01 3.399 -90) (layer "F.Fab") hide
        (effects (font (size 0.7 0.7) (thickness 0.15)) (justify left bottom))
    )
    (fp_line (start -0.532 -0.63) (end 0.53 -0.63)
      (stroke (width 0.15) (type solid)) (layer "F.SilkS"))
    (fp_line (start -0.532 0.628) (end 0.53 0.628)
      (stroke (width 0.15) (type solid)) (layer "F.SilkS"))
    (fp_circle (center -1.31 -0.36) (end -1.25 -0.31)
      (stroke (width 0.15) (type solid)) (fill solid) (layer "F.SilkS"))
    (fp_rect (start -0.75 -0.85) (end 0.748 0.848)
      (stroke (width 0.05) (type solid)) (fill none) (layer "F.CrtYd"))
    (fp_line (start -0.532 -0.532) (end 0.53 -0.532)
      (stroke (width 0.15) (type solid)) (layer "F.Fab"))
    (fp_line (start -0.532 0.53) (end -0.532 -0.532)
      (stroke (width 0.15) (type solid)) (layer "F.Fab"))
    (fp_line (start 0.53 -0.532) (end 0.53 0.53)
      (stroke (width 0.15) (type solid)) (layer "F.Fab"))
    (fp_line (start 0.53 0.53) (end -0.532 0.53)
      (stroke (width 0.15) (type solid)) (layer "F.Fab"))
    (pad "1" smd roundrect (at -0.277 -0.351 270) (size 0.4 0.2) (layers "F.Cu" "F.Paste" "F.Mask") (roundrect_rratio 0.25)
      (net 363 "/Display Port/DP_AUX_C_TVS_N") (pintype "passive"))
    (pad "2" smd roundrect (at -0.277 0 270) (size 0.4 0.2) (layers "F.Cu" "F.Paste" "F.Mask") (roundrect_rratio 0.25)
      (net 362 "/Display Port/DP_AUX_C_TVS_P") (pintype "passive"))
    (pad "3" smd roundrect (at -0.277 0.349 270) (size 0.4 0.2) (layers "F.Cu" "F.Paste" "F.Mask") (roundrect_rratio 0.25)
      (net 1 "GND") (pintype "passive"))
    (pad "4" smd roundrect (at 0.275 0.349 270) (size 0.4 0.2) (layers "F.Cu" "F.Paste" "F.Mask") (roundrect_rratio 0.25)
      (net 1 "GND") (pintype "passive"))
    (pad "5" smd roundrect (at 0.275 0 270) (size 0.4 0.2) (layers "F.Cu" "F.Paste" "F.Mask") (roundrect_rratio 0.25)
      (net 97 "/Display Port/DP_AUX_C_P") (pintype "passive"))
    (pad "6" smd roundrect (at 0.275 -0.351 270) (size 0.4 0.2) (layers "F.Cu" "F.Paste" "F.Mask") (roundrect_rratio 0.25)
      (net 99 "/Display Port/DP_AUX_C_N") (pintype "passive"))
  )

  (footprint "kria-k26-devboard-footprints:MicroSD_Amphenol_1140084168" (layer "F.Cu")
    (at 130.9 145.3)
    (property "Author" "Antmicro")
    (property "License" "Apache-2.0")
    (property "MPN" "1140084168")
    (property "Manufacturer" "Amphenol")
    (property "Sheetfile" "sd-3-card.kicad_sch")
    (property "Sheetname" "SD 3.0 card")
    (property "ki_description" "Memory Card Connector, MicroSD, Push-Pull, 8 Contacts, Copper Alloy, Gold Plated Contacts")
    (property "ki_keywords" "HORIZONTAL, SMT, MEMORY, CONNECTOR, MICRO")
    (attr smd)
    (fp_text reference "J2" (at -6.26 -5) (layer "F.SilkS")
        (effects (font (size 0.7 0.7) (thickness 0.15)) (justify left bottom))
    )
    (fp_text value "MicroSD_1140084168" (at -6.9 11.4) (layer "F.Fab") hide
        (effects (font (size 0.7 0.7) (thickness 0.15)) (justify left bottom))
    )
    (fp_text user "Author: Antmicro" (at -6.925 14.1) (layer "F.Fab") hide
        (effects (font (size 0.7 0.7) (thickness 0.15)) (justify left bottom))
    )
    (fp_text user "${REFERENCE}" (at -6.925 12.774) (layer "F.Fab") hide
        (effects (font (size 0.7 0.7) (thickness 0.15)) (justify left bottom))
    )
    (fp_text user "License: Apache-2.0" (at -6.925 15.4) (layer "F.Fab") hide
        (effects (font (size 0.7 0.7) (thickness 0.15)) (justify left bottom))
    )
    (fp_line (start -6.3 -6.1) (end -6.3 -4.7)
      (stroke (width 0.15) (type solid)) (layer "F.SilkS"))
    (fp_line (start -6.3 -1.6) (end -6.3 4.2)
      (stroke (width 0.15) (type solid)) (layer "F.SilkS"))
    (fp_line (start 4.8 -6.1) (end -6.3 -6.1)
      (stroke (width 0.15) (type solid)) (layer "F.SilkS"))
    (fp_line (start 6.2 -6.1) (end 6.1 -6.1)
      (stroke (width 0.15) (type solid)) (layer "F.SilkS"))
    (fp_line (start 6.2 -4) (end 6.2 -6.1)
      (stroke (width 0.15) (type solid)) (layer "F.SilkS"))
    (fp_line (start 6.2 4.2) (end 6.2 -2.2)
      (stroke (width 0.15) (type solid)) (layer "F.SilkS"))
    (fp_rect (start -6.5 -6.3) (end 6.4 6.2)
      (stroke (width 0.05) (type solid)) (fill none) (layer "F.CrtYd"))
    (fp_line (start -5.6 5.8) (end -5.6 9.5)
      (stroke (width 0.12) (type solid)) (layer "F.Fab"))
    (fp_line (start -5.1 8.8) (end -5.6 8.9)
      (stroke (width 0.12) (type solid)) (layer "F.Fab"))
    (fp_line (start -5.1 9.1) (end -5.6 9.2)
      (stroke (width 0.12) (type solid)) (layer "F.Fab"))
    (fp_line (start -3.8 8.5) (end -5.1 8.8)
      (stroke (width 0.12) (type solid)) (layer "F.Fab"))
    (fp_line (start -3.8 8.8) (end -5.1 9.1)
      (stroke (width 0.12) (type solid)) (layer "F.Fab"))
    (fp_line (start -2.3 8.3) (end -3.8 8.5)
      (stroke (width 0.12) (type solid)) (layer "F.Fab"))
    (fp_line (start -2.3 8.6) (end -3.8 8.8)
      (stroke (width 0.12) (type solid)) (layer "F.Fab"))
    (fp_line (start -1 8.2) (end -2.3 8.3)
      (stroke (width 0.12) (type solid)) (layer "F.Fab"))
    (fp_line (start -1 8.5) (end -2.3 8.6)
      (stroke (width 0.12) (type solid)) (layer "F.Fab"))
    (fp_line (start 0.8 8.2) (end -1 8.2)
      (stroke (width 0.12) (type solid)) (layer "F.Fab"))
    (fp_line (start 0.8 8.5) (end -1 8.5)
      (stroke (width 0.12) (type solid)) (layer "F.Fab"))
    (fp_line (start 2.1 8.3) (end 0.8 8.2)
      (stroke (width 0.12) (type solid)) (layer "F.Fab"))
    (fp_line (start 2.1 8.6) (end 0.8 8.5)
      (stroke (width 0.12) (type solid)) (layer "F.Fab"))
    (fp_line (start 2.9 8.4) (end 2.1 8.3)
      (stroke (width 0.12) (type solid)) (layer "F.Fab"))
    (fp_line (start 2.9 8.7) (end 2.1 8.6)
      (stroke (width 0.12) (type solid)) (layer "F.Fab"))
    (fp_line (start 4.6 8.7) (end 2.9 8.4)
      (stroke (width 0.12) (type solid)) (layer "F.Fab"))
    (fp_line (start 4.6 9) (end 2.9 8.7)
      (stroke (width 0.12) (type solid)) (layer "F.Fab"))
    (fp_line (start 4.9 10) (end -5.1 10)
      (stroke (width 0.12) (type solid)) (layer "F.Fab"))
    (fp_line (start 5.4 8.9) (end 4.6 8.7)
      (stroke (width 0.12) (type solid)) (layer "F.Fab"))
    (fp_line (start 5.4 9.2) (end 4.6 9)
      (stroke (width 0.12) (type solid)) (layer "F.Fab"))
    (fp_line (start 5.4 9.5) (end 5.4 5.8)
      (stroke (width 0.12) (type solid)) (layer "F.Fab"))
    (fp_rect (start -6 -5.8) (end 5.999 5.799)
      (stroke (width 0.1) (type solid)) (fill none) (layer "F.Fab"))
    (fp_arc (start -5.1 10) (mid -5.453553 9.853553) (end -5.6 9.5)
      (stroke (width 0.12) (type solid)) (layer "F.Fab"))
    (fp_arc (start 5.4 9.5) (mid 5.253553 9.853553) (end 4.9 10)
      (stroke (width 0.12) (type solid)) (layer "F.Fab"))
    (pad "1" smd rect (at 3.124 5.254 180) (size 0.7 1.75) (layers "F.Cu" "F.Paste" "F.Mask")
      (net 264 "/SD 3.0 card/SD_DAT2") (pinfunction "DAT2") (pintype "bidirectional"))
    (pad "2" smd rect (at 2.024 5.254 180) (size 0.7 1.75) (layers "F.Cu" "F.Paste" "F.Mask")
      (net 263 "/SD 3.0 card/SD_DAT3") (pinfunction "CD/DAT3") (pintype "bidirectional"))
    (pad "3" smd rect (at 0.925 5.254 180) (size 0.7 1.75) (layers "F.Cu" "F.Paste" "F.Mask")
      (net 262 "/SD 3.0 card/SD_CMD") (pinfunction "CMD") (pintype "bidirectional"))
    (pad "4" smd rect (at -0.176 5.254 180) (size 0.7 1.75) (layers "F.Cu" "F.Paste" "F.Mask")
      (net 317 "/SD 3.0 card/SD_VDD") (pinfunction "VDD") (pintype "power_in"))
    (pad "5" smd rect (at -1.276 5.254 180) (size 0.7 1.75) (layers "F.Cu" "F.Paste" "F.Mask")
      (net 261 "/SD 3.0 card/SD_CLK") (pinfunction "CLK") (pintype "output"))
    (pad "6" smd rect (at -2.375 5.254 180) (size 0.7 1.75) (layers "F.Cu" "F.Paste" "F.Mask")
      (net 1 "GND") (pinfunction "VSS") (pintype "power_in"))
    (pad "7" smd rect (at -3.476 5.254 180) (size 0.7 1.75) (layers "F.Cu" "F.Paste" "F.Mask")
      (net 260 "/SD 3.0 card/SD_DAT0") (pinfunction "DAT0") (pintype "bidirectional"))
    (pad "8" smd rect (at -4.576 5.254 180) (size 0.7 1.75) (layers "F.Cu" "F.Paste" "F.Mask")
      (net 259 "/SD 3.0 card/SD_DAT1") (pinfunction "DAT1") (pintype "bidirectional"))
    (pad "9" smd rect (at -5.675 -4.05) (size 1.4 1) (layers "F.Cu" "F.Paste" "F.Mask")
      (net 106 "/SD 3.0 card/MIO45") (pinfunction "CD1") (pintype "passive"))
    (pad "10" smd rect (at 5.424 -5.531 90) (size 1.4 1) (layers "F.Cu" "F.Paste" "F.Mask")
      (net 1 "GND") (pinfunction "CD2") (pintype "passive"))
    (pad "SH" smd rect (at -5.976 -2.48 90) (size 1.5 0.8) (layers "F.Cu" "F.Paste" "F.Mask")
      (net 1 "GND") (pinfunction "Shell") (pintype "passive"))
    (pad "SH" smd rect (at -5.776 5.129) (size 1.3 1.5) (layers "F.Cu" "F.Paste" "F.Mask")
      (net 1 "GND") (pinfunction "Shell") (pintype "passive"))
    (pad "SH" smd rect (at 5.575 5.129) (size 1.5 1.5) (layers "F.Cu" "F.Paste" "F.Mask")
      (net 1 "GND") (pinfunction "Shell") (pintype "passive"))
    (pad "SH" smd rect (at 5.874 -3.13 90) (size 1.5 0.8) (layers "F.Cu" "F.Paste" "F.Mask")
      (net 1 "GND") (pinfunction "Shell") (pintype "passive"))
  )

  (footprint "kria-k26-devboard-footprints:SOT-563" (layer "F.Cu")
    (at 144.49 61.9 90)
    (property "Author" "Antmicro")
    (property "License" "Apache-2.0")
    (property "MPN" "82400152")
    (property "Manufacturer" "Würth Elektronik")
    (property "Sheetfile" "usbc-socket.kicad_sch")
    (property "Sheetname" "USB-C socket")
    (property "ki_description" "TVS diode")
    (property "ki_keywords" "SMT, DIODE, IC, ESD, TVS")
    (attr smd)
    (fp_text reference "U59" (at -1.93 -1.26 180) (layer "F.SilkS")
        (effects (font (size 0.7 0.7) (thickness 0.15)) (justify left bottom))
    )
    (fp_text value "82400152" (at 0 2 90) (layer "F.Fab") hide
        (effects (font (size 0.7 0.7) (thickness 0.15)) (justify left bottom))
    )
    (fp_text user "${REFERENCE}" (at -1.299 7.323 90) (layer "F.Fab") hide
        (effects (font (size 0.7 0.7) (thickness 0.15)) (justify left bottom))
    )
    (fp_text user "Author: Antmicro" (at -1.299 6.124 90) (layer "F.Fab") hide
        (effects (font (size 0.7 0.7) (thickness 0.15)) (justify left bottom))
    )
    (fp_text user "License: Apache-2.0" (at -1.299 4.924 90) (layer "F.Fab") hide
        (effects (font (size 0.7 0.7) (thickness 0.15)) (justify left bottom))
    )
    (fp_line (start -0.778 0.776) (end -0.778 0.949)
      (stroke (width 0.15) (type solid)) (layer "F.SilkS"))
    (fp_line (start -0.778 0.949) (end -0.424 0.949)
      (stroke (width 0.15) (type solid)) (layer "F.SilkS"))
    (fp_line (start -0.499 -0.974) (end -0.724 -0.778)
      (stroke (width 0.15) (type solid)) (layer "F.SilkS"))
    (fp_line (start 0.776 -0.974) (end 0.526 -0.974)
      (stroke (width 0.15) (type solid)) (layer "F.SilkS"))
    (fp_line (start 0.776 -0.974) (end 0.776 -0.778)
      (stroke (width 0.15) (type solid)) (layer "F.SilkS"))
    (fp_line (start 0.776 0.776) (end 0.776 0.972)
      (stroke (width 0.15) (type solid)) (layer "F.SilkS"))
    (fp_line (start 0.776 0.972) (end 0.526 0.972)
      (stroke (width 0.15) (type solid)) (layer "F.SilkS"))
    (fp_circle (center -0.903 -0.999) (end -0.952 -0.95)
      (stroke (width 0.15) (type solid)) (fill solid) (layer "F.SilkS"))
    (fp_rect (start 1.19 -1.12) (end -1.2 1.1)
      (stroke (width 0.05) (type solid)) (fill none) (layer "F.CrtYd"))
    (fp_line (start -0.653 -0.678) (end -0.653 0.847)
      (stroke (width 0.15) (type solid)) (layer "F.Fab"))
    (fp_line (start -0.453 -0.849) (end -0.653 -0.678)
      (stroke (width 0.15) (type solid)) (layer "F.Fab"))
    (fp_line (start -0.453 -0.849) (end 0.651 -0.849)
      (stroke (width 0.15) (type solid)) (layer "F.Fab"))
    (fp_line (start 0.651 -0.849) (end 0.651 0.847)
      (stroke (width 0.15) (type solid)) (layer "F.Fab"))
    (fp_line (start 0.651 0.847) (end -0.653 0.847)
      (stroke (width 0.15) (type solid)) (layer "F.Fab"))
    (pad "1" smd roundrect (at -0.749 -0.499) (size 0.3 0.6) (layers "F.Cu" "F.Paste" "F.Mask") (roundrect_rratio 0.25)
      (net 308 "/Debug and JTAG/USBC_CC2") (pintype "passive"))
    (pad "2" smd roundrect (at -0.749 0.001) (size 0.3 0.6) (layers "F.Cu" "F.Paste" "F.Mask") (roundrect_rratio 0.25)
      (net 1 "GND") (pintype "passive"))
    (pad "3" smd roundrect (at -0.749 0.497) (size 0.3 0.6) (layers "F.Cu" "F.Paste" "F.Mask") (roundrect_rratio 0.25)
      (net 307 "/Debug and JTAG/USBC_CC1") (pintype "passive"))
    (pad "4" smd roundrect (at 0.747 0.497) (size 0.3 0.6) (layers "F.Cu" "F.Paste" "F.Mask") (roundrect_rratio 0.25)
      (net 301 "/Power Supply/USB-C socket/USBC_TVS_CC1") (pintype "passive"))
    (pad "5" smd roundrect (at 0.747 0.001) (size 0.3 0.6) (layers "F.Cu" "F.Paste" "F.Mask") (roundrect_rratio 0.25)
      (net 756 "unconnected-(U59-Pad5)") (pintype "passive+no_connect"))
    (pad "6" smd roundrect (at 0.747 -0.499) (size 0.3 0.6) (layers "F.Cu" "F.Paste" "F.Mask") (roundrect_rratio 0.25)
      (net 300 "/Power Supply/USB-C socket/USBC_TVS_CC2") (pintype "passive"))
  )

  (footprint "kria-k26-devboard-footprints:C_0402_1005Metric" (layer "F.Cu")
    (at 142.45 75.575 180)
    (descr "Capacitor SMD 0402")
    (tags "capacitor SMD 0402")
    (property "Author" "Antmicro")
    (property "Dielectric" "X5R")
    (property "License" "Apache-2.0")
    (property "MPN" "GRM155R61H104KE14D")
    (property "Manufacturer" "Murata")
    (property "Sheetfile" "usb.kicad_sch")
    (property "Sheetname" "USB")
    (property "Val" "100n")
    (property "Voltage" "50V")
    (property "ki_description" " ")
    (attr smd)
    (fp_text reference "C63" (at 1.1 -1.355 180) (layer "F.SilkS")
        (effects (font (size 0.7 0.7) (thickness 0.15)) (justify left bottom))
    )
    (fp_text value "C_100n_0402" (at 0 1.4 180) (layer "F.Fab") hide
        (effects (font (size 0.7 0.7) (thickness 0.15)) (justify left bottom))
    )
    (fp_text user "Author: Antmicro" (at -0.932 4.17 180) (layer "F.Fab") hide
        (effects (font (size 0.7 0.7) (thickness 0.15)) (justify left bottom))
    )
    (fp_text user "License: Apache-2.0" (at -0.932 5.17 180) (layer "F.Fab") hide
        (effects (font (size 0.7 0.7) (thickness 0.15)) (justify left bottom))
    )
    (fp_text user "${REFERENCE}" (at -0.932 3.168 180) (layer "F.Fab") hide
        (effects (font (size 0.7 0.7) (thickness 0.15)) (justify left bottom))
    )
    (fp_rect (start -0.94 -0.47) (end 0.94 0.47)
      (stroke (width 0.05) (type solid)) (fill none) (layer "F.CrtYd"))
    (fp_rect (start -0.499 -0.249) (end 0.499 0.249)
      (stroke (width 0.15) (type solid)) (fill none) (layer "F.Fab"))
    (pad "1" smd roundrect (at -0.484 0 180) (size 0.59 0.64) (layers "F.Cu" "F.Paste" "F.Mask") (roundrect_rratio 0.25)
      (net 306 "USB_5V") (pintype "passive"))
    (pad "2" smd roundrect (at 0.484 0 180) (size 0.59 0.64) (layers "F.Cu" "F.Paste" "F.Mask") (roundrect_rratio 0.25)
      (net 1 "GND") (pintype "passive"))
  )

  (footprint "kria-k26-devboard-footprints:R_0402_1005Metric" (layer "F.Cu")
    (at 118.36 76.79 -90)
    (descr "Resistor SMD 0402")
    (tags "resistor SMD 0402")
    (property "Author" "Antmicro")
    (property "License" "Apache-2.0")
    (property "MPN" "CR0402-FX-2003GLF")
    (property "Manufacturer" "Bourns")
    (property "Sheetfile" "usb.kicad_sch")
    (property "Sheetname" "USB")
    (property "Tolerance" "1%")
    (property "Val" "200k")
    (property "ki_description" "200k resistor in 0402 package with 1% tolerance")
    (attr smd)
    (fp_text reference "R56" (at 1.06 2.46 -90) (layer "F.SilkS")
        (effects (font (size 0.7 0.7) (thickness 0.15)) (justify left bottom))
    )
    (fp_text value "R_200k_0402" (at 0 1.4 -90) (layer "F.Fab") hide
        (effects (font (size 0.7 0.7) (thickness 0.15)) (justify left bottom))
    )
    (fp_text user "${REFERENCE}" (at -0.95 3.168 -90) (layer "F.Fab") hide
        (effects (font (size 0.7 0.7) (thickness 0.15)) (justify left bottom))
    )
    (fp_text user "Author: Antmicro" (at -0.95 4.169 -90) (layer "F.Fab") hide
        (effects (font (size 0.7 0.7) (thickness 0.15)) (justify left bottom))
    )
    (fp_text user "License: Apache-2.0" (at -0.95 5.169 -90) (layer "F.Fab") hide
        (effects (font (size 0.7 0.7) (thickness 0.15)) (justify left bottom))
    )
    (fp_rect (start -0.93 -0.47) (end 0.93 0.47)
      (stroke (width 0.05) (type solid)) (fill none) (layer "F.CrtYd"))
    (fp_rect (start -0.5 -0.25) (end 0.5 0.25)
      (stroke (width 0.15) (type solid)) (fill none) (layer "F.Fab"))
    (pad "1" smd roundrect (at -0.485 0 270) (size 0.59 0.64) (layers "F.Cu" "F.Paste" "F.Mask") (roundrect_rratio 0.25)
      (net 1 "GND") (pintype "passive"))
    (pad "2" smd roundrect (at 0.485 0 270) (size 0.59 0.64) (layers "F.Cu" "F.Paste" "F.Mask") (roundrect_rratio 0.25)
      (net 659 "Net-(U17-PF6)") (pintype "passive"))
  )

  (footprint "kria-k26-devboard-footprints:R_0402_1005Metric" (layer "F.Cu")
    (at 129.906942 88.724862 180)
    (descr "Resistor SMD 0402")
    (tags "resistor SMD 0402")
    (property "Author" "Antmicro")
    (property "License" "Apache-2.0")
    (property "MPN" "CR0402-FX-2003GLF")
    (property "Manufacturer" "Bourns")
    (property "Sheetfile" "usb.kicad_sch")
    (property "Sheetname" "USB")
    (property "Tolerance" "1%")
    (property "Val" "200k")
    (property "ki_description" "200k resistor in 0402 package with 1% tolerance")
    (attr smd)
    (fp_text reference "R61" (at -0.873058 -0.405138 180) (layer "F.SilkS")
        (effects (font (size 0.7 0.7) (thickness 0.15)) (justify left bottom))
    )
    (fp_text value "R_200k_0402" (at 0 1.4 180) (layer "F.Fab") hide
        (effects (font (size 0.7 0.7) (thickness 0.15)) (justify left bottom))
    )
    (fp_text user "Author: Antmicro" (at -0.95 4.169 180) (layer "F.Fab") hide
        (effects (font (size 0.7 0.7) (thickness 0.15)) (justify left bottom))
    )
    (fp_text user "License: Apache-2.0" (at -0.95 5.169 180) (layer "F.Fab") hide
        (effects (font (size 0.7 0.7) (thickness 0.15)) (justify left bottom))
    )
    (fp_text user "${REFERENCE}" (at -0.95 3.168 180) (layer "F.Fab") hide
        (effects (font (size 0.7 0.7) (thickness 0.15)) (justify left bottom))
    )
    (fp_rect (start -0.93 -0.47) (end 0.93 0.47)
      (stroke (width 0.05) (type solid)) (fill none) (layer "F.CrtYd"))
    (fp_rect (start -0.5 -0.25) (end 0.5 0.25)
      (stroke (width 0.15) (type solid)) (fill none) (layer "F.Fab"))
    (pad "1" smd roundrect (at -0.485 0 180) (size 0.59 0.64) (layers "F.Cu" "F.Paste" "F.Mask") (roundrect_rratio 0.25)
      (net 1 "GND") (pintype "passive"))
    (pad "2" smd roundrect (at 0.485 0 180) (size 0.59 0.64) (layers "F.Cu" "F.Paste" "F.Mask") (roundrect_rratio 0.25)
      (net 664 "Net-(U17-PF31)") (pintype "passive"))
  )

  (footprint "kria-k26-devboard-footprints:R_0402_1005Metric" (layer "F.Cu")
    (at 117.286942 76.79 -90)
    (descr "Resistor SMD 0402")
    (tags "resistor SMD 0402")
    (property "Author" "Antmicro")
    (property "License" "Apache-2.0")
    (property "MPN" "CR0402-FX-2003GLF")
    (property "Manufacturer" "Bourns")
    (property "Sheetfile" "usb.kicad_sch")
    (property "Sheetname" "USB")
    (property "Tolerance" "1%")
    (property "Val" "200k")
    (property "ki_description" "200k resistor in 0402 package with 1% tolerance")
    (attr smd)
    (fp_text reference "R58" (at 1.06 2.46 -90) (layer "F.SilkS")
        (effects (font (size 0.7 0.7) (thickness 0.15)) (justify left bottom))
    )
    (fp_text value "R_200k_0402" (at 0 1.4 -90) (layer "F.Fab") hide
        (effects (font (size 0.7 0.7) (thickness 0.15)) (justify left bottom))
    )
    (fp_text user "${REFERENCE}" (at -0.95 3.168 -90) (layer "F.Fab") hide
        (effects (font (size 0.7 0.7) (thickness 0.15)) (justify left bottom))
    )
    (fp_text user "Author: Antmicro" (at -0.95 4.169 -90) (layer "F.Fab") hide
        (effects (font (size 0.7 0.7) (thickness 0.15)) (justify left bottom))
    )
    (fp_text user "License: Apache-2.0" (at -0.95 5.169 -90) (layer "F.Fab") hide
        (effects (font (size 0.7 0.7) (thickness 0.15)) (justify left bottom))
    )
    (fp_rect (start -0.93 -0.47) (end 0.93 0.47)
      (stroke (width 0.05) (type solid)) (fill none) (layer "F.CrtYd"))
    (fp_rect (start -0.5 -0.25) (end 0.5 0.25)
      (stroke (width 0.15) (type solid)) (fill none) (layer "F.Fab"))
    (pad "1" smd roundrect (at -0.485 0 270) (size 0.59 0.64) (layers "F.Cu" "F.Paste" "F.Mask") (roundrect_rratio 0.25)
      (net 1 "GND") (pintype "passive"))
    (pad "2" smd roundrect (at 0.485 0 270) (size 0.59 0.64) (layers "F.Cu" "F.Paste" "F.Mask") (roundrect_rratio 0.25)
      (net 661 "Net-(U17-PF8)") (pintype "passive"))
  )

  (footprint "kria-k26-devboard-footprints:R_0402_1005Metric" (layer "F.Cu")
    (at 119.32 76.79 -90)
    (descr "Resistor SMD 0402")
    (tags "resistor SMD 0402")
    (property "Author" "Antmicro")
    (property "License" "Apache-2.0")
    (property "MPN" "CR0402-FX-2003GLF")
    (property "Manufacturer" "Bourns")
    (property "Sheetfile" "usb.kicad_sch")
    (property "Sheetname" "USB")
    (property "Tolerance" "1%")
    (property "Val" "200k")
    (property "ki_description" "200k resistor in 0402 package with 1% tolerance")
    (attr smd)
    (fp_text reference "R54" (at 1.06 2.46 -90) (layer "F.SilkS")
        (effects (font (size 0.7 0.7) (thickness 0.15)) (justify left bottom))
    )
    (fp_text value "R_200k_0402" (at 0 1.4 -90) (layer "F.Fab") hide
        (effects (font (size 0.7 0.7) (thickness 0.15)) (justify left bottom))
    )
    (fp_text user "License: Apache-2.0" (at -0.95 5.169 -90) (layer "F.Fab") hide
        (effects (font (size 0.7 0.7) (thickness 0.15)) (justify left bottom))
    )
    (fp_text user "Author: Antmicro" (at -0.95 4.169 -90) (layer "F.Fab") hide
        (effects (font (size 0.7 0.7) (thickness 0.15)) (justify left bottom))
    )
    (fp_text user "${REFERENCE}" (at -0.95 3.168 -90) (layer "F.Fab") hide
        (effects (font (size 0.7 0.7) (thickness 0.15)) (justify left bottom))
    )
    (fp_rect (start -0.93 -0.47) (end 0.93 0.47)
      (stroke (width 0.05) (type solid)) (fill none) (layer "F.CrtYd"))
    (fp_rect (start -0.5 -0.25) (end 0.5 0.25)
      (stroke (width 0.15) (type solid)) (fill none) (layer "F.Fab"))
    (pad "1" smd roundrect (at -0.485 0 270) (size 0.59 0.64) (layers "F.Cu" "F.Paste" "F.Mask") (roundrect_rratio 0.25)
      (net 1 "GND") (pintype "passive"))
    (pad "2" smd roundrect (at 0.485 0 270) (size 0.59 0.64) (layers "F.Cu" "F.Paste" "F.Mask") (roundrect_rratio 0.25)
      (net 657 "Net-(U17-PF4)") (pintype "passive"))
  )

  (footprint "kria-k26-devboard-footprints:R_0402_1005Metric" (layer "F.Cu")
    (at 114.406942 85.024862)
    (descr "Resistor SMD 0402")
    (tags "resistor SMD 0402")
    (property "Author" "Antmicro")
    (property "License" "Apache-2.0")
    (property "MPN" "CR0402-FX-1002GLF")
    (property "Manufacturer" "Bourns")
    (property "Sheetfile" "usb.kicad_sch")
    (property "Sheetname" "USB")
    (property "Tolerance" "1%")
    (property "Val" "10k")
    (property "ki_description" "10k resistor in 0402 package with 1% tolerance")
    (attr smd)
    (fp_text reference "R47" (at -3.086942 0.335138) (layer "F.SilkS")
        (effects (font (size 0.7 0.7) (thickness 0.15)) (justify left bottom))
    )
    (fp_text value "R_10k_0402" (at 0 1.4) (layer "F.Fab") hide
        (effects (font (size 0.7 0.7) (thickness 0.15)) (justify left bottom))
    )
    (fp_text user "${REFERENCE}" (at -0.95 3.168) (layer "F.Fab") hide
        (effects (font (size 0.7 0.7) (thickness 0.15)) (justify left bottom))
    )
    (fp_text user "License: Apache-2.0" (at -0.95 5.169) (layer "F.Fab") hide
        (effects (font (size 0.7 0.7) (thickness 0.15)) (justify left bottom))
    )
    (fp_text user "Author: Antmicro" (at -0.95 4.169) (layer "F.Fab") hide
        (effects (font (size 0.7 0.7) (thickness 0.15)) (justify left bottom))
    )
    (fp_rect (start -0.93 -0.47) (end 0.93 0.47)
      (stroke (width 0.05) (type solid)) (fill none) (layer "F.CrtYd"))
    (fp_rect (start -0.5 -0.25) (end 0.5 0.25)
      (stroke (width 0.15) (type solid)) (fill none) (layer "F.Fab"))
    (pad "1" smd roundrect (at -0.485 0) (size 0.59 0.64) (layers "F.Cu" "F.Paste" "F.Mask") (roundrect_rratio 0.25)
      (net 1 "GND") (pintype "passive"))
    (pad "2" smd roundrect (at 0.485 0) (size 0.59 0.64) (layers "F.Cu" "F.Paste" "F.Mask") (roundrect_rratio 0.25)
      (net 650 "Net-(U17-TEST2)") (pintype "passive"))
  )

  (footprint "kria-k26-devboard-footprints:R_0402_1005Metric" (layer "F.Cu")
    (at 129.95 81.8 180)
    (descr "Resistor SMD 0402")
    (tags "resistor SMD 0402")
    (property "Author" "Antmicro")
    (property "License" "Apache-2.0")
    (property "MPN" "CR0402-FX-2003GLF")
    (property "Manufacturer" "Bourns")
    (property "Sheetfile" "usb.kicad_sch")
    (property "Sheetname" "USB")
    (property "Tolerance" "1%")
    (property "Val" "200k")
    (property "ki_description" "200k resistor in 0402 package with 1% tolerance")
    (attr smd)
    (fp_text reference "R50" (at -0.8 -0.37 180) (layer "F.SilkS")
        (effects (font (size 0.7 0.7) (thickness 0.15)) (justify left bottom))
    )
    (fp_text value "R_200k_0402" (at 0 1.4 180) (layer "F.Fab") hide
        (effects (font (size 0.7 0.7) (thickness 0.15)) (justify left bottom))
    )
    (fp_text user "${REFERENCE}" (at -0.95 3.168 180) (layer "F.Fab") hide
        (effects (font (size 0.7 0.7) (thickness 0.15)) (justify left bottom))
    )
    (fp_text user "License: Apache-2.0" (at -0.95 5.169 180) (layer "F.Fab") hide
        (effects (font (size 0.7 0.7) (thickness 0.15)) (justify left bottom))
    )
    (fp_text user "Author: Antmicro" (at -0.95 4.169 180) (layer "F.Fab") hide
        (effects (font (size 0.7 0.7) (thickness 0.15)) (justify left bottom))
    )
    (fp_rect (start -0.93 -0.47) (end 0.93 0.47)
      (stroke (width 0.05) (type solid)) (fill none) (layer "F.CrtYd"))
    (fp_rect (start -0.5 -0.25) (end 0.5 0.25)
      (stroke (width 0.15) (type solid)) (fill none) (layer "F.Fab"))
    (pad "1" smd roundrect (at -0.485 0 180) (size 0.59 0.64) (layers "F.Cu" "F.Paste" "F.Mask") (roundrect_rratio 0.25)
      (net 1 "GND") (pintype "passive"))
    (pad "2" smd roundrect (at 0.485 0 180) (size 0.59 0.64) (layers "F.Cu" "F.Paste" "F.Mask") (roundrect_rratio 0.25)
      (net 653 "Net-(U17-CFG_STRAP2)") (pintype "passive"))
  )

  (footprint "kria-k26-devboard-footprints:R_0402_1005Metric" (layer "F.Cu")
    (at 129.95 80.8 180)
    (descr "Resistor SMD 0402")
    (tags "resistor SMD 0402")
    (property "Author" "Antmicro")
    (property "License" "Apache-2.0")
    (property "MPN" "CR0402-FX-2003GLF")
    (property "Manufacturer" "Bourns")
    (property "Sheetfile" "usb.kicad_sch")
    (property "Sheetname" "USB")
    (property "Tolerance" "1%")
    (property "Val" "200k")
    (property "ki_description" "200k resistor in 0402 package with 1% tolerance")
    (attr smd)
    (fp_text reference "R51" (at -0.8 -0.37 180) (layer "F.SilkS")
        (effects (font (size 0.7 0.7) (thickness 0.15)) (justify left bottom))
    )
    (fp_text value "R_200k_0402" (at 0 1.4 180) (layer "F.Fab") hide
        (effects (font (size 0.7 0.7) (thickness 0.15)) (justify left bottom))
    )
    (fp_text user "License: Apache-2.0" (at -0.95 5.169 180) (layer "F.Fab") hide
        (effects (font (size 0.7 0.7) (thickness 0.15)) (justify left bottom))
    )
    (fp_text user "${REFERENCE}" (at -0.95 3.168 180) (layer "F.Fab") hide
        (effects (font (size 0.7 0.7) (thickness 0.15)) (justify left bottom))
    )
    (fp_text user "Author: Antmicro" (at -0.95 4.169 180) (layer "F.Fab") hide
        (effects (font (size 0.7 0.7) (thickness 0.15)) (justify left bottom))
    )
    (fp_rect (start -0.93 -0.47) (end 0.93 0.47)
      (stroke (width 0.05) (type solid)) (fill none) (layer "F.CrtYd"))
    (fp_rect (start -0.5 -0.25) (end 0.5 0.25)
      (stroke (width 0.15) (type solid)) (fill none) (layer "F.Fab"))
    (pad "1" smd roundrect (at -0.485 0 180) (size 0.59 0.64) (layers "F.Cu" "F.Paste" "F.Mask") (roundrect_rratio 0.25)
      (net 1 "GND") (pintype "passive"))
    (pad "2" smd roundrect (at 0.485 0 180) (size 0.59 0.64) (layers "F.Cu" "F.Paste" "F.Mask") (roundrect_rratio 0.25)
      (net 654 "Net-(U17-CFG_STRAP3)") (pintype "passive"))
  )

  (footprint "kria-k26-devboard-footprints:C_0603_1608Metric" (layer "F.Cu")
    (at 169.25 137.65)
    (descr "Capacitor SMD 0603")
    (tags "capacitor 0603")
    (property "Author" "Antmicro")
    (property "Dielectric" "")
    (property "License" "Apache-2.0")
    (property "MPN" "GRM188R60J226MEA0D")
    (property "Manufacturer" "Murata")
    (property "Sheetfile" "dc-dc-conventers.kicad_sch")
    (property "Sheetname" "DC/DC conventers")
    (property "Val" "22u")
    (property "Voltage" "")
    (property "ki_description" " ")
    (attr smd)
    (fp_text reference "C216" (at 0.69 2.55) (layer "F.SilkS")
        (effects (font (size 0.7 0.7) (thickness 0.15)) (justify left bottom))
    )
    (fp_text value "C_22u_0603" (at 0 1.6) (layer "F.Fab") hide
        (effects (font (size 0.7 0.7) (thickness 0.15)) (justify left bottom))
    )
    (fp_text user "${REFERENCE}" (at -1.682 3.895) (layer "F.Fab") hide
        (effects (font (size 0.7 0.7) (thickness 0.15)) (justify left bottom))
    )
    (fp_text user "Author: Antmicro" (at -1.682 4.894) (layer "F.Fab") hide
        (effects (font (size 0.7 0.7) (thickness 0.15)) (justify left bottom))
    )
    (fp_text user "License: Apache-2.0" (at -1.682 5.895) (layer "F.Fab") hide
        (effects (font (size 0.7 0.7) (thickness 0.15)) (justify left bottom))
    )
    (fp_line (start -0.3 -0.3) (end 0.3 -0.3)
      (stroke (width 0.15) (type solid)) (layer "F.SilkS"))
    (fp_line (start -0.3 0.3) (end 0.3 0.3)
      (stroke (width 0.15) (type solid)) (layer "F.SilkS"))
    (fp_rect (start -1.24 -0.7) (end 1.24 0.7)
      (stroke (width 0.05) (type solid)) (fill none) (layer "F.CrtYd"))
    (fp_rect (start -0.8 -0.4) (end 0.8 0.4)
      (stroke (width 0.15) (type solid)) (fill none) (layer "F.Fab"))
    (pad "1" smd roundrect (at -0.7 0) (size 0.6 0.8) (layers "F.Cu" "F.Paste" "F.Mask") (roundrect_rratio 0.2)
      (net 765 "/Power Supply/DC/DC conventers/PS_3V3_OUT") (pintype "passive"))
    (pad "2" smd roundrect (at 0.7 0) (size 0.6 0.8) (layers "F.Cu" "F.Paste" "F.Mask") (roundrect_rratio 0.2)
      (net 1 "GND") (pintype "passive"))
  )

  (footprint "kria-k26-devboard-footprints:C_0603_1608Metric" (layer "F.Cu")
    (at 169.25 139.06)
    (descr "Capacitor SMD 0603")
    (tags "capacitor 0603")
    (property "Author" "Antmicro")
    (property "Dielectric" "")
    (property "License" "Apache-2.0")
    (property "MPN" "GRM188R60J226MEA0D")
    (property "Manufacturer" "Murata")
    (property "Sheetfile" "dc-dc-conventers.kicad_sch")
    (property "Sheetname" "DC/DC conventers")
    (property "Val" "22u")
    (property "Voltage" "")
    (property "ki_description" " ")
    (attr smd)
    (fp_text reference "C211" (at 0.69 2.04) (layer "F.SilkS")
        (effects (font (size 0.7 0.7) (thickness 0.15)) (justify left bottom))
    )
    (fp_text value "C_22u_0603" (at 0 1.6) (layer "F.Fab") hide
        (effects (font (size 0.7 0.7) (thickness 0.15)) (justify left bottom))
    )
    (fp_text user "${REFERENCE}" (at -1.682 3.895) (layer "F.Fab") hide
        (effects (font (size 0.7 0.7) (thickness 0.15)) (justify left bottom))
    )
    (fp_text user "License: Apache-2.0" (at -1.682 5.895) (layer "F.Fab") hide
        (effects (font (size 0.7 0.7) (thickness 0.15)) (justify left bottom))
    )
    (fp_text user "Author: Antmicro" (at -1.682 4.894) (layer "F.Fab") hide
        (effects (font (size 0.7 0.7) (thickness 0.15)) (justify left bottom))
    )
    (fp_line (start -0.3 -0.3) (end 0.3 -0.3)
      (stroke (width 0.15) (type solid)) (layer "F.SilkS"))
    (fp_line (start -0.3 0.3) (end 0.3 0.3)
      (stroke (width 0.15) (type solid)) (layer "F.SilkS"))
    (fp_rect (start -1.24 -0.7) (end 1.24 0.7)
      (stroke (width 0.05) (type solid)) (fill none) (layer "F.CrtYd"))
    (fp_rect (start -0.8 -0.4) (end 0.8 0.4)
      (stroke (width 0.15) (type solid)) (fill none) (layer "F.Fab"))
    (pad "1" smd roundrect (at -0.7 0) (size 0.6 0.8) (layers "F.Cu" "F.Paste" "F.Mask") (roundrect_rratio 0.2)
      (net 765 "/Power Supply/DC/DC conventers/PS_3V3_OUT") (pintype "passive"))
    (pad "2" smd roundrect (at 0.7 0) (size 0.6 0.8) (layers "F.Cu" "F.Paste" "F.Mask") (roundrect_rratio 0.2)
      (net 1 "GND") (pintype "passive"))
  )

  (footprint "kria-k26-devboard-footprints:TSOT23-6" (layer "F.Cu")
    (at 170.93 134.89)
    (property "Author" "Antmicro")
    (property "License" "Apache-2.0")
    (property "MPN" "AP62301WU-7")
    (property "Manufacturer" "Diodes Incorporated")
    (property "Sheetfile" "dc-dc-conventers.kicad_sch")
    (property "Sheetname" "DC/DC conventers")
    (property "ki_description" "DC-DC Switching Synchronous Buck Regulator, Adjustable, 4.2V-18Vin, 0.8V-7V/3A out, TSOT-26-6")
    (property "ki_keywords" "SMT, PMIC, IC, VOLTAGE")
    (attr smd)
    (fp_text reference "U49" (at 1.285 1.79) (layer "F.SilkS")
        (effects (font (size 0.7 0.7) (thickness 0.15)) (justify left bottom))
    )
    (fp_text value "AP62301_TSOT" (at -0.005 2.6) (layer "F.Fab") hide
        (effects (font (size 0.7 0.7) (thickness 0.15)) (justify left bottom))
    )
    (fp_text user "${REFERENCE}" (at -1.893 6.168) (layer "F.Fab") hide
        (effects (font (size 0.7 0.7) (thickness 0.15)) (justify left bottom))
    )
    (fp_text user "License: Apache-2.0" (at -1.893 4.967) (layer "F.Fab") hide
        (effects (font (size 0.7 0.7) (thickness 0.15)) (justify left bottom))
    )
    (fp_text user "Author: Antmicro" (at -1.893 7.368) (layer "F.Fab") hide
        (effects (font (size 0.7 0.7) (thickness 0.15)) (justify left bottom))
    )
    (fp_line (start -1.4805 0.725) (end -1.4795 -0.725)
      (stroke (width 0.15) (type solid)) (layer "F.SilkS"))
    (fp_line (start -1.4805 0.725) (end -1.3905 0.725)
      (stroke (width 0.15) (type solid)) (layer "F.SilkS"))
    (fp_line (start -1.4795 -0.725) (end -1.3905 -0.725)
      (stroke (width 0.15) (type solid)) (layer "F.SilkS"))
    (fp_line (start 1.479 0.73) (end 1.38 0.73)
      (stroke (width 0.15) (type solid)) (layer "F.SilkS"))
    (fp_line (start 1.48 -0.72) (end 1.38 -0.72)
      (stroke (width 0.15) (type solid)) (layer "F.SilkS"))
    (fp_line (start 1.48 -0.72) (end 1.479 0.73)
      (stroke (width 0.15) (type solid)) (layer "F.SilkS"))
    (fp_circle (center -1.499 1.236) (end -1.45 1.236)
      (stroke (width 0.15) (type solid)) (fill solid) (layer "F.SilkS"))
    (fp_rect (start -1.65 -1.61) (end 1.65 1.61)
      (stroke (width 0.05) (type solid)) (fill none) (layer "F.CrtYd"))
    (fp_line (start -1.527 -0.833) (end 1.523 -0.833)
      (stroke (width 0.15) (type solid)) (layer "F.Fab"))
    (fp_line (start -1.527 0.491) (end -1.527 -0.833)
      (stroke (width 0.15) (type solid)) (layer "F.Fab"))
    (fp_line (start -1.527 0.491) (end -1.102 0.916)
      (stroke (width 0.15) (type solid)) (layer "F.Fab"))
    (fp_line (start -1.102 0.916) (end 1.523 0.916)
      (stroke (width 0.15) (type solid)) (layer "F.Fab"))
    (fp_line (start 1.523 -0.833) (end 1.523 0.916)
      (stroke (width 0.15) (type solid)) (layer "F.Fab"))
    (pad "1" smd rect (at -0.952 1.18) (size 0.7 0.8) (layers "F.Cu" "F.Paste" "F.Mask")
      (net 1 "GND") (pinfunction "GND") (pintype "power_in"))
    (pad "2" smd rect (at -0.001 1.18) (size 0.7 0.8) (layers "F.Cu" "F.Paste" "F.Mask")
      (net 309 "/Power Supply/DC/DC conventers/SW_PS_3V3") (pinfunction "SW") (pintype "power_out"))
    (pad "3" smd rect (at 0.947 1.18) (size 0.7 0.8) (layers "F.Cu" "F.Paste" "F.Mask")
      (net 14 "/Power Supply/DC/DC conventers/DC_MAIN_BUS") (pinfunction "VIN") (pintype "power_in"))
    (pad "4" smd rect (at 0.947 -1.18) (size 0.7 0.8) (layers "F.Cu" "F.Paste" "F.Mask")
      (net 688 "Net-(U49-FB)") (pinfunction "FB") (pintype "input"))
    (pad "5" smd rect (at -0.001 -1.18) (size 0.7 0.8) (layers "F.Cu" "F.Paste" "F.Mask")
      (net 23 "/Power Supply/VCCOEN_PS_M2C") (pinfunction "EN") (pintype "input"))
    (pad "6" smd rect (at -0.952 -1.18) (size 0.7 0.8) (layers "F.Cu" "F.Paste" "F.Mask")
      (net 257 "Net-(U49-BST)") (pinfunction "BST") (pintype "output"))
  )

  (footprint "kria-k26-devboard-footprints:L_Coilcraft-XEL4030" (layer "F.Cu")
    (at 166.825 134.85 -90)
    (property "Author" "Antmicro")
    (property "IMax" "")
    (property "ISat" "")
    (property "License" "Apache-2.0")
    (property "MPN" "XEL4030-222MEC")
    (property "Manufacturer" "Coilcraft")
    (property "Sheetfile" "dc-dc-conventers.kicad_sch")
    (property "Sheetname" "DC/DC conventers")
    (property "Size" "4x4")
    (property "Val" "2u2/6.1A")
    (attr smd)
    (fp_text reference "L3" (at -1.86 3.505) (layer "F.SilkS")
        (effects (font (size 0.7 0.7) (thickness 0.15)) (justify left bottom))
    )
    (fp_text value "L_2u2_6.1A_XEL4030" (at 0.05 2.996 -90) (layer "F.Fab") hide
        (effects (font (size 0.7 0.7) (thickness 0.15)) (justify left bottom))
    )
    (fp_text user "Author: Antmicro" (at -2.15 5.996 -90) (layer "F.Fab") hide
        (effects (font (size 0.7 0.7) (thickness 0.15)) (justify left bottom))
    )
    (fp_text user "License: Apache-2.0" (at -2.15 6.996 -90) (layer "F.Fab") hide
        (effects (font (size 0.7 0.7) (thickness 0.15)) (justify left bottom))
    )
    (fp_text user "${REFERENCE}" (at -2.15 4.996 -90) (layer "F.Fab") hide
        (effects (font (size 0.7 0.7) (thickness 0.15)) (justify left bottom))
    )
    (fp_line (start -1.8 -2.2) (end 1.85 -2.201)
      (stroke (width 0.15) (type solid)) (layer "F.SilkS"))
    (fp_line (start -1.8 2.2) (end 1.85 2.199)
      (stroke (width 0.15) (type solid)) (layer "F.SilkS"))
    (fp_rect (start -2.45 -2.45) (end 2.45 2.45)
      (stroke (width 0.05) (type solid)) (fill none) (layer "F.CrtYd"))
    (fp_line (start -2 -2) (end 1.999 -2)
      (stroke (width 0.15) (type solid)) (layer "F.Fab"))
    (fp_line (start -2 1.999) (end -2 -2)
      (stroke (width 0.15) (type solid)) (layer "F.Fab"))
    (fp_line (start 1.999 -2) (end 1.999 1.999)
      (stroke (width 0.15) (type solid)) (layer "F.Fab"))
    (fp_line (start 1.999 1.999) (end -2 1.999)
      (stroke (width 0.15) (type solid)) (layer "F.Fab"))
    (pad "1" smd rect (at -1.186 0 270) (size 0.98 3.4) (layers "F.Cu" "F.Paste" "F.Mask")
      (net 309 "/Power Supply/DC/DC conventers/SW_PS_3V3") (pintype "passive"))
    (pad "2" smd rect (at 1.185 0 270) (size 0.98 3.4) (layers "F.Cu" "F.Paste" "F.Mask")
      (net 765 "/Power Supply/DC/DC conventers/PS_3V3_OUT") (pintype "passive"))
  )

  (footprint "kria-k26-devboard-footprints:LED_0603_1608Metric_G" (layer "F.Cu")
    (at 171.1 131.175)
    (descr "LED SMD 0603 Green")
    (tags "LED SMD 0603 Green")
    (property "Author" "Antmicro")
    (property "Color" "Green")
    (property "License" "Apache-2.0")
    (property "MPN" "LG L29K-G2J1-24-Z")
    (property "Manufacturer" "OSRAM")
    (property "Sheetfile" "dc-dc-conventers.kicad_sch")
    (property "Sheetname" "DC/DC conventers")
    (property "ki_description" "LED, Green, SMT, 0603, 20 mA, 2.1 V, 570 nm")
    (property "ki_keywords" "0603, SMT, DIODE, SEMICONDUCTOR, UNICOLOR")
    (attr smd)
    (fp_text reference "D14" (at -2.3 -0.605) (layer "F.SilkS")
        (effects (font (size 0.7 0.7) (thickness 0.15)) (justify left bottom))
    )
    (fp_text value "LED_G_0603_LG_L29K-G2J1-24-Z" (at 0 1.6) (layer "F.Fab") hide
        (effects (font (size 0.7 0.7) (thickness 0.15)) (justify left bottom))
    )
    (fp_text user "License: Apache-2.0" (at -1.31 5.769) (layer "F.Fab") hide
        (effects (font (size 0.7 0.7) (thickness 0.15)) (justify left bottom))
    )
    (fp_text user "${REFERENCE}" (at -1.31 3.769) (layer "F.Fab") hide
        (effects (font (size 0.7 0.7) (thickness 0.15)) (justify left bottom))
    )
    (fp_text user "Author: Antmicro" (at -1.31 4.769) (layer "F.Fab") hide
        (effects (font (size 0.7 0.7) (thickness 0.15)) (justify left bottom))
    )
    (fp_line (start -0.27 -0.35) (end 0.27 -0.35)
      (stroke (width 0.15) (type solid)) (layer "F.SilkS"))
    (fp_line (start -0.27 0.351) (end 0.27 0.351)
      (stroke (width 0.15) (type solid)) (layer "F.SilkS"))
    (fp_line (start -0.106328 -0.200008) (end -0.106328 0.199992)
      (stroke (width 0.1) (type solid)) (layer "F.SilkS"))
    (fp_line (start -0.106328 -0.200008) (end 0.093672 -0.000008)
      (stroke (width 0.1) (type solid)) (layer "F.SilkS"))
    (fp_line (start -0.106328 -0.000008) (end -0.29 0)
      (stroke (width 0.1) (type solid)) (layer "F.SilkS"))
    (fp_line (start 0.093672 -0.200008) (end 0.093672 0.199992)
      (stroke (width 0.1) (type solid)) (layer "F.SilkS"))
    (fp_line (start 0.093672 -0.000008) (end -0.106328 0.199992)
      (stroke (width 0.1) (type solid)) (layer "F.SilkS"))
    (fp_line (start 0.093672 -0.000008) (end 0.293672 -0.000008)
      (stroke (width 0.1) (type solid)) (layer "F.SilkS"))
    (fp_line (start 1.25 0.32) (end 1.25 -0.32)
      (stroke (width 0.15) (type solid)) (layer "F.SilkS"))
    (fp_rect (start 1.26 0.65) (end -1.26 -0.65)
      (stroke (width 0.05) (type solid)) (fill none) (layer "F.CrtYd"))
    (fp_line (start -0.599 0) (end -0.201 0)
      (stroke (width 0.15) (type solid)) (layer "F.Fab"))
    (fp_line (start -0.201 -0.2) (end -0.201 0)
      (stroke (width 0.15) (type solid)) (layer "F.Fab"))
    (fp_line (start -0.201 0) (end -0.201 0.202)
      (stroke (width 0.15) (type solid)) (layer "F.Fab"))
    (fp_line (start -0.201 0.202) (end 0.101 0)
      (stroke (width 0.15) (type solid)) (layer "F.Fab"))
    (fp_line (start 0.101 0) (end -0.201 -0.2)
      (stroke (width 0.15) (type solid)) (layer "F.Fab"))
    (fp_line (start 0.199 -0.2) (end 0.199 -0.1)
      (stroke (width 0.15) (type solid)) (layer "F.Fab"))
    (fp_line (start 0.199 0) (end 0.597 0)
      (stroke (width 0.15) (type solid)) (layer "F.Fab"))
    (fp_line (start 0.199 0.202) (end 0.199 -0.1)
      (stroke (width 0.15) (type solid)) (layer "F.Fab"))
    (fp_rect (start -0.848 -0.4) (end 0.85 0.402)
      (stroke (width 0.15) (type solid)) (fill none) (layer "F.Fab"))
    (pad "1" smd rect (at -0.75 0 180) (size 0.8 0.8) (layers "F.Cu" "F.Paste" "F.Mask")
      (net 239 "Net-(D14-Pad1)") (pintype "passive"))
    (pad "2" smd rect (at 0.75 0 180) (size 0.8 0.8) (layers "F.Cu" "F.Paste" "F.Mask")
      (net 1 "GND") (pinfunction "2") (pintype "passive"))
  )

  (footprint "kria-k26-devboard-footprints:C_0402_1005Metric" (layer "F.Cu")
    (at 86.6 71.317 90)
    (descr "Capacitor SMD 0402")
    (tags "capacitor SMD 0402")
    (property "Author" "Antmicro")
    (property "Dielectric" "X5R")
    (property "License" "Apache-2.0")
    (property "MPN" "GRM155R61H104KE14D")
    (property "Manufacturer" "Murata")
    (property "Sheetfile" "dp.kicad_sch")
    (property "Sheetname" "Display Port")
    (property "Val" "100n")
    (property "Voltage" "50V")
    (property "ki_description" " ")
    (attr smd)
    (fp_text reference "C8" (at -2.403 0.37 90) (layer "F.SilkS")
        (effects (font (size 0.7 0.7) (thickness 0.15)) (justify left bottom))
    )
    (fp_text value "C_100n_0402" (at 0 1.4 90) (layer "F.Fab") hide
        (effects (font (size 0.7 0.7) (thickness 0.15)) (justify left bottom))
    )
    (fp_text user "${REFERENCE}" (at -0.932 3.168 90) (layer "F.Fab") hide
        (effects (font (size 0.7 0.7) (thickness 0.15)) (justify left bottom))
    )
    (fp_text user "Author: Antmicro" (at -0.932 4.17 90) (layer "F.Fab") hide
        (effects (font (size 0.7 0.7) (thickness 0.15)) (justify left bottom))
    )
    (fp_text user "License: Apache-2.0" (at -0.932 5.17 90) (layer "F.Fab") hide
        (effects (font (size 0.7 0.7) (thickness 0.15)) (justify left bottom))
    )
    (fp_rect (start -0.94 -0.47) (end 0.94 0.47)
      (stroke (width 0.05) (type solid)) (fill none) (layer "F.CrtYd"))
    (fp_rect (start -0.499 -0.249) (end 0.499 0.249)
      (stroke (width 0.15) (type solid)) (fill none) (layer "F.Fab"))
    (pad "1" smd roundrect (at -0.484 0 90) (size 0.59 0.64) (layers "F.Cu" "F.Paste" "F.Mask") (roundrect_rratio 0.25)
      (net 100 "/Display Port/GTR_DP0_M2C_P") (pintype "passive"))
    (pad "2" smd roundrect (at 0.484 0 90) (size 0.59 0.64) (layers "F.Cu" "F.Paste" "F.Mask") (roundrect_rratio 0.25)
      (net 101 "/Display Port/GTR_DP0_M2C_C_P") (pintype "passive"))
  )

  (footprint "kria-k26-devboard-footprints:C_0402_1005Metric" (layer "F.Cu")
    (at 87.59 71.317 90)
    (descr "Capacitor SMD 0402")
    (tags "capacitor SMD 0402")
    (property "Author" "Antmicro")
    (property "Dielectric" "X5R")
    (property "License" "Apache-2.0")
    (property "MPN" "GRM155R61H104KE14D")
    (property "Manufacturer" "Murata")
    (property "Sheetfile" "dp.kicad_sch")
    (property "Sheetname" "Display Port")
    (property "Val" "100n")
    (property "Voltage" "50V")
    (property "ki_description" " ")
    (attr smd)
    (fp_text reference "C9" (at -2.403 0.37 90) (layer "F.SilkS")
        (effects (font (size 0.7 0.7) (thickness 0.15)) (justify left bottom))
    )
    (fp_text value "C_100n_0402" (at 0 1.4 90) (layer "F.Fab") hide
        (effects (font (size 0.7 0.7) (thickness 0.15)) (justify left bottom))
    )
    (fp_text user "Author: Antmicro" (at -0.932 4.17 90) (layer "F.Fab") hide
        (effects (font (size 0.7 0.7) (thickness 0.15)) (justify left bottom))
    )
    (fp_text user "${REFERENCE}" (at -0.932 3.168 90) (layer "F.Fab") hide
        (effects (font (size 0.7 0.7) (thickness 0.15)) (justify left bottom))
    )
    (fp_text user "License: Apache-2.0" (at -0.932 5.17 90) (layer "F.Fab") hide
        (effects (font (size 0.7 0.7) (thickness 0.15)) (justify left bottom))
    )
    (fp_rect (start -0.94 -0.47) (end 0.94 0.47)
      (stroke (width 0.05) (type solid)) (fill none) (layer "F.CrtYd"))
    (fp_rect (start -0.499 -0.249) (end 0.499 0.249)
      (stroke (width 0.15) (type solid)) (fill none) (layer "F.Fab"))
    (pad "1" smd roundrect (at -0.484 0 90) (size 0.59 0.64) (layers "F.Cu" "F.Paste" "F.Mask") (roundrect_rratio 0.25)
      (net 102 "/Display Port/GTR_DP0_M2C_N") (pintype "passive"))
    (pad "2" smd roundrect (at 0.484 0 90) (size 0.59 0.64) (layers "F.Cu" "F.Paste" "F.Mask") (roundrect_rratio 0.25)
      (net 103 "/Display Port/GTR_DP0_M2C_C_N") (pintype "passive"))
  )

  (footprint "kria-k26-devboard-footprints:Oscillator_SMD_Geyer_KX-7-4Pin_3.2x2.5mm" (layer "F.Cu")
    (at 150.21906 125.686827)
    (property "Author" "Antmicro")
    (property "License" "Apache-2.0")
    (property "MPN" "ABM8G-12.000MHZ-18-D2Y-T")
    (property "Manufacturer" "Abracon")
    (property "Sheetfile" "debug.kicad_sch")
    (property "Sheetname" "Debug and JTAG")
    (property "Val" "12 MHz")
    (property "ki_description" "Crystal, 12 MHz, SMT, 3.2mm x 2.5mm, 30 ppm, 18 pF, 20 ppm, ABM8G")
    (property "ki_keywords" "SMT, CERAMIC, OSCILLATOR")
    (attr smd)
    (fp_text reference "Y7" (at -1.46906 2.383173 180) (layer "F.SilkS")
        (effects (font (size 0.7 0.7) (thickness 0.15)) (justify left bottom))
    )
    (fp_text value "Resonator_12MHz_ABM8G" (at -1.75 2.548) (layer "F.Fab") hide
        (effects (font (size 0.7 0.7) (thickness 0.15)) (justify left bottom))
    )
    (fp_text user "License: Apache-2.0" (at -1.75 6.5) (layer "F.Fab") hide
        (effects (font (size 0.7 0.7) (thickness 0.15)) (justify left bottom))
    )
    (fp_text user "${REFERENCE}" (at -1.75 3.75) (layer "F.Fab") hide
        (effects (font (size 0.7 0.7) (thickness 0.15)) (justify left bottom))
    )
    (fp_text user "Author: Antmicro" (at -1.75 5) (layer "F.Fab") hide
        (effects (font (size 0.7 0.7) (thickness 0.15)) (justify left bottom))
    )
    (fp_line (start -1.6 0.3) (end -1.6 -0.2)
      (stroke (width 0.15) (type solid)) (layer "F.SilkS"))
    (fp_line (start -0.35 -1.25) (end 0.45 -1.25)
      (stroke (width 0.15) (type solid)) (layer "F.SilkS"))
    (fp_line (start -0.35 1.25) (end 0.45 1.25)
      (stroke (width 0.15) (type solid)) (layer "F.SilkS"))
    (fp_line (start 1.6 0.3) (end 1.6 -0.2)
      (stroke (width 0.15) (type solid)) (layer "F.SilkS"))
    (fp_circle (center -1.75 1.5) (end -1.7 1.5)
      (stroke (width 0.15) (type solid)) (fill none) (layer "F.SilkS"))
    (fp_rect (start -1.907 -1.55) (end 2.006 1.649)
      (stroke (width 0.05) (type solid)) (fill none) (layer "F.CrtYd"))
    (pad "1" smd roundrect (at -1.101 0.949) (size 1.3 1.1) (layers "F.Cu" "F.Paste" "F.Mask") (roundrect_rratio 0)
      (chamfer_ratio 0.2) (chamfer bottom_left)
      (net 137 "/Debug and JTAG/XIN") (pintype "passive"))
    (pad "2" smd rect (at 1.199 0.949) (size 1.3 1.1) (layers "F.Cu" "F.Paste" "F.Mask")
      (net 1 "GND") (pinfunction "SH") (pintype "passive"))
    (pad "3" smd rect (at 1.199 -0.85) (size 1.3 1.1) (layers "F.Cu" "F.Paste" "F.Mask")
      (net 139 "/Debug and JTAG/XOUT") (pintype "passive"))
    (pad "4" smd rect (at -1.101 -0.85) (size 1.3 1.1) (layers "F.Cu" "F.Paste" "F.Mask")
      (net 1 "GND") (pinfunction "SH") (pintype "passive"))
  )

  (footprint "kria-k26-devboard-footprints:C_0402_1005Metric" (layer "F.Cu")
    (at 127.3 95.025)
    (descr "Capacitor SMD 0402")
    (tags "capacitor SMD 0402")
    (property "Author" "Antmicro")
    (property "Dielectric" "X5R")
    (property "License" "Apache-2.0")
    (property "MPN" "GRM155R61H104KE14D")
    (property "Manufacturer" "Murata")
    (property "Sheetfile" "usb.kicad_sch")
    (property "Sheetname" "USB")
    (property "Val" "100n")
    (property "Voltage" "50V")
    (property "ki_description" " ")
    (attr smd)
    (fp_text reference "C39" (at 0.76 0.375) (layer "F.SilkS")
        (effects (font (size 0.7 0.7) (thickness 0.15)) (justify left bottom))
    )
    (fp_text value "C_100n_0402" (at 0 1.4) (layer "F.Fab") hide
        (effects (font (size 0.7 0.7) (thickness 0.15)) (justify left bottom))
    )
    (fp_text user "Author: Antmicro" (at -0.932 4.17) (layer "F.Fab") hide
        (effects (font (size 0.7 0.7) (thickness 0.15)) (justify left bottom))
    )
    (fp_text user "${REFERENCE}" (at -0.932 3.168) (layer "F.Fab") hide
        (effects (font (size 0.7 0.7) (thickness 0.15)) (justify left bottom))
    )
    (fp_text user "License: Apache-2.0" (at -0.932 5.17) (layer "F.Fab") hide
        (effects (font (size 0.7 0.7) (thickness 0.15)) (justify left bottom))
    )
    (fp_rect (start -0.94 -0.47) (end 0.94 0.47)
      (stroke (width 0.05) (type solid)) (fill none) (layer "F.CrtYd"))
    (fp_rect (start -0.499 -0.249) (end 0.499 0.249)
      (stroke (width 0.15) (type solid)) (fill none) (layer "F.Fab"))
    (pad "1" smd roundrect (at -0.484 0) (size 0.59 0.64) (layers "F.Cu" "F.Paste" "F.Mask") (roundrect_rratio 0.25)
      (net 15 "PS_3V3") (pintype "passive"))
    (pad "2" smd roundrect (at 0.484 0) (size 0.59 0.64) (layers "F.Cu" "F.Paste" "F.Mask") (roundrect_rratio 0.25)
      (net 1 "GND") (pintype "passive"))
  )

  (footprint "kria-k26-devboard-footprints:VSSOP-8-1EP_3x3x1.1mm_P0.65mm" (layer "F.Cu")
    (at 140.165 73.25 180)
    (property "Author" "Antmicro")
    (property "License" "Apache-2.0")
    (property "MPN" "TPS2066TDGNRQ1")
    (property "Manufacturer" "Texas Instruments")
    (property "Sheetfile" "usb.kicad_sch")
    (property "Sheetname" "USB")
    (property "ki_description" "Power switch")
    (property "ki_keywords" "IC")
    (attr smd)
    (fp_text reference "U16" (at 1.105 -2.55 180) (layer "F.SilkS")
        (effects (font (size 0.7 0.7) (thickness 0.15)) (justify left bottom))
    )
    (fp_text value "TPS2066TDGNRQ1" (at 0 2.8 180) (layer "F.Fab") hide
        (effects (font (size 0.7 0.7) (thickness 0.15)) (justify left bottom))
    )
    (fp_text user "Author: Antmicro" (at -0.301 6.336 180) (layer "F.Fab") hide
        (effects (font (size 0.7 0.7) (thickness 0.15)) (justify left bottom))
    )
    (fp_text user "License: Apache-2.0" (at -0.301 7.336 180) (layer "F.Fab") hide
        (effects (font (size 0.7 0.7) (thickness 0.15)) (justify left bottom))
    )
    (fp_text user "${REFERENCE}" (at 0 0.4 180) (layer "F.Fab") hide
        (effects (font (size 0.7 0.7) (thickness 0.15)) (justify bottom))
    )
    (fp_poly
      (pts
        (xy -0.435 -0.511)
        (xy 0.436 -0.511)
        (xy 0.436 0.514)
        (xy -0.435 0.514)
      )

      (stroke (width 0.01) (type solid)) (fill solid) (layer "F.Paste"))
    (fp_line (start -1.55 1.55) (end 1.552 1.55)
      (stroke (width 0.15) (type solid)) (layer "F.SilkS"))
    (fp_line (start -1.5 -1.548) (end 1.552 -1.55)
      (stroke (width 0.15) (type solid)) (layer "F.SilkS"))
    (fp_circle (center -1.8 -1.4) (end -1.75 -1.35)
      (stroke (width 0.15) (type solid)) (fill solid) (layer "F.SilkS"))
    (fp_rect (start -2.95 -1.75) (end 2.95 1.75)
      (stroke (width 0.05) (type solid)) (fill none) (layer "F.CrtYd"))
    (fp_line (start -1.55 -0.948) (end -1.55 1.55)
      (stroke (width 0.15) (type solid)) (layer "F.Fab"))
    (fp_line (start -1.55 -0.948) (end -0.949 -1.55)
      (stroke (width 0.15) (type solid)) (layer "F.Fab"))
    (fp_line (start -1.55 1.55) (end 1.552 1.55)
      (stroke (width 0.15) (type solid)) (layer "F.Fab"))
    (fp_line (start -0.949 -1.55) (end 1.552 -1.55)
      (stroke (width 0.15) (type solid)) (layer "F.Fab"))
    (fp_line (start 1.552 -1.55) (end 1.552 1.55)
      (stroke (width 0.15) (type solid)) (layer "F.Fab"))
    (pad "1" smd roundrect (at -2.148 -0.973 180) (size 1.47 0.5) (layers "F.Cu" "F.Paste" "F.Mask") (roundrect_rratio 0.25)
      (net 1 "GND") (pinfunction "GND") (pintype "power_in"))
    (pad "2" smd roundrect (at -2.148 -0.324 180) (size 1.47 0.5) (layers "F.Cu" "F.Paste" "F.Mask") (roundrect_rratio 0.25)
      (net 306 "USB_5V") (pinfunction "IN") (pintype "power_in"))
    (pad "3" smd roundrect (at -2.148 0.327 180) (size 1.47 0.5) (layers "F.Cu" "F.Paste" "F.Mask") (roundrect_rratio 0.25)
      (net 302 "/USB/USB_PRT_CTL1") (pinfunction "EN1") (pintype "input"))
    (pad "4" smd roundrect (at -2.148 0.976 180) (size 1.47 0.5) (layers "F.Cu" "F.Paste" "F.Mask") (roundrect_rratio 0.25)
      (net 303 "/USB/USB_PRT_CTL2") (pinfunction "EN2") (pintype "input"))
    (pad "5" smd roundrect (at 2.151 0.976 180) (size 1.47 0.5) (layers "F.Cu" "F.Paste" "F.Mask") (roundrect_rratio 0.25)
      (net 303 "/USB/USB_PRT_CTL2") (pinfunction "~{OC2}") (pintype "output"))
    (pad "6" smd roundrect (at 2.151 0.327 180) (size 1.47 0.5) (layers "F.Cu" "F.Paste" "F.Mask") (roundrect_rratio 0.25)
      (net 85 "/USB/USB2_VBUS") (pinfunction "OUT2") (pintype "output"))
    (pad "7" smd roundrect (at 2.151 -0.324 180) (size 1.47 0.5) (layers "F.Cu" "F.Paste" "F.Mask") (roundrect_rratio 0.25)
      (net 64 "/USB/USB1_VBUS") (pinfunction "OUT1") (pintype "output"))
    (pad "8" smd roundrect (at 2.151 -0.973 180) (size 1.47 0.5) (layers "F.Cu" "F.Paste" "F.Mask") (roundrect_rratio 0.25)
      (net 302 "/USB/USB_PRT_CTL1") (pinfunction "~{OC1}") (pintype "output"))
    (pad "9" smd rect (at 0 0 180) (size 1.746 2.05) (layers "F.Cu" "F.Mask")
      (net 1 "GND") (pinfunction "EP") (pintype "passive"))
  )

  (footprint "kria-k26-devboard-footprints:VSSOP-8-1EP_3x3x1.1mm_P0.65mm" (layer "F.Cu")
    (at 120.32 74.1 180)
    (property "Author" "Antmicro")
    (property "License" "Apache-2.0")
    (property "MPN" "TPS2066TDGNRQ1")
    (property "Manufacturer" "Texas Instruments")
    (property "Sheetfile" "usb.kicad_sch")
    (property "Sheetname" "USB")
    (property "ki_description" "Power switch")
    (property "ki_keywords" "IC")
    (attr smd)
    (fp_text reference "U18" (at 1.38 1.78 180) (layer "F.SilkS")
        (effects (font (size 0.7 0.7) (thickness 0.15)) (justify left bottom))
    )
    (fp_text value "TPS2066TDGNRQ1" (at 0 2.8 180) (layer "F.Fab") hide
        (effects (font (size 0.7 0.7) (thickness 0.15)) (justify left bottom))
    )
    (fp_text user "${REFERENCE}" (at 0 0.4 180) (layer "F.Fab") hide
        (effects (font (size 0.7 0.7) (thickness 0.15)) (justify bottom))
    )
    (fp_text user "Author: Antmicro" (at -0.301 6.336 180) (layer "F.Fab") hide
        (effects (font (size 0.7 0.7) (thickness 0.15)) (justify left bottom))
    )
    (fp_text user "License: Apache-2.0" (at -0.301 7.336 180) (layer "F.Fab") hide
        (effects (font (size 0.7 0.7) (thickness 0.15)) (justify left bottom))
    )
    (fp_poly
      (pts
        (xy -0.435 -0.511)
        (xy 0.436 -0.511)
        (xy 0.436 0.514)
        (xy -0.435 0.514)
      )

      (stroke (width 0.01) (type solid)) (fill solid) (layer "F.Paste"))
    (fp_line (start -1.55 1.55) (end 1.552 1.55)
      (stroke (width 0.15) (type solid)) (layer "F.SilkS"))
    (fp_line (start -1.5 -1.548) (end 1.552 -1.55)
      (stroke (width 0.15) (type solid)) (layer "F.SilkS"))
    (fp_circle (center -1.8 -1.4) (end -1.75 -1.35)
      (stroke (width 0.15) (type solid)) (fill solid) (layer "F.SilkS"))
    (fp_rect (start -2.95 -1.75) (end 2.95 1.75)
      (stroke (width 0.05) (type solid)) (fill none) (layer "F.CrtYd"))
    (fp_line (start -1.55 -0.948) (end -1.55 1.55)
      (stroke (width 0.15) (type solid)) (layer "F.Fab"))
    (fp_line (start -1.55 -0.948) (end -0.949 -1.55)
      (stroke (width 0.15) (type solid)) (layer "F.Fab"))
    (fp_line (start -1.55 1.55) (end 1.552 1.55)
      (stroke (width 0.15) (type solid)) (layer "F.Fab"))
    (fp_line (start -0.949 -1.55) (end 1.552 -1.55)
      (stroke (width 0.15) (type solid)) (layer "F.Fab"))
    (fp_line (start 1.552 -1.55) (end 1.552 1.55)
      (stroke (width 0.15) (type solid)) (layer "F.Fab"))
    (pad "1" smd roundrect (at -2.148 -0.973 180) (size 1.47 0.5) (layers "F.Cu" "F.Paste" "F.Mask") (roundrect_rratio 0.25)
      (net 1 "GND") (pinfunction "GND") (pintype "power_in"))
    (pad "2" smd roundrect (at -2.148 -0.324 180) (size 1.47 0.5) (layers "F.Cu" "F.Paste" "F.Mask") (roundrect_rratio 0.25)
      (net 306 "USB_5V") (pinfunction "IN") (pintype "power_in"))
    (pad "3" smd roundrect (at -2.148 0.327 180) (size 1.47 0.5) (layers "F.Cu" "F.Paste" "F.Mask") (roundrect_rratio 0.25)
      (net 304 "/USB/USB_PRT_CTL3") (pinfunction "EN1") (pintype "input"))
    (pad "4" smd roundrect (at -2.148 0.976 180) (size 1.47 0.5) (layers "F.Cu" "F.Paste" "F.Mask") (roundrect_rratio 0.25)
      (net 305 "/USB/USB_PRT_CTL4") (pinfunction "EN2") (pintype "input"))
    (pad "5" smd roundrect (at 2.151 0.976 180) (size 1.47 0.5) (layers "F.Cu" "F.Paste" "F.Mask") (roundrect_rratio 0.25)
      (net 305 "/USB/USB_PRT_CTL4") (pinfunction "~{OC2}") (pintype "output"))
    (pad "6" smd roundrect (at 2.151 0.327 180) (size 1.47 0.5) (layers "F.Cu" "F.Paste" "F.Mask") (roundrect_rratio 0.25)
      (net 87 "/USB/USB4_VBUS") (pinfunction "OUT2") (pintype "output"))
    (pad "7" smd roundrect (at 2.151 -0.324 180) (size 1.47 0.5) (layers "F.Cu" "F.Paste" "F.Mask") (roundrect_rratio 0.25)
      (net 86 "/USB/USB3_VBUS") (pinfunction "OUT1") (pintype "output"))
    (pad "8" smd roundrect (at 2.151 -0.973 180) (size 1.47 0.5) (layers "F.Cu" "F.Paste" "F.Mask") (roundrect_rratio 0.25)
      (net 304 "/USB/USB_PRT_CTL3") (pinfunction "~{OC1}") (pintype "output"))
    (pad "9" smd rect (at 0 0 180) (size 1.746 2.05) (layers "F.Cu" "F.Mask")
      (net 1 "GND") (pinfunction "EP") (pintype "passive"))
  )

  (footprint "kria-k26-devboard-footprints:Oscillator_SMD_ECS_2016MV_2x1.6x0.85mm" (layer "F.Cu")
    (at 127.042501 97.4475 -90)
    (property "Author" "Antmicro")
    (property "License" "Apache-2.0")
    (property "MPN" "ECS-2016MV-240-CN-TR")
    (property "Manufacturer" "ECS Inc. International")
    (property "Sheetfile" "usb.kicad_sch")
    (property "Sheetname" "USB")
    (property "Val" "24 MHz")
    (property "ki_description" "Oscillator, 24 MHz XO (Standard) CMOS 1.6V ~ 3.6V Enable/Disable 4-SMD, No Lead")
    (property "ki_keywords" "OSCILLATOR")
    (attr smd)
    (fp_text reference "Y5" (at 1.4725 -1.217499 180) (layer "F.SilkS")
        (effects (font (size 0.7 0.7) (thickness 0.15)) (justify left bottom))
    )
    (fp_text value "Oscillator_24MHz_ESC_2016MV" (at 0 2.2 -90) (layer "F.Fab") hide
        (effects (font (size 0.7 0.7) (thickness 0.15)) (justify left bottom))
    )
    (fp_text user "License: Apache-2.0" (at -1.05 5.8 -90) (layer "F.Fab") hide
        (effects (font (size 0.7 0.7) (thickness 0.15)) (justify left bottom))
    )
    (fp_text user "Author: Antmicro" (at -1.05 4.6 -90) (layer "F.Fab") hide
        (effects (font (size 0.7 0.7) (thickness 0.15)) (justify left bottom))
    )
    (fp_text user "${REFERENCE}" (at -1.05 3.4 -90) (layer "F.Fab") hide
        (effects (font (size 0.7 0.7) (thickness 0.15)) (justify left bottom))
    )
    (fp_line (start -0.95 0.4) (end -0.95 -0.4)
      (stroke (width 0.15) (type solid)) (layer "F.SilkS"))
    (fp_line (start -0.4 -1.15) (end 0.4 -1.15)
      (stroke (width 0.15) (type solid)) (layer "F.SilkS"))
    (fp_line (start -0.4 1.15) (end 0.4 1.15)
      (stroke (width 0.15) (type solid)) (layer "F.SilkS"))
    (fp_line (start 0.95 0.4) (end 0.95 -0.4)
      (stroke (width 0.15) (type solid)) (layer "F.SilkS"))
    (fp_circle (center -0.95 -1.15) (end -0.9 -1.15)
      (stroke (width 0.15) (type solid)) (fill solid) (layer "F.SilkS"))
    (fp_rect (start -1.05 -1.25) (end 1.05 1.24)
      (stroke (width 0.05) (type solid)) (fill none) (layer "F.CrtYd"))
    (fp_rect (start -0.85 -1.054) (end 0.852 1.054)
      (stroke (width 0.15) (type solid)) (fill none) (layer "F.Fab"))
    (pad "1" smd rect (at -0.486 -0.637 270) (size 0.6858 0.7874) (layers "F.Cu" "F.Paste" "F.Mask")
      (net 802 "unconnected-(Y5-EN-Pad1)") (pinfunction "EN") (pintype "input+no_connect"))
    (pad "2" smd rect (at -0.486 0.636 270) (size 0.6858 0.7874) (layers "F.Cu" "F.Paste" "F.Mask")
      (net 1 "GND") (pinfunction "GND") (pintype "power_in"))
    (pad "3" smd rect (at 0.487 0.636 270) (size 0.6858 0.7874) (layers "F.Cu" "F.Paste" "F.Mask")
      (net 277 "/USB/USB2_REFCLK") (pinfunction "OUT") (pintype "output"))
    (pad "4" smd rect (at 0.487 -0.637 270) (size 0.6858 0.7874) (layers "F.Cu" "F.Paste" "F.Mask")
      (net 17 "PS_1V8") (pinfunction "VDD") (pintype "power_in"))
  )

  (footprint "kria-k26-devboard-footprints:C_0402_1005Metric" (layer "F.Cu")
    (at 110.675 75.145 90)
    (descr "Capacitor SMD 0402")
    (tags "capacitor SMD 0402")
    (property "Author" "Antmicro")
    (property "Dielectric" "X5R")
    (property "License" "Apache-2.0")
    (property "MPN" "GRM155R61H104KE14D")
    (property "Manufacturer" "Murata")
    (property "Sheetfile" "usb.kicad_sch")
    (property "Sheetname" "USB")
    (property "Val" "100n")
    (property "Voltage" "50V")
    (property "ki_description" " ")
    (attr smd)
    (fp_text reference "C76" (at -3.055 0.385 90) (layer "F.SilkS")
        (effects (font (size 0.7 0.7) (thickness 0.15)) (justify left bottom))
    )
    (fp_text value "C_100n_0402" (at 0 1.4 90) (layer "F.Fab") hide
        (effects (font (size 0.7 0.7) (thickness 0.15)) (justify left bottom))
    )
    (fp_text user "${REFERENCE}" (at -0.932 3.168 90) (layer "F.Fab") hide
        (effects (font (size 0.7 0.7) (thickness 0.15)) (justify left bottom))
    )
    (fp_text user "License: Apache-2.0" (at -0.932 5.17 90) (layer "F.Fab") hide
        (effects (font (size 0.7 0.7) (thickness 0.15)) (justify left bottom))
    )
    (fp_text user "Author: Antmicro" (at -0.932 4.17 90) (layer "F.Fab") hide
        (effects (font (size 0.7 0.7) (thickness 0.15)) (justify left bottom))
    )
    (fp_rect (start -0.94 -0.47) (end 0.94 0.47)
      (stroke (width 0.05) (type solid)) (fill none) (layer "F.CrtYd"))
    (fp_rect (start -0.499 -0.249) (end 0.499 0.249)
      (stroke (width 0.15) (type solid)) (fill none) (layer "F.Fab"))
    (pad "1" smd roundrect (at -0.484 0 90) (size 0.59 0.64) (layers "F.Cu" "F.Paste" "F.Mask") (roundrect_rratio 0.25)
      (net 75 "/USB/USB4_TX_N") (pintype "passive"))
    (pad "2" smd roundrect (at 0.484 0 90) (size 0.59 0.64) (layers "F.Cu" "F.Paste" "F.Mask") (roundrect_rratio 0.25)
      (net 284 "/USB/USB4_TX_C_N") (pintype "passive"))
  )

  (footprint "kria-k26-devboard-footprints:C_0402_1005Metric" (layer "F.Cu")
    (at 123.65 92.91 90)
    (descr "Capacitor SMD 0402")
    (tags "capacitor SMD 0402")
    (property "Author" "Antmicro")
    (property "Dielectric" "X5R")
    (property "License" "Apache-2.0")
    (property "MPN" "GRM155R61H104KE14D")
    (property "Manufacturer" "Murata")
    (property "Sheetfile" "usb.kicad_sch")
    (property "Sheetname" "USB")
    (property "Val" "100n")
    (property "Voltage" "50V")
    (property "ki_description" " ")
    (attr smd)
    (fp_text reference "C53" (at -1.94 -3.25 90) (layer "F.SilkS")
        (effects (font (size 0.7 0.7) (thickness 0.15)) (justify left bottom))
    )
    (fp_text value "C_100n_0402" (at 0 1.4 90) (layer "F.Fab") hide
        (effects (font (size 0.7 0.7) (thickness 0.15)) (justify left bottom))
    )
    (fp_text user "${REFERENCE}" (at -0.932 3.168 90) (layer "F.Fab") hide
        (effects (font (size 0.7 0.7) (thickness 0.15)) (justify left bottom))
    )
    (fp_text user "License: Apache-2.0" (at -0.932 5.17 90) (layer "F.Fab") hide
        (effects (font (size 0.7 0.7) (thickness 0.15)) (justify left bottom))
    )
    (fp_text user "Author: Antmicro" (at -0.932 4.17 90) (layer "F.Fab") hide
        (effects (font (size 0.7 0.7) (thickness 0.15)) (justify left bottom))
    )
    (fp_rect (start -0.94 -0.47) (end 0.94 0.47)
      (stroke (width 0.05) (type solid)) (fill none) (layer "F.CrtYd"))
    (fp_rect (start -0.499 -0.249) (end 0.499 0.249)
      (stroke (width 0.15) (type solid)) (fill none) (layer "F.Fab"))
    (pad "1" smd roundrect (at -0.484 0 90) (size 0.59 0.64) (layers "F.Cu" "F.Paste" "F.Mask") (roundrect_rratio 0.25)
      (net 57 "/USB/GTR_DP2_C2M_N") (pintype "passive"))
    (pad "2" smd roundrect (at 0.484 0 90) (size 0.59 0.64) (layers "F.Cu" "F.Paste" "F.Mask") (roundrect_rratio 0.25)
      (net 53 "/USB/GTR_DP2_C2M_C_N") (pintype "passive"))
  )

  (footprint "kria-k26-devboard-footprints:C_0402_1005Metric" (layer "F.Cu")
    (at 129.95 78.8)
    (descr "Capacitor SMD 0402")
    (tags "capacitor SMD 0402")
    (property "Author" "Antmicro")
    (property "Dielectric" "X5R")
    (property "License" "Apache-2.0")
    (property "MPN" "GRM155R61H104KE14D")
    (property "Manufacturer" "Murata")
    (property "Sheetfile" "usb.kicad_sch")
    (property "Sheetname" "USB")
    (property "Val" "100n")
    (property "Voltage" "50V")
    (property "ki_description" " ")
    (attr smd)
    (fp_text reference "C46" (at 0.84 0.37) (layer "F.SilkS")
        (effects (font (size 0.7 0.7) (thickness 0.15)) (justify left bottom))
    )
    (fp_text value "C_100n_0402" (at 0 1.4) (layer "F.Fab") hide
        (effects (font (size 0.7 0.7) (thickness 0.15)) (justify left bottom))
    )
    (fp_text user "${REFERENCE}" (at -0.932 3.168) (layer "F.Fab") hide
        (effects (font (size 0.7 0.7) (thickness 0.15)) (justify left bottom))
    )
    (fp_text user "License: Apache-2.0" (at -0.932 5.17) (layer "F.Fab") hide
        (effects (font (size 0.7 0.7) (thickness 0.15)) (justify left bottom))
    )
    (fp_text user "Author: Antmicro" (at -0.932 4.17) (layer "F.Fab") hide
        (effects (font (size 0.7 0.7) (thickness 0.15)) (justify left bottom))
    )
    (fp_rect (start -0.94 -0.47) (end 0.94 0.47)
      (stroke (width 0.05) (type solid)) (fill none) (layer "F.CrtYd"))
    (fp_rect (start -0.499 -0.249) (end 0.499 0.249)
      (stroke (width 0.15) (type solid)) (fill none) (layer "F.Fab"))
    (pad "1" smd roundrect (at -0.484 0) (size 0.59 0.64) (layers "F.Cu" "F.Paste" "F.Mask") (roundrect_rratio 0.25)
      (net 15 "PS_3V3") (pintype "passive"))
    (pad "2" smd roundrect (at 0.484 0) (size 0.59 0.64) (layers "F.Cu" "F.Paste" "F.Mask") (roundrect_rratio 0.25)
      (net 1 "GND") (pintype "passive"))
  )

  (footprint "kria-k26-devboard-footprints:C_0402_1005Metric" (layer "F.Cu")
    (at 122.701223 92.91 90)
    (descr "Capacitor SMD 0402")
    (tags "capacitor SMD 0402")
    (property "Author" "Antmicro")
    (property "Dielectric" "X5R")
    (property "License" "Apache-2.0")
    (property "MPN" "GRM155R61H104KE14D")
    (property "Manufacturer" "Murata")
    (property "Sheetfile" "usb.kicad_sch")
    (property "Sheetname" "USB")
    (property "Val" "100n")
    (property "Voltage" "50V")
    (property "ki_description" " ")
    (attr smd)
    (fp_text reference "C52" (at -1.94 -3.25 90) (layer "F.SilkS")
        (effects (font (size 0.7 0.7) (thickness 0.15)) (justify left bottom))
    )
    (fp_text value "C_100n_0402" (at 0 1.4 90) (layer "F.Fab") hide
        (effects (font (size 0.7 0.7) (thickness 0.15)) (justify left bottom))
    )
    (fp_text user "License: Apache-2.0" (at -0.932 5.17 90) (layer "F.Fab") hide
        (effects (font (size 0.7 0.7) (thickness 0.15)) (justify left bottom))
    )
    (fp_text user "Author: Antmicro" (at -0.932 4.17 90) (layer "F.Fab") hide
        (effects (font (size 0.7 0.7) (thickness 0.15)) (justify left bottom))
    )
    (fp_text user "${REFERENCE}" (at -0.932 3.168 90) (layer "F.Fab") hide
        (effects (font (size 0.7 0.7) (thickness 0.15)) (justify left bottom))
    )
    (fp_rect (start -0.94 -0.47) (end 0.94 0.47)
      (stroke (width 0.05) (type solid)) (fill none) (layer "F.CrtYd"))
    (fp_rect (start -0.499 -0.249) (end 0.499 0.249)
      (stroke (width 0.15) (type solid)) (fill none) (layer "F.Fab"))
    (pad "1" smd roundrect (at -0.484 0 90) (size 0.59 0.64) (layers "F.Cu" "F.Paste" "F.Mask") (roundrect_rratio 0.25)
      (net 56 "/USB/GTR_DP2_C2M_P") (pintype "passive"))
    (pad "2" smd roundrect (at 0.484 0 90) (size 0.59 0.64) (layers "F.Cu" "F.Paste" "F.Mask") (roundrect_rratio 0.25)
      (net 52 "/USB/GTR_DP2_C2M_C_P") (pintype "passive"))
  )

  (footprint "kria-k26-devboard-footprints:C_0402_1005Metric" (layer "F.Cu")
    (at 111.625 75.145 90)
    (descr "Capacitor SMD 0402")
    (tags "capacitor SMD 0402")
    (property "Author" "Antmicro")
    (property "Dielectric" "X5R")
    (property "License" "Apache-2.0")
    (property "MPN" "GRM155R61H104KE14D")
    (property "Manufacturer" "Murata")
    (property "Sheetfile" "usb.kicad_sch")
    (property "Sheetname" "USB")
    (property "Val" "100n")
    (property "Voltage" "50V")
    (property "ki_description" " ")
    (attr smd)
    (fp_text reference "C77" (at -3.055 0.385 90) (layer "F.SilkS")
        (effects (font (size 0.7 0.7) (thickness 0.15)) (justify left bottom))
    )
    (fp_text value "C_100n_0402" (at 0 1.4 90) (layer "F.Fab") hide
        (effects (font (size 0.7 0.7) (thickness 0.15)) (justify left bottom))
    )
    (fp_text user "License: Apache-2.0" (at -0.932 5.17 90) (layer "F.Fab") hide
        (effects (font (size 0.7 0.7) (thickness 0.15)) (justify left bottom))
    )
    (fp_text user "Author: Antmicro" (at -0.932 4.17 90) (layer "F.Fab") hide
        (effects (font (size 0.7 0.7) (thickness 0.15)) (justify left bottom))
    )
    (fp_text user "${REFERENCE}" (at -0.932 3.168 90) (layer "F.Fab") hide
        (effects (font (size 0.7 0.7) (thickness 0.15)) (justify left bottom))
    )
    (fp_rect (start -0.94 -0.47) (end 0.94 0.47)
      (stroke (width 0.05) (type solid)) (fill none) (layer "F.CrtYd"))
    (fp_rect (start -0.499 -0.249) (end 0.499 0.249)
      (stroke (width 0.15) (type solid)) (fill none) (layer "F.Fab"))
    (pad "1" smd roundrect (at -0.484 0 90) (size 0.59 0.64) (layers "F.Cu" "F.Paste" "F.Mask") (roundrect_rratio 0.25)
      (net 76 "/USB/USB4_TX_P") (pintype "passive"))
    (pad "2" smd roundrect (at 0.484 0 90) (size 0.59 0.64) (layers "F.Cu" "F.Paste" "F.Mask") (roundrect_rratio 0.25)
      (net 285 "/USB/USB4_TX_C_P") (pintype "passive"))
  )

  (footprint "kria-k26-devboard-footprints:RJ45_5-2337992-8_Horizontal" (layer "F.Cu")
    (at 169.69555 71.7845 180)
    (property "Author" "Antmicro")
    (property "License" "Apache-2.0")
    (property "MPN" "5-2337992-8")
    (property "Manufacturer" "TE Connectivity")
    (property "Sheetfile" "eth.kicad_sch")
    (property "Sheetname" "Ethernet")
    (property "VSD_Class" "Ethernet")
    (property "ki_description" "Modular Connector, RJ45 Jack, 1 x 1 (Port), 8P8C, Cat5e, Through Hole Mount")
    (property "ki_keywords" "RJ45, HORIZONTAL, THT, ETHERNET, CONNECTOR, FEMALE")
    (attr through_hole)
    (fp_text reference "J5" (at -1.76445 -2.7955) (layer "F.SilkS")
        (effects (font (size 0.7 0.7) (thickness 0.15)) (justify right bottom))
    )
    (fp_text value "Bus_RJ45_5-2337992-8" (at -2.6 22) (layer "F.Fab") hide
        (effects (font (size 0.7 0.7) (thickness 0.15)) (justify right bottom))
    )
    (fp_text user "License: Apache-2.0" (at -2.644 26.2) (layer "F.Fab") hide
        (effects (font (size 0.7 0.7) (thickness 0.15)) (justify right bottom))
    )
    (fp_text user "Author: Antmicro" (at -2.644 24.8) (layer "F.Fab") hide
        (effects (font (size 0.7 0.7) (thickness 0.15)) (justify right bottom))
    )
    (fp_text user "${REFERENCE}" (at -2.644 23.4) (layer "F.Fab") hide
        (effects (font (size 0.7 0.7) (thickness 0.15)) (justify right bottom))
    )
    (fp_line (start -2.363 -1.845) (end -2.363 4.48)
      (stroke (width 0.15) (type solid)) (layer "F.SilkS"))
    (fp_line (start -2.363 7.217) (end -2.363 19.771)
      (stroke (width 0.15) (type solid)) (layer "F.SilkS"))
    (fp_line (start -2.363 19.771) (end 13.791 19.771)
      (stroke (width 0.15) (type solid)) (layer "F.SilkS"))
    (fp_line (start 13.791 -1.845) (end -2.363 -1.845)
      (stroke (width 0.15) (type solid)) (layer "F.SilkS"))
    (fp_line (start 13.791 4.48) (end 13.791 -1.845)
      (stroke (width 0.15) (type solid)) (layer "F.SilkS"))
    (fp_line (start 13.791 19.771) (end 13.791 7.217)
      (stroke (width 0.15) (type solid)) (layer "F.SilkS"))
    (fp_rect (start -2.4 -1.8) (end 13.9 19.999)
      (stroke (width 0.05) (type solid)) (fill none) (layer "F.CrtYd"))
    (fp_line (start -2.237 -1.718) (end -2.237 19.644)
      (stroke (width 0.15) (type solid)) (layer "F.Fab"))
    (fp_line (start -2.237 19.644) (end 13.665 19.644)
      (stroke (width 0.15) (type solid)) (layer "F.Fab"))
    (fp_line (start 13.665 -1.718) (end -2.237 -1.718)
      (stroke (width 0.15) (type solid)) (layer "F.Fab"))
    (fp_line (start 13.665 19.644) (end 13.665 -1.718)
      (stroke (width 0.15) (type solid)) (layer "F.Fab"))
    (pad "" np_thru_hole circle (at 0 8.9 180) (size 3.25 3.25) (drill 3.25) (layers "*.Cu" "*.Mask"))
    (pad "" np_thru_hole circle (at 11.429 8.9 180) (size 3.25 3.25) (drill 3.25) (layers "*.Cu" "*.Mask"))
    (pad "1" thru_hole circle (at 0 0 180) (size 1.397 1.397) (drill 0.889) (layers "*.Cu" "*.Mask")
      (net 267 "/Ethernet/TD_A_P") (pinfunction "P1") (pintype "bidirectional"))
    (pad "2" thru_hole circle (at 1.269 2.539 180) (size 1.397 1.397) (drill 0.889) (layers "*.Cu" "*.Mask")
      (net 268 "/Ethernet/TD_A_N") (pinfunction "P2") (pintype "bidirectional"))
    (pad "3" thru_hole circle (at 2.539 0 180) (size 1.397 1.397) (drill 0.889) (layers "*.Cu" "*.Mask")
      (net 269 "/Ethernet/TD_B_P") (pinfunction "P3") (pintype "bidirectional"))
    (pad "4" thru_hole circle (at 3.809 2.539 180) (size 1.397 1.397) (drill 0.889) (layers "*.Cu" "*.Mask")
      (net 332 "Net-(J5-P4)") (pinfunction "P4") (pintype "bidirectional"))
    (pad "5" thru_hole circle (at 5.078 0 180) (size 1.397 1.397) (drill 0.889) (layers "*.Cu" "*.Mask")
      (net 333 "Net-(J5-P5)") (pinfunction "P5") (pintype "bidirectional"))
    (pad "6" thru_hole circle (at 6.349 2.539 180) (size 1.397 1.397) (drill 0.889) (layers "*.Cu" "*.Mask")
      (net 270 "/Ethernet/TD_B_N") (pinfunction "P6") (pintype "bidirectional"))
    (pad "7" thru_hole circle (at 7.618 0 180) (size 1.397 1.397) (drill 0.889) (layers "*.Cu" "*.Mask")
      (net 271 "/Ethernet/TD_C_P") (pinfunction "P7") (pintype "bidirectional"))
    (pad "8" thru_hole circle (at 8.89 2.539 180) (size 1.397 1.397) (drill 0.889) (layers "*.Cu" "*.Mask")
      (net 272 "/Ethernet/TD_C_N") (pinfunction "P8") (pintype "bidirectional"))
    (pad "9" thru_hole circle (at 10.159 0 180) (size 1.397 1.397) (drill 0.889) (layers "*.Cu" "*.Mask")
      (net 273 "/Ethernet/TD_D_P") (pinfunction "P9") (pintype "bidirectional"))
    (pad "10" thru_hole circle (at 11.429 2.539 180) (size 1.397 1.397) (drill 0.889) (layers "*.Cu" "*.Mask")
      (net 274 "/Ethernet/TD_D_N") (pinfunction "P10") (pintype "bidirectional"))
    (pad "11" thru_hole circle (at 0 5.078 180) (size 1.397 1.397) (drill 0.889) (layers "*.Cu" "*.Mask")
      (net 236 "/Ethernet/POE_VC1") (pinfunction "VC1") (pintype "bidirectional"))
    (pad "12" thru_hole circle (at 2.539 6.339 180) (size 1.397 1.397) (drill 0.889) (layers "*.Cu" "*.Mask")
      (net 235 "/Ethernet/POE_VC2") (pinfunction "VC2") (pintype "bidirectional"))
    (pad "13" thru_hole circle (at 8.89 6.339 180) (size 1.397 1.397) (drill 0.889) (layers "*.Cu" "*.Mask")
      (net 238 "/Ethernet/POE_VC3") (pinfunction "VC3") (pintype "bidirectional"))
    (pad "14" thru_hole circle (at 11.429 5.07 180) (size 1.397 1.397) (drill 0.889) (layers "*.Cu" "*.Mask")
      (net 237 "/Ethernet/POE_VC4") (pinfunction "VC4") (pintype "bidirectional"))
    (pad "15" thru_hole circle (at -0.927 12.958 180) (size 1.524 1.524) (drill 1.016) (layers "*.Cu" "*.Mask")
      (net 350 "Net-(J5-LED_GRN+)") (pinfunction "LED_GRN+") (pintype "passive"))
    (pad "16" thru_hole circle (at 1.614 12.958 180) (size 1.524 1.524) (drill 1.016) (layers "*.Cu" "*.Mask")
      (net 351 "Net-(J5-LED_GRN-)") (pinfunction "LED_GRN-") (pintype "passive"))
    (pad "17" thru_hole circle (at 9.814 12.958 180) (size 1.524 1.524) (drill 1.016) (layers "*.Cu" "*.Mask")
      (net 352 "Net-(J5-LED_YEL+)") (pinfunction "LED_YEL+") (pintype "passive"))
    (pad "18" thru_hole circle (at 12.355 12.958 180) (size 1.524 1.524) (drill 1.016) (layers "*.Cu" "*.Mask")
      (net 353 "Net-(J5-LED_YEL-)") (pinfunction "LED_YEL-") (pintype "passive"))
    (pad "19" thru_hole circle (at -2.136 5.85 180) (size 2.1 2.1) (drill 1.6) (layers "*.Cu" "*.Mask")
      (net 319 "SH_UP") (pinfunction "SHIELD") (pintype "passive"))
    (pad "20" thru_hole circle (at 13.563 5.85 180) (size 2.1082 2.1082) (drill 1.6002) (layers "*.Cu" "*.Mask")
      (net 319 "SH_UP") (pinfunction "SHIELD") (pintype "passive"))
  )

  (footprint "kria-k26-devboard-footprints:R_0402_1005Metric" (layer "F.Cu")
    (at 175.45 132.05 90)
    (descr "Resistor SMD 0402")
    (tags "resistor SMD 0402")
    (property "Author" "Antmicro")
    (property "License" "Apache-2.0")
    (property "MPN" "CR0402-FX-3162GLF")
    (property "Manufacturer" "Bourns")
    (property "Sheetfile" "dc-dc-conventers.kicad_sch")
    (property "Sheetname" "DC/DC conventers")
    (property "Tolerance" "1%")
    (property "Val" "31k6")
    (property "ki_description" "31k6 resistor in 0402 package with 1% tolerance")
    (attr smd)
    (fp_text reference "R144" (at 0.85 -1.62 180) (layer "F.SilkS")
        (effects (font (size 0.7 0.7) (thickness 0.15)) (justify left bottom))
    )
    (fp_text value "R_31k6_0402" (at 0 1.4 90) (layer "F.Fab") hide
        (effects (font (size 0.7 0.7) (thickness 0.15)) (justify left bottom))
    )
    (fp_text user "${REFERENCE}" (at -0.95 3.168 90) (layer "F.Fab") hide
        (effects (font (size 0.7 0.7) (thickness 0.15)) (justify left bottom))
    )
    (fp_text user "Author: Antmicro" (at -0.95 4.169 90) (layer "F.Fab") hide
        (effects (font (size 0.7 0.7) (thickness 0.15)) (justify left bottom))
    )
    (fp_text user "License: Apache-2.0" (at -0.95 5.169 90) (layer "F.Fab") hide
        (effects (font (size 0.7 0.7) (thickness 0.15)) (justify left bottom))
    )
    (fp_rect (start -0.93 -0.47) (end 0.93 0.47)
      (stroke (width 0.05) (type solid)) (fill none) (layer "F.CrtYd"))
    (fp_rect (start -0.5 -0.25) (end 0.5 0.25)
      (stroke (width 0.15) (type solid)) (fill none) (layer "F.Fab"))
    (pad "1" smd roundrect (at -0.485 0 90) (size 0.59 0.64) (layers "F.Cu" "F.Paste" "F.Mask") (roundrect_rratio 0.25)
      (net 770 "/Power Supply/DC/DC conventers/PL_3V3_OUT") (pintype "passive"))
    (pad "2" smd roundrect (at 0.485 0 90) (size 0.59 0.64) (layers "F.Cu" "F.Paste" "F.Mask") (roundrect_rratio 0.25)
      (net 693 "Net-(U54-FB)") (pintype "passive"))
  )

  (footprint "kria-k26-devboard-footprints:C_2220_5650Metric" (layer "F.Cu")
    (at 165.06 82.94 90)
    (descr "Capacitor SMD 2220")
    (tags "capacitor SMD 2220")
    (property "Author" "Antmicro")
    (property "Dielectric" "")
    (property "License" "Apache-2.0")
    (property "MPN" "C5750X7S2A226M280KB")
    (property "Manufacturer" "TDK")
    (property "Sheetfile" "PoE.kicad_sch")
    (property "Sheetname" "PoE")
    (property "Val" "22u/100V")
    (property "Voltage" "")
    (property "ki_description" " ")
    (attr smd)
    (fp_text reference "C172" (at -1.41 -5.93 90) (layer "F.SilkS")
        (effects (font (size 0.7 0.7) (thickness 0.15)) (justify left bottom))
    )
    (fp_text value "C_22u_100V_2220" (at 0 3.9 90) (layer "F.Fab") hide
        (effects (font (size 0.7 0.7) (thickness 0.15)) (justify left bottom))
    )
    (fp_text user "Author: Antmicro" (at -3.7 7.9 90) (layer "F.Fab") hide
        (effects (font (size 0.7 0.7) (thickness 0.15)) (justify left bottom))
    )
    (fp_text user "${REFERENCE}" (at -3.7 5.9 90) (layer "F.Fab") hide
        (effects (font (size 0.7 0.7) (thickness 0.15)) (justify left bottom))
    )
    (fp_text user "License: Apache-2.0" (at -3.7 6.9 90) (layer "F.Fab") hide
        (effects (font (size 0.7 0.7) (thickness 0.15)) (justify left bottom))
    )
    (fp_line (start -1.415 -2.61) (end 1.415 -2.61)
      (stroke (width 0.15) (type solid)) (layer "F.SilkS"))
    (fp_line (start -1.415 2.61) (end 1.415 2.61)
      (stroke (width 0.15) (type solid)) (layer "F.SilkS"))
    (fp_rect (start -3.7 -2.95) (end 3.7 2.95)
      (stroke (width 0.05) (type solid)) (fill none) (layer "F.CrtYd"))
    (fp_rect (start -2.85 -2.5) (end 2.85 2.5)
      (stroke (width 0.15) (type solid)) (fill none) (layer "F.Fab"))
    (pad "1" smd roundrect (at -2.55 0 90) (size 1.8 5.4) (layers "F.Cu" "F.Paste" "F.Mask") (roundrect_rratio 0.138889)
      (net 9 "/Power Supply/PoE/VDD_POE_IN") (pintype "passive"))
    (pad "2" smd roundrect (at 2.55 0 90) (size 1.8 5.4) (layers "F.Cu" "F.Paste" "F.Mask") (roundrect_rratio 0.138889)
      (net 11 "GNDD") (pintype "passive"))
  )

  (footprint "kria-k26-devboard-footprints:C_2220_5650Metric" (layer "F.Cu")
    (at 171.01 82.95 90)
    (descr "Capacitor SMD 2220")
    (tags "capacitor SMD 2220")
    (property "Author" "Antmicro")
    (property "Dielectric" "")
    (property "License" "Apache-2.0")
    (property "MPN" "C5750X7S2A226M280KB")
    (property "Manufacturer" "TDK")
    (property "Sheetfile" "PoE.kicad_sch")
    (property "Sheetname" "PoE")
    (property "Val" "22u/100V")
    (property "Voltage" "")
    (property "ki_description" " ")
    (attr smd)
    (fp_text reference "C175" (at -1.4 -10.9 90) (layer "F.SilkS")
        (effects (font (size 0.7 0.7) (thickness 0.15)) (justify left bottom))
    )
    (fp_text value "C_22u_100V_2220" (at 0 3.9 90) (layer "F.Fab") hide
        (effects (font (size 0.7 0.7) (thickness 0.15)) (justify left bottom))
    )
    (fp_text user "${REFERENCE}" (at -3.7 5.9 90) (layer "F.Fab") hide
        (effects (font (size 0.7 0.7) (thickness 0.15)) (justify left bottom))
    )
    (fp_text user "Author: Antmicro" (at -3.7 7.9 90) (layer "F.Fab") hide
        (effects (font (size 0.7 0.7) (thickness 0.15)) (justify left bottom))
    )
    (fp_text user "License: Apache-2.0" (at -3.7 6.9 90) (layer "F.Fab") hide
        (effects (font (size 0.7 0.7) (thickness 0.15)) (justify left bottom))
    )
    (fp_line (start -1.415 -2.61) (end 1.415 -2.61)
      (stroke (width 0.15) (type solid)) (layer "F.SilkS"))
    (fp_line (start -1.415 2.61) (end 1.415 2.61)
      (stroke (width 0.15) (type solid)) (layer "F.SilkS"))
    (fp_rect (start -3.7 -2.95) (end 3.7 2.95)
      (stroke (width 0.05) (type solid)) (fill none) (layer "F.CrtYd"))
    (fp_rect (start -2.85 -2.5) (end 2.85 2.5)
      (stroke (width 0.15) (type solid)) (fill none) (layer "F.Fab"))
    (pad "1" smd roundrect (at -2.55 0 90) (size 1.8 5.4) (layers "F.Cu" "F.Paste" "F.Mask") (roundrect_rratio 0.138889)
      (net 9 "/Power Supply/PoE/VDD_POE_IN") (pintype "passive"))
    (pad "2" smd roundrect (at 2.55 0 90) (size 1.8 5.4) (layers "F.Cu" "F.Paste" "F.Mask") (roundrect_rratio 0.138889)
      (net 11 "GNDD") (pintype "passive"))
  )

  (footprint "kria-k26-devboard-footprints:SOIC-4_W3.9mm" (layer "F.Cu")
    (at 177.79 75.63 180)
    (property "Author" "Antmicro")
    (property "License" "Apache-2.0")
    (property "MPN" "MB10S")
    (property "Manufacturer" "Multicomp Pro")
    (property "Sheetfile" "PoE.kicad_sch")
    (property "Sheetname" "PoE")
    (property "ki_description" "TVS diode")
    (property "ki_keywords" "SMT, DIODE, SEMICONDUCTOR, TVS, BRIDGE, RECTIFIER")
    (attr smd)
    (fp_text reference "D9" (at 3.6 -0.4 180) (layer "F.SilkS")
        (effects (font (size 0.7 0.7) (thickness 0.15)) (justify left bottom))
    )
    (fp_text value "MB10S" (at 0 3.6 180) (layer "F.Fab") hide
        (effects (font (size 0.7 0.7) (thickness 0.15)) (justify left bottom))
    )
    (fp_text user "${REFERENCE}" (at -4.111 5.347 180) (layer "F.Fab") hide
        (effects (font (size 0.7 0.7) (thickness 0.15)) (justify left bottom))
    )
    (fp_text user "License: Apache-2.0" (at -4.111 7.746 180) (layer "F.Fab") hide
        (effects (font (size 0.7 0.7) (thickness 0.15)) (justify left bottom))
    )
    (fp_text user "Author: Antmicro" (at -4.111 6.546 180) (layer "F.Fab") hide
        (effects (font (size 0.7 0.7) (thickness 0.15)) (justify left bottom))
    )
    (fp_line (start -2.101 2.479) (end 2.1 2.479)
      (stroke (width 0.15) (type solid)) (layer "F.SilkS"))
    (fp_line (start -2.1 -2.5) (end 2.101 -2.5)
      (stroke (width 0.15) (type solid)) (layer "F.SilkS"))
    (fp_circle (center -2.55 -2) (end -2.451 -2)
      (stroke (width 0.15) (type solid)) (fill solid) (layer "F.SilkS"))
    (fp_rect (start -3.8 -2.7) (end 3.8 2.7)
      (stroke (width 0.05) (type solid)) (fill none) (layer "F.CrtYd"))
    (fp_line (start -2.101 -2.48) (end 2.1 -2.48)
      (stroke (width 0.15) (type solid)) (layer "F.Fab"))
    (fp_line (start -2.101 2.479) (end -2.101 -2.48)
      (stroke (width 0.15) (type solid)) (layer "F.Fab"))
    (fp_line (start 2.1 -2.48) (end 2.1 2.479)
      (stroke (width 0.15) (type solid)) (layer "F.Fab"))
    (fp_line (start 2.1 2.479) (end -2.101 2.479)
      (stroke (width 0.15) (type solid)) (layer "F.Fab"))
    (pad "1" smd roundrect (at -2.851 -1.226 180) (size 1.8 1) (layers "F.Cu" "F.Paste" "F.Mask") (roundrect_rratio 0.25)
      (net 9 "/Power Supply/PoE/VDD_POE_IN") (pinfunction "1") (pintype "passive"))
    (pad "2" smd roundrect (at -2.851 1.225 180) (size 1.8 1) (layers "F.Cu" "F.Paste" "F.Mask") (roundrect_rratio 0.25)
      (net 10 "/Power Supply/PoE/VSS_POE_IN") (pinfunction "2") (pintype "passive"))
    (pad "3" smd roundrect (at 2.85 1.225 180) (size 1.8 1) (layers "F.Cu" "F.Paste" "F.Mask") (roundrect_rratio 0.25)
      (net 238 "/Ethernet/POE_VC3") (pinfunction "3") (pintype "passive"))
    (pad "4" smd roundrect (at 2.85 -1.226 180) (size 1.8 1) (layers "F.Cu" "F.Paste" "F.Mask") (roundrect_rratio 0.25)
      (net 237 "/Ethernet/POE_VC4") (pinfunction "4") (pintype "passive"))
  )

  (footprint "kria-k26-devboard-footprints:TSOT23-6" (layer "F.Cu")
    (at 187.1 132.9 90)
    (property "Author" "Antmicro")
    (property "License" "Apache-2.0")
    (property "MPN" "AP62301WU-7")
    (property "Manufacturer" "Diodes Incorporated")
    (property "Sheetfile" "dc-dc-conventers.kicad_sch")
    (property "Sheetname" "DC/DC conventers")
    (property "ki_description" "DC-DC Switching Synchronous Buck Regulator, Adjustable, 4.2V-18Vin, 0.8V-7V/3A out, TSOT-26-6")
    (property "ki_keywords" "SMT, PMIC, IC, VOLTAGE")
    (attr smd)
    (fp_text reference "U55" (at 1.71 -0.33 180) (layer "F.SilkS")
        (effects (font (size 0.7 0.7) (thickness 0.15)) (justify left bottom))
    )
    (fp_text value "AP62301_TSOT" (at -0.005 2.6 90) (layer "F.Fab") hide
        (effects (font (size 0.7 0.7) (thickness 0.15)) (justify left bottom))
    )
    (fp_text user "Author: Antmicro" (at -1.893 7.368 90) (layer "F.Fab") hide
        (effects (font (size 0.7 0.7) (thickness 0.15)) (justify left bottom))
    )
    (fp_text user "${REFERENCE}" (at -1.893 6.168 90) (layer "F.Fab") hide
        (effects (font (size 0.7 0.7) (thickness 0.15)) (justify left bottom))
    )
    (fp_text user "License: Apache-2.0" (at -1.893 4.967 90) (layer "F.Fab") hide
        (effects (font (size 0.7 0.7) (thickness 0.15)) (justify left bottom))
    )
    (fp_line (start -1.4805 0.725) (end -1.4795 -0.725)
      (stroke (width 0.15) (type solid)) (layer "F.SilkS"))
    (fp_line (start -1.4805 0.725) (end -1.3905 0.725)
      (stroke (width 0.15) (type solid)) (layer "F.SilkS"))
    (fp_line (start -1.4795 -0.725) (end -1.3905 -0.725)
      (stroke (width 0.15) (type solid)) (layer "F.SilkS"))
    (fp_line (start 1.479 0.73) (end 1.38 0.73)
      (stroke (width 0.15) (type solid)) (layer "F.SilkS"))
    (fp_line (start 1.48 -0.72) (end 1.38 -0.72)
      (stroke (width 0.15) (type solid)) (layer "F.SilkS"))
    (fp_line (start 1.48 -0.72) (end 1.479 0.73)
      (stroke (width 0.15) (type solid)) (layer "F.SilkS"))
    (fp_circle (center -1.499 1.236) (end -1.45 1.236)
      (stroke (width 0.15) (type solid)) (fill solid) (layer "F.SilkS"))
    (fp_rect (start -1.65 -1.61) (end 1.65 1.61)
      (stroke (width 0.05) (type solid)) (fill none) (layer "F.CrtYd"))
    (fp_line (start -1.527 -0.833) (end 1.523 -0.833)
      (stroke (width 0.15) (type solid)) (layer "F.Fab"))
    (fp_line (start -1.527 0.491) (end -1.527 -0.833)
      (stroke (width 0.15) (type solid)) (layer "F.Fab"))
    (fp_line (start -1.527 0.491) (end -1.102 0.916)
      (stroke (width 0.15) (type solid)) (layer "F.Fab"))
    (fp_line (start -1.102 0.916) (end 1.523 0.916)
      (stroke (width 0.15) (type solid)) (layer "F.Fab"))
    (fp_line (start 1.523 -0.833) (end 1.523 0.916)
      (stroke (width 0.15) (type solid)) (layer "F.Fab"))
    (pad "1" smd rect (at -0.952 1.18 90) (size 0.7 0.8) (layers "F.Cu" "F.Paste" "F.Mask")
      (net 1 "GND") (pinfunction "GND") (pintype "power_in"))
    (pad "2" smd rect (at -0.001 1.18 90) (size 0.7 0.8) (layers "F.Cu" "F.Paste" "F.Mask")
      (net 316 "/Power Supply/DC/DC conventers/SW_PL_1V2") (pinfunction "SW") (pintype "power_out"))
    (pad "3" smd rect (at 0.947 1.18 90) (size 0.7 0.8) (layers "F.Cu" "F.Paste" "F.Mask")
      (net 14 "/Power Supply/DC/DC conventers/DC_MAIN_BUS") (pinfunction "VIN") (pintype "power_in"))
    (pad "4" smd rect (at 0.947 -1.18 90) (size 0.7 0.8) (layers "F.Cu" "F.Paste" "F.Mask")
      (net 694 "Net-(U55-FB)") (pinfunction "FB") (pintype "input"))
    (pad "5" smd rect (at -0.001 -1.18 90) (size 0.7 0.8) (layers "F.Cu" "F.Paste" "F.Mask")
      (net 24 "/Power Supply/VCCOEN_PL_M2C") (pinfunction "EN") (pintype "input"))
    (pad "6" smd rect (at -0.952 -1.18 90) (size 0.7 0.8) (layers "F.Cu" "F.Paste" "F.Mask")
      (net 326 "Net-(U55-BST)") (pinfunction "BST") (pintype "output"))
  )

  (footprint "kria-k26-devboard-footprints:SOIC-4_W3.9mm" (layer "F.Cu")
    (at 177.79 70.21 180)
    (property "Author" "Antmicro")
    (property "License" "Apache-2.0")
    (property "MPN" "MB10S")
    (property "Manufacturer" "Multicomp Pro")
    (property "Sheetfile" "PoE.kicad_sch")
    (property "Sheetname" "PoE")
    (property "ki_description" "TVS diode")
    (property "ki_keywords" "SMT, DIODE, SEMICONDUCTOR, TVS, BRIDGE, RECTIFIER")
    (attr smd)
    (fp_text reference "D8" (at 3.48 -0.46 180) (layer "F.SilkS")
        (effects (font (size 0.7 0.7) (thickness 0.15)) (justify left bottom))
    )
    (fp_text value "MB10S" (at 0 3.6 180) (layer "F.Fab") hide
        (effects (font (size 0.7 0.7) (thickness 0.15)) (justify left bottom))
    )
    (fp_text user "Author: Antmicro" (at -4.111 6.546 180) (layer "F.Fab") hide
        (effects (font (size 0.7 0.7) (thickness 0.15)) (justify left bottom))
    )
    (fp_text user "${REFERENCE}" (at -4.111 5.347 180) (layer "F.Fab") hide
        (effects (font (size 0.7 0.7) (thickness 0.15)) (justify left bottom))
    )
    (fp_text user "License: Apache-2.0" (at -4.111 7.746 180) (layer "F.Fab") hide
        (effects (font (size 0.7 0.7) (thickness 0.15)) (justify left bottom))
    )
    (fp_line (start -2.101 2.479) (end 2.1 2.479)
      (stroke (width 0.15) (type solid)) (layer "F.SilkS"))
    (fp_line (start -2.1 -2.5) (end 2.101 -2.5)
      (stroke (width 0.15) (type solid)) (layer "F.SilkS"))
    (fp_circle (center -2.55 -2) (end -2.451 -2)
      (stroke (width 0.15) (type solid)) (fill solid) (layer "F.SilkS"))
    (fp_rect (start -3.8 -2.7) (end 3.8 2.7)
      (stroke (width 0.05) (type solid)) (fill none) (layer "F.CrtYd"))
    (fp_line (start -2.101 -2.48) (end 2.1 -2.48)
      (stroke (width 0.15) (type solid)) (layer "F.Fab"))
    (fp_line (start -2.101 2.479) (end -2.101 -2.48)
      (stroke (width 0.15) (type solid)) (layer "F.Fab"))
    (fp_line (start 2.1 -2.48) (end 2.1 2.479)
      (stroke (width 0.15) (type solid)) (layer "F.Fab"))
    (fp_line (start 2.1 2.479) (end -2.101 2.479)
      (stroke (width 0.15) (type solid)) (layer "F.Fab"))
    (pad "1" smd roundrect (at -2.851 -1.226 180) (size 1.8 1) (layers "F.Cu" "F.Paste" "F.Mask") (roundrect_rratio 0.25)
      (net 9 "/Power Supply/PoE/VDD_POE_IN") (pinfunction "1") (pintype "passive"))
    (pad "2" smd roundrect (at -2.851 1.225 180) (size 1.8 1) (layers "F.Cu" "F.Paste" "F.Mask") (roundrect_rratio 0.25)
      (net 10 "/Power Supply/PoE/VSS_POE_IN") (pinfunction "2") (pintype "passive"))
    (pad "3" smd roundrect (at 2.85 1.225 180) (size 1.8 1) (layers "F.Cu" "F.Paste" "F.Mask") (roundrect_rratio 0.25)
      (net 236 "/Ethernet/POE_VC1") (pinfunction "3") (pintype "passive"))
    (pad "4" smd roundrect (at 2.85 -1.226 180) (size 1.8 1) (layers "F.Cu" "F.Paste" "F.Mask") (roundrect_rratio 0.25)
      (net 235 "/Ethernet/POE_VC2") (pinfunction "4") (pintype "passive"))
  )

  (footprint "kria-k26-devboard-footprints:DO-214AC" (layer "F.Cu")
    (at 184.125 73.9 -90)
    (property "Author" "Antmicro")
    (property "License" "Apache-2.0")
    (property "MPN" "SMAJ58A-13-F")
    (property "Manufacturer" "Diodes Incorporated")
    (property "Sheetfile" "PoE.kicad_sch")
    (property "Sheetname" "PoE")
    (attr smd)
    (fp_text reference "D10" (at 0 -2.05 -90) (layer "F.SilkS")
        (effects (font (size 0.7 0.7) (thickness 0.15)) (justify left bottom))
    )
    (fp_text value "SMAJ58A-13-F" (at 0 2.45 -90) (layer "F.Fab") hide
        (effects (font (size 0.7 0.7) (thickness 0.15)) (justify left bottom))
    )
    (fp_text user "Author: Antmicro" (at -3.301 5.65 -90) (layer "F.Fab") hide
        (effects (font (size 0.7 0.7) (thickness 0.15)) (justify left bottom))
    )
    (fp_text user "${REFERENCE}" (at -3.301 4.45 -90) (layer "F.Fab") hide
        (effects (font (size 0.7 0.7) (thickness 0.15)) (justify left bottom))
    )
    (fp_text user "License: Apache-2.0" (at -3.301 6.85 -90) (layer "F.Fab") hide
        (effects (font (size 0.7 0.7) (thickness 0.15)) (justify left bottom))
    )
    (fp_line (start -0.9 1.3) (end -0.9 -1.3)
      (stroke (width 0.15) (type solid)) (layer "F.SilkS"))
    (fp_rect (start -3.25 -1.55) (end 3.25 1.55)
      (stroke (width 0.05) (type solid)) (fill none) (layer "F.CrtYd"))
    (fp_line (start -2.15 -1.301) (end -2.15 1.3)
      (stroke (width 0.15) (type solid)) (layer "F.Fab"))
    (fp_line (start -2.15 -1.301) (end 2.148 -1.301)
      (stroke (width 0.15) (type solid)) (layer "F.Fab"))
    (fp_line (start -2.15 1.3) (end 2.148 1.3)
      (stroke (width 0.15) (type solid)) (layer "F.Fab"))
    (fp_line (start -1.442 1.3) (end -1.365 1.3)
      (stroke (width 0.15) (type solid)) (layer "F.Fab"))
    (fp_line (start -1.363 -1.301) (end -1.442 -1.301)
      (stroke (width 0.15) (type solid)) (layer "F.Fab"))
    (fp_line (start 2.148 -1.301) (end 2.148 1.3)
      (stroke (width 0.15) (type solid)) (layer "F.Fab"))
    (fp_rect (start -1.363 -1.301) (end -1.1 1.3)
      (stroke (width 0.15) (type solid)) (fill solid) (layer "F.Fab"))
    (pad "A" smd roundrect (at 1.999 0 270) (size 2 2.1) (layers "F.Cu" "F.Paste" "F.Mask") (roundrect_rratio 0.1)
      (net 10 "/Power Supply/PoE/VSS_POE_IN") (pinfunction "A") (pintype "passive"))
    (pad "K" smd roundrect (at -2 0 270) (size 2 2.1) (layers "F.Cu" "F.Paste" "F.Mask") (roundrect_rratio 0.1)
      (net 9 "/Power Supply/PoE/VDD_POE_IN") (pinfunction "K") (pintype "passive"))
  )

  (footprint "kria-k26-devboard-footprints:C_0805_2012Metric" (layer "F.Cu")
    (at 187.1766 72.904773 -90)
    (descr "Capacitor SMD 0805")
    (tags "capacitor SMD 0805")
    (property "Author" "Antmicro")
    (property "Dielectric" "X7R")
    (property "License" "Apache-2.0")
    (property "MPN" "CL21B104KCFNNNE")
    (property "Manufacturer" "SAMSUNG")
    (property "Sheetfile" "PoE.kicad_sch")
    (property "Sheetname" "PoE")
    (property "Val" "100n/100V")
    (property "Voltage" "100V")
    (property "ki_description" " ")
    (attr smd)
    (fp_text reference "C171" (at 1.855227 -1.7934 -90) (layer "F.SilkS")
        (effects (font (size 0.7 0.7) (thickness 0.15)) (justify left bottom))
    )
    (fp_text value "C_100n_0805_100V" (at 0 1.947 -90) (layer "F.Fab") hide
        (effects (font (size 0.7 0.7) (thickness 0.15)) (justify left bottom))
    )
    (fp_text user "${REFERENCE}" (at -1.9 3.947 -90) (layer "F.Fab") hide
        (effects (font (size 0.7 0.7) (thickness 0.15)) (justify left bottom))
    )
    (fp_text user "Author: Antmicro" (at -1.9 5.947 -90) (layer "F.Fab") hide
        (effects (font (size 0.7 0.7) (thickness 0.15)) (justify left bottom))
    )
    (fp_text user "License: Apache-2.0" (at -1.9 4.947 -90) (layer "F.Fab") hide
        (effects (font (size 0.7 0.7) (thickness 0.15)) (justify left bottom))
    )
    (fp_line (start -0.3 -0.8) (end 0.3 -0.8)
      (stroke (width 0.15) (type solid)) (layer "F.SilkS"))
    (fp_line (start -0.3 0.8) (end 0.3 0.8)
      (stroke (width 0.15) (type solid)) (layer "F.SilkS"))
    (fp_rect (start -1.9 -0.93) (end 1.9 0.93)
      (stroke (width 0.05) (type solid)) (fill none) (layer "F.CrtYd"))
    (fp_rect (start -0.95 -0.675) (end 0.95 0.675)
      (stroke (width 0.15) (type solid)) (fill none) (layer "F.Fab"))
    (pad "1" smd rect (at -1.05 0 270) (size 1.2 1.2) (layers "F.Cu" "F.Paste" "F.Mask")
      (net 9 "/Power Supply/PoE/VDD_POE_IN") (pintype "passive"))
    (pad "2" smd rect (at 1.05 0 270) (size 1.2 1.2) (layers "F.Cu" "F.Paste" "F.Mask")
      (net 10 "/Power Supply/PoE/VSS_POE_IN") (pintype "passive"))
  )

  (footprint "kria-k26-devboard-footprints:R_0402_1005Metric" (layer "F.Cu")
    (at 141.785 89.2 180)
    (descr "Resistor SMD 0402")
    (tags "resistor SMD 0402")
    (property "Author" "Antmicro")
    (property "License" "Apache-2.0")
    (property "MPN" "CR0402-FX-4701GLF")
    (property "Manufacturer" "Bourns")
    (property "Sheetfile" "eth.kicad_sch")
    (property "Sheetname" "Ethernet")
    (property "Tolerance" "1%")
    (property "Val" "4k7")
    (property "ki_description" "4k7 resistor in 0402 package with 1% tolerance")
    (attr smd)
    (fp_text reference "R74" (at 2.995 -0.41 180) (layer "F.SilkS")
        (effects (font (size 0.7 0.7) (thickness 0.15)) (justify left bottom))
    )
    (fp_text value "R_4k7_0402" (at 0 1.4 180) (layer "F.Fab") hide
        (effects (font (size 0.7 0.7) (thickness 0.15)) (justify left bottom))
    )
    (fp_text user "Author: Antmicro" (at -0.95 4.169 180) (layer "F.Fab") hide
        (effects (font (size 0.7 0.7) (thickness 0.15)) (justify left bottom))
    )
    (fp_text user "License: Apache-2.0" (at -0.95 5.169 180) (layer "F.Fab") hide
        (effects (font (size 0.7 0.7) (thickness 0.15)) (justify left bottom))
    )
    (fp_text user "${REFERENCE}" (at -0.95 3.168 180) (layer "F.Fab") hide
        (effects (font (size 0.7 0.7) (thickness 0.15)) (justify left bottom))
    )
    (fp_rect (start -0.93 -0.47) (end 0.93 0.47)
      (stroke (width 0.05) (type solid)) (fill none) (layer "F.CrtYd"))
    (fp_rect (start -0.5 -0.25) (end 0.5 0.25)
      (stroke (width 0.15) (type solid)) (fill none) (layer "F.Fab"))
    (pad "1" smd roundrect (at -0.485 0 180) (size 0.59 0.64) (layers "F.Cu" "F.Paste" "F.Mask") (roundrect_rratio 0.25)
      (net 673 "Net-(U30-JTAG_CLK)") (pintype "passive"))
    (pad "2" smd roundrect (at 0.485 0 180) (size 0.59 0.64) (layers "F.Cu" "F.Paste" "F.Mask") (roundrect_rratio 0.25)
      (net 17 "PS_1V8") (pintype "passive"))
  )

  (footprint "kria-k26-devboard-footprints:C_0402_1005Metric" (layer "F.Cu")
    (at 140.925 86.358222 -90)
    (descr "Capacitor SMD 0402")
    (tags "capacitor SMD 0402")
    (property "Author" "Antmicro")
    (property "Dielectric" "X5R")
    (property "License" "Apache-2.0")
    (property "MPN" "GRM155R61H104KE14D")
    (property "Manufacturer" "Murata")
    (property "Sheetfile" "eth.kicad_sch")
    (property "Sheetname" "Ethernet")
    (property "Val" "100n")
    (property "Voltage" "50V")
    (property "ki_description" " ")
    (attr smd)
    (fp_text reference "C104" (at 1.291778 0.675 -90) (layer "F.SilkS")
        (effects (font (size 0.7 0.7) (thickness 0.15)) (justify left bottom))
    )
    (fp_text value "C_100n_0402" (at 0 1.4 -90) (layer "F.Fab") hide
        (effects (font (size 0.7 0.7) (thickness 0.15)) (justify left bottom))
    )
    (fp_text user "${REFERENCE}" (at -0.932 3.168 -90) (layer "F.Fab") hide
        (effects (font (size 0.7 0.7) (thickness 0.15)) (justify left bottom))
    )
    (fp_text user "License: Apache-2.0" (at -0.932 5.17 -90) (layer "F.Fab") hide
        (effects (font (size 0.7 0.7) (thickness 0.15)) (justify left bottom))
    )
    (fp_text user "Author: Antmicro" (at -0.932 4.17 -90) (layer "F.Fab") hide
        (effects (font (size 0.7 0.7) (thickness 0.15)) (justify left bottom))
    )
    (fp_rect (start -0.94 -0.47) (end 0.94 0.47)
      (stroke (width 0.05) (type solid)) (fill none) (layer "F.CrtYd"))
    (fp_rect (start -0.499 -0.249) (end 0.499 0.249)
      (stroke (width 0.15) (type solid)) (fill none) (layer "F.Fab"))
    (pad "1" smd roundrect (at -0.484 0 270) (size 0.59 0.64) (layers "F.Cu" "F.Paste" "F.Mask") (roundrect_rratio 0.25)
      (net 17 "PS_1V8") (pintype "passive"))
    (pad "2" smd roundrect (at 0.484 0 270) (size 0.59 0.64) (layers "F.Cu" "F.Paste" "F.Mask") (roundrect_rratio 0.25)
      (net 1 "GND") (pintype "passive"))
  )

  (footprint "kria-k26-devboard-footprints:R_0402_1005Metric" (layer "F.Cu")
    (at 141.787154 88.19 180)
    (descr "Resistor SMD 0402")
    (tags "resistor SMD 0402")
    (property "Author" "Antmicro")
    (property "License" "Apache-2.0")
    (property "MPN" "CR0402-FX-2201GLF")
    (property "Manufacturer" "Bourns")
    (property "Sheetfile" "eth.kicad_sch")
    (property "Sheetname" "Ethernet")
    (property "Tolerance" "1%")
    (property "Val" "2k2")
    (property "ki_description" "2k2 resistor in 0402 package with 1% tolerance")
    (attr smd)
    (fp_text reference "R76" (at 2.995 -0.41 180) (layer "F.SilkS")
        (effects (font (size 0.7 0.7) (thickness 0.15)) (justify left bottom))
    )
    (fp_text value "R_2k2_0402" (at 0 1.4 180) (layer "F.Fab") hide
        (effects (font (size 0.7 0.7) (thickness 0.15)) (justify left bottom))
    )
    (fp_text user "License: Apache-2.0" (at -0.95 5.169 180) (layer "F.Fab") hide
        (effects (font (size 0.7 0.7) (thickness 0.15)) (justify left bottom))
    )
    (fp_text user "${REFERENCE}" (at -0.95 3.168 180) (layer "F.Fab") hide
        (effects (font (size 0.7 0.7) (thickness 0.15)) (justify left bottom))
    )
    (fp_text user "Author: Antmicro" (at -0.95 4.169 180) (layer "F.Fab") hide
        (effects (font (size 0.7 0.7) (thickness 0.15)) (justify left bottom))
    )
    (fp_rect (start -0.93 -0.47) (end 0.93 0.47)
      (stroke (width 0.05) (type solid)) (fill none) (layer "F.CrtYd"))
    (fp_rect (start -0.5 -0.25) (end 0.5 0.25)
      (stroke (width 0.15) (type solid)) (fill none) (layer "F.Fab"))
    (pad "1" smd roundrect (at -0.485 0 180) (size 0.59 0.64) (layers "F.Cu" "F.Paste" "F.Mask") (roundrect_rratio 0.25)
      (net 50 "/Ethernet/MIO77") (pintype "passive"))
    (pad "2" smd roundrect (at 0.485 0 180) (size 0.59 0.64) (layers "F.Cu" "F.Paste" "F.Mask") (roundrect_rratio 0.25)
      (net 17 "PS_1V8") (pintype "passive"))
  )

  (footprint "kria-k26-devboard-footprints:R_0402_1005Metric" (layer "F.Cu")
    (at 141.775 91.21 180)
    (descr "Resistor SMD 0402")
    (tags "resistor SMD 0402")
    (property "Author" "Antmicro")
    (property "License" "Apache-2.0")
    (property "MPN" "CR0402-FX-4701GLF")
    (property "Manufacturer" "Bourns")
    (property "Sheetfile" "eth.kicad_sch")
    (property "Sheetname" "Ethernet")
    (property "Tolerance" "1%")
    (property "Val" "4k7")
    (property "ki_description" "4k7 resistor in 0402 package with 1% tolerance")
    (attr smd)
    (fp_text reference "R73" (at 2.995 -0.41 180) (layer "F.SilkS")
        (effects (font (size 0.7 0.7) (thickness 0.15)) (justify left bottom))
    )
    (fp_text value "R_4k7_0402" (at 0 1.4 180) (layer "F.Fab") hide
        (effects (font (size 0.7 0.7) (thickness 0.15)) (justify left bottom))
    )
    (fp_text user "Author: Antmicro" (at -0.95 4.169 180) (layer "F.Fab") hide
        (effects (font (size 0.7 0.7) (thickness 0.15)) (justify left bottom))
    )
    (fp_text user "License: Apache-2.0" (at -0.95 5.169 180) (layer "F.Fab") hide
        (effects (font (size 0.7 0.7) (thickness 0.15)) (justify left bottom))
    )
    (fp_text user "${REFERENCE}" (at -0.95 3.168 180) (layer "F.Fab") hide
        (effects (font (size 0.7 0.7) (thickness 0.15)) (justify left bottom))
    )
    (fp_rect (start -0.93 -0.47) (end 0.93 0.47)
      (stroke (width 0.05) (type solid)) (fill none) (layer "F.CrtYd"))
    (fp_rect (start -0.5 -0.25) (end 0.5 0.25)
      (stroke (width 0.15) (type solid)) (fill none) (layer "F.Fab"))
    (pad "1" smd roundrect (at -0.485 0 180) (size 0.59 0.64) (layers "F.Cu" "F.Paste" "F.Mask") (roundrect_rratio 0.25)
      (net 672 "Net-(U30-JTAG_TDI)") (pintype "passive"))
    (pad "2" smd roundrect (at 0.485 0 180) (size 0.59 0.64) (layers "F.Cu" "F.Paste" "F.Mask") (roundrect_rratio 0.25)
      (net 17 "PS_1V8") (pintype "passive"))
  )

  (footprint "kria-k26-devboard-footprints:R_0402_1005Metric" (layer "F.Cu")
    (at 141.785 90.2 180)
    (descr "Resistor SMD 0402")
    (tags "resistor SMD 0402")
    (property "Author" "Antmicro")
    (property "License" "Apache-2.0")
    (property "MPN" "CR0402-FX-4701GLF")
    (property "Manufacturer" "Bourns")
    (property "Sheetfile" "eth.kicad_sch")
    (property "Sheetname" "Ethernet")
    (property "Tolerance" "1%")
    (property "Val" "4k7")
    (property "ki_description" "4k7 resistor in 0402 package with 1% tolerance")
    (attr smd)
    (fp_text reference "R75" (at 2.995 -0.41 180) (layer "F.SilkS")
        (effects (font (size 0.7 0.7) (thickness 0.15)) (justify left bottom))
    )
    (fp_text value "R_4k7_0402" (at 0 1.4 180) (layer "F.Fab") hide
        (effects (font (size 0.7 0.7) (thickness 0.15)) (justify left bottom))
    )
    (fp_text user "Author: Antmicro" (at -0.95 4.169 180) (layer "F.Fab") hide
        (effects (font (size 0.7 0.7) (thickness 0.15)) (justify left bottom))
    )
    (fp_text user "${REFERENCE}" (at -0.95 3.168 180) (layer "F.Fab") hide
        (effects (font (size 0.7 0.7) (thickness 0.15)) (justify left bottom))
    )
    (fp_text user "License: Apache-2.0" (at -0.95 5.169 180) (layer "F.Fab") hide
        (effects (font (size 0.7 0.7) (thickness 0.15)) (justify left bottom))
    )
    (fp_rect (start -0.93 -0.47) (end 0.93 0.47)
      (stroke (width 0.05) (type solid)) (fill none) (layer "F.CrtYd"))
    (fp_rect (start -0.5 -0.25) (end 0.5 0.25)
      (stroke (width 0.15) (type solid)) (fill none) (layer "F.Fab"))
    (pad "1" smd roundrect (at -0.485 0 180) (size 0.59 0.64) (layers "F.Cu" "F.Paste" "F.Mask") (roundrect_rratio 0.25)
      (net 674 "Net-(U30-JTAG_TMS)") (pintype "passive"))
    (pad "2" smd roundrect (at 0.485 0 180) (size 0.59 0.64) (layers "F.Cu" "F.Paste" "F.Mask") (roundrect_rratio 0.25)
      (net 17 "PS_1V8") (pintype "passive"))
  )

  (footprint "kria-k26-devboard-footprints:C_0402_1005Metric" (layer "F.Cu")
    (at 149.245911 93.839035 -90)
    (descr "Capacitor SMD 0402")
    (tags "capacitor SMD 0402")
    (property "Author" "Antmicro")
    (property "Dielectric" "X5R")
    (property "License" "Apache-2.0")
    (property "MPN" "GRM155R61H104KE14D")
    (property "Manufacturer" "Murata")
    (property "Sheetfile" "eth.kicad_sch")
    (property "Sheetname" "Ethernet")
    (property "Val" "100n")
    (property "Voltage" "50V")
    (property "ki_description" " ")
    (attr smd)
    (fp_text reference "C107" (at 3.69 -0.41 -90) (layer "F.SilkS")
        (effects (font (size 0.7 0.7) (thickness 0.15)) (justify left bottom))
    )
    (fp_text value "C_100n_0402" (at 0 1.4 -90) (layer "F.Fab") hide
        (effects (font (size 0.7 0.7) (thickness 0.15)) (justify left bottom))
    )
    (fp_text user "License: Apache-2.0" (at -0.932 5.17 -90) (layer "F.Fab") hide
        (effects (font (size 0.7 0.7) (thickness 0.15)) (justify left bottom))
    )
    (fp_text user "Author: Antmicro" (at -0.932 4.17 -90) (layer "F.Fab") hide
        (effects (font (size 0.7 0.7) (thickness 0.15)) (justify left bottom))
    )
    (fp_text user "${REFERENCE}" (at -0.932 3.168 -90) (layer "F.Fab") hide
        (effects (font (size 0.7 0.7) (thickness 0.15)) (justify left bottom))
    )
    (fp_rect (start -0.94 -0.47) (end 0.94 0.47)
      (stroke (width 0.05) (type solid)) (fill none) (layer "F.CrtYd"))
    (fp_rect (start -0.499 -0.249) (end 0.499 0.249)
      (stroke (width 0.15) (type solid)) (fill none) (layer "F.Fab"))
    (pad "1" smd roundrect (at -0.484 0 270) (size 0.59 0.64) (layers "F.Cu" "F.Paste" "F.Mask") (roundrect_rratio 0.25)
      (net 19 "PS_1V0") (pintype "passive"))
    (pad "2" smd roundrect (at 0.484 0 270) (size 0.59 0.64) (layers "F.Cu" "F.Paste" "F.Mask") (roundrect_rratio 0.25)
      (net 1 "GND") (pintype "passive"))
  )

  (footprint "kria-k26-devboard-footprints:C_0402_1005Metric" (layer "F.Cu")
    (at 154.106621 90.117588)
    (descr "Capacitor SMD 0402")
    (tags "capacitor SMD 0402")
    (property "Author" "Antmicro")
    (property "Dielectric" "X5R")
    (property "License" "Apache-2.0")
    (property "MPN" "GRM155R61H104KE14D")
    (property "Manufacturer" "Murata")
    (property "Sheetfile" "eth.kicad_sch")
    (property "Sheetname" "Ethernet")
    (property "Val" "100n")
    (property "Voltage" "50V")
    (property "ki_description" " ")
    (attr smd)
    (fp_text reference "C101" (at -1.126621 1.262412) (layer "F.SilkS")
        (effects (font (size 0.7 0.7) (thickness 0.15)) (justify left bottom))
    )
    (fp_text value "C_100n_0402" (at 0 1.4) (layer "F.Fab") hide
        (effects (font (size 0.7 0.7) (thickness 0.15)) (justify left bottom))
    )
    (fp_text user "Author: Antmicro" (at -0.932 4.17) (layer "F.Fab") hide
        (effects (font (size 0.7 0.7) (thickness 0.15)) (justify left bottom))
    )
    (fp_text user "${REFERENCE}" (at -0.932 3.168) (layer "F.Fab") hide
        (effects (font (size 0.7 0.7) (thickness 0.15)) (justify left bottom))
    )
    (fp_text user "License: Apache-2.0" (at -0.932 5.17) (layer "F.Fab") hide
        (effects (font (size 0.7 0.7) (thickness 0.15)) (justify left bottom))
    )
    (fp_rect (start -0.94 -0.47) (end 0.94 0.47)
      (stroke (width 0.05) (type solid)) (fill none) (layer "F.CrtYd"))
    (fp_rect (start -0.499 -0.249) (end 0.499 0.249)
      (stroke (width 0.15) (type solid)) (fill none) (layer "F.Fab"))
    (pad "1" smd roundrect (at -0.484 0) (size 0.59 0.64) (layers "F.Cu" "F.Paste" "F.Mask") (roundrect_rratio 0.25)
      (net 17 "PS_1V8") (pintype "passive"))
    (pad "2" smd roundrect (at 0.484 0) (size 0.59 0.64) (layers "F.Cu" "F.Paste" "F.Mask") (roundrect_rratio 0.25)
      (net 1 "GND") (pintype "passive"))
  )

  (footprint "kria-k26-devboard-footprints:QFN-48-1EP_7x7mm" (layer "F.Cu")
    (at 148.846 88.714 -90)
    (property "Author" "Antmicro")
    (property "License" "Apache-2.0")
    (property "MPN" "DP83867CRRGZR")
    (property "Manufacturer" "Texas Instruments")
    (property "Sheetfile" "eth.kicad_sch")
    (property "Sheetname" "Ethernet")
    (property "ki_description" "Robust, High Immunity 10/100/1000 Ethernet Physical Layer Transceiver")
    (property "ki_keywords" "SMT, ETHERNET, IC, TRANSCEIVER")
    (attr smd)
    (fp_text reference "U30" (at -4.834 2.236) (layer "F.SilkS")
        (effects (font (size 0.7 0.7) (thickness 0.15)) (justify left bottom))
    )
    (fp_text value "DP83867CR_VQFN" (at 0 5.749 -90) (layer "F.Fab") hide
        (effects (font (size 0.7 0.7) (thickness 0.15)) (justify left bottom))
    )
    (fp_text user "License: Apache-2.0" (at -4.1 9.45 -90) (layer "F.Fab") hide
        (effects (font (size 0.7 0.7) (thickness 0.15)) (justify left bottom))
    )
    (fp_text user "Author: Antmicro" (at -4.1 8.249 -90) (layer "F.Fab") hide
        (effects (font (size 0.7 0.7) (thickness 0.15)) (justify left bottom))
    )
    (fp_text user "${REFERENCE}" (at -4.1 7.05 -90) (layer "F.Fab") hide
        (effects (font (size 0.7 0.7) (thickness 0.15)) (justify left bottom))
    )
    (fp_line (start -3.6 -3.6) (end -3.6 -3)
      (stroke (width 0.15) (type solid)) (layer "F.SilkS"))
    (fp_line (start -3.6 3) (end -3.6 3.6)
      (stroke (width 0.15) (type solid)) (layer "F.SilkS"))
    (fp_line (start -3.6 3.6) (end -3 3.6)
      (stroke (width 0.15) (type solid)) (layer "F.SilkS"))
    (fp_line (start -3 -3.6) (end -3.6 -3.6)
      (stroke (width 0.15) (type solid)) (layer "F.SilkS"))
    (fp_line (start 3.6 -3.6) (end 3 -3.6)
      (stroke (width 0.15) (type solid)) (layer "F.SilkS"))
    (fp_line (start 3.6 -3) (end 3.6 -3.6)
      (stroke (width 0.15) (type solid)) (layer "F.SilkS"))
    (fp_line (start 3.6 3) (end 3.6 3.6)
      (stroke (width 0.15) (type solid)) (layer "F.SilkS"))
    (fp_line (start 3.6 3.6) (end 2.999 3.6)
      (stroke (width 0.15) (type solid)) (layer "F.SilkS"))
    (fp_circle (center -3.85 -3.1) (end -3.8 -3.1)
      (stroke (width 0.15) (type solid)) (fill solid) (layer "F.SilkS"))
    (fp_line (start -4.1 -3.1) (end -4.1 3.1)
      (stroke (width 0.05) (type solid)) (layer "F.CrtYd"))
    (fp_line (start -4.1 3.1) (end -3.8 3.1)
      (stroke (width 0.05) (type solid)) (layer "F.CrtYd"))
    (fp_line (start -4.05 -3.1) (end -4.1 -3.1)
      (stroke (width 0.05) (type solid)) (layer "F.CrtYd"))
    (fp_line (start -3.8 -3.8) (end -3.8 -3.1)
      (stroke (width 0.05) (type solid)) (layer "F.CrtYd"))
    (fp_line (start -3.8 -3.1) (end -4.05 -3.1)
      (stroke (width 0.05) (type solid)) (layer "F.CrtYd"))
    (fp_line (start -3.8 3.1) (end -3.8 3.8)
      (stroke (width 0.05) (type solid)) (layer "F.CrtYd"))
    (fp_line (start -3.8 3.8) (end -3.1 3.8)
      (stroke (width 0.05) (type solid)) (layer "F.CrtYd"))
    (fp_line (start -3.1 -4.1) (end -3.1 -3.8)
      (stroke (width 0.05) (type solid)) (layer "F.CrtYd"))
    (fp_line (start -3.1 -3.8) (end -3.8 -3.8)
      (stroke (width 0.05) (type solid)) (layer "F.CrtYd"))
    (fp_line (start -3.1 3.8) (end -3.1 4.1)
      (stroke (width 0.05) (type solid)) (layer "F.CrtYd"))
    (fp_line (start -3.1 4.1) (end 3.1 4.1)
      (stroke (width 0.05) (type solid)) (layer "F.CrtYd"))
    (fp_line (start 3.1 -4.1) (end -3.1 -4.1)
      (stroke (width 0.05) (type solid)) (layer "F.CrtYd"))
    (fp_line (start 3.1 -3.75) (end 3.1 -4.1)
      (stroke (width 0.05) (type solid)) (layer "F.CrtYd"))
    (fp_line (start 3.1 3.8) (end 3.8 3.8)
      (stroke (width 0.05) (type solid)) (layer "F.CrtYd"))
    (fp_line (start 3.1 4.1) (end 3.1 3.8)
      (stroke (width 0.05) (type solid)) (layer "F.CrtYd"))
    (fp_line (start 3.8 -3.75) (end 3.1 -3.75)
      (stroke (width 0.05) (type solid)) (layer "F.CrtYd"))
    (fp_line (start 3.8 -3.1) (end 3.8 -3.75)
      (stroke (width 0.05) (type solid)) (layer "F.CrtYd"))
    (fp_line (start 3.8 3.1) (end 4.1 3.1)
      (stroke (width 0.05) (type solid)) (layer "F.CrtYd"))
    (fp_line (start 3.8 3.8) (end 3.8 3.1)
      (stroke (width 0.05) (type solid)) (layer "F.CrtYd"))
    (fp_line (start 4.1 -3.1) (end 3.8 -3.1)
      (stroke (width 0.05) (type solid)) (layer "F.CrtYd"))
    (fp_line (start 4.1 3.1) (end 4.1 -3.1)
      (stroke (width 0.05) (type solid)) (layer "F.CrtYd"))
    (fp_line (start -2.95 -3.5) (end -3.5 -2.95)
      (stroke (width 0.15) (type solid)) (layer "F.Fab"))
    (fp_rect (start 3.531 3.531) (end -3.519 -3.519)
      (stroke (width 0.15) (type solid)) (fill none) (layer "F.Fab"))
    (pad "" smd roundrect (at -1.6 -1.6 270) (size 1.4 1.4) (layers "F.Paste") (roundrect_rratio 0.05))
    (pad "" smd roundrect (at -1.6 0 270) (size 1.4 1.4) (layers "F.Paste") (roundrect_rratio 0.05))
    (pad "" smd roundrect (at -1.6 1.6 270) (size 1.4 1.4) (layers "F.Paste") (roundrect_rratio 0.05))
    (pad "" smd roundrect (at 0 -1.6 270) (size 1.4 1.4) (layers "F.Paste") (roundrect_rratio 0.05))
    (pad "" smd roundrect (at 0 0 270) (size 1.4 1.4) (layers "F.Paste") (roundrect_rratio 0.05))
    (pad "" smd roundrect (at 0 1.6 270) (size 1.4 1.4) (layers "F.Paste") (roundrect_rratio 0.05))
    (pad "" smd roundrect (at 1.6 -1.6 270) (size 1.4 1.4) (layers "F.Paste") (roundrect_rratio 0.05))
    (pad "" smd roundrect (at 1.6 0 270) (size 1.4 1.4) (layers "F.Paste") (roundrect_rratio 0.05))
    (pad "" smd roundrect (at 1.6 1.6 270) (size 1.4 1.4) (layers "F.Paste") (roundrect_rratio 0.05))
    (pad "1" smd rect (at -3.476 -2.75 270) (size 0.85 0.28) (layers "F.Cu" "F.Paste" "F.Mask")
      (net 267 "/Ethernet/TD_A_P") (pinfunction "TD_P_A") (pintype "bidirectional"))
    (pad "2" smd rect (at -3.476 -2.25 270) (size 0.85 0.28) (layers "F.Cu" "F.Paste" "F.Mask")
      (net 268 "/Ethernet/TD_A_N") (pinfunction "TD_M_A") (pintype "bidirectional"))
    (pad "3" smd rect (at -3.476 -1.75 270) (size 0.85 0.28) (layers "F.Cu" "F.Paste" "F.Mask")
      (net 16 "PS_2V5") (pinfunction "VDDA2P5") (pintype "power_in"))
    (pad "4" smd rect (at -3.476 -1.25 270) (size 0.85 0.28) (layers "F.Cu" "F.Paste" "F.Mask")
      (net 269 "/Ethernet/TD_B_P") (pinfunction "TD_P_B") (pintype "bidirectional"))
    (pad "5" smd rect (at -3.476 -0.75 270) (size 0.85 0.28) (layers "F.Cu" "F.Paste" "F.Mask")
      (net 270 "/Ethernet/TD_B_N") (pinfunction "TD_M_B") (pintype "bidirectional"))
    (pad "6" smd rect (at -3.476 -0.25 270) (size 0.85 0.28) (layers "F.Cu" "F.Paste" "F.Mask")
      (net 19 "PS_1V0") (pinfunction "VDD1P0") (pintype "passive"))
    (pad "7" smd rect (at -3.476 0.248 270) (size 0.85 0.28) (layers "F.Cu" "F.Paste" "F.Mask")
      (net 271 "/Ethernet/TD_C_P") (pinfunction "TD_P_C") (pintype "bidirectional"))
    (pad "8" smd rect (at -3.476 0.748 270) (size 0.85 0.28) (layers "F.Cu" "F.Paste" "F.Mask")
      (net 272 "/Ethernet/TD_C_N") (pinfunction "TD_M_C") (pintype "bidirectional"))
    (pad "9" smd rect (at -3.476 1.249 270) (size 0.85 0.28) (layers "F.Cu" "F.Paste" "F.Mask")
      (net 16 "PS_2V5") (pinfunction "VDDA2P5") (pintype "passive"))
    (pad "10" smd rect (at -3.476 1.749 270) (size 0.85 0.28) (layers "F.Cu" "F.Paste" "F.Mask")
      (net 273 "/Ethernet/TD_D_P") (pinfunction "TD_P_D") (pintype "bidirectional"))
    (pad "11" smd rect (at -3.476 2.249 270) (size 0.85 0.28) (layers "F.Cu" "F.Paste" "F.Mask")
      (net 274 "/Ethernet/TD_D_N") (pinfunction "TD_M_D") (pintype "bidirectional"))
    (pad "12" smd rect (at -3.476 2.749 270) (size 0.85 0.28) (layers "F.Cu" "F.Paste" "F.Mask")
      (net 671 "Net-(U30-RBIAS)") (pinfunction "RBIAS") (pintype "passive"))
    (pad "13" smd rect (at -2.75 3.475 270) (size 0.28 0.85) (layers "F.Cu" "F.Paste" "F.Mask")
      (net 724 "unconnected-(U30-VDDA1P8-Pad13)") (pinfunction "VDDA1P8") (pintype "power_in+no_connect"))
    (pad "14" smd rect (at -2.25 3.475 270) (size 0.28 0.85) (layers "F.Cu" "F.Paste" "F.Mask")
      (net 725 "unconnected-(U30-X_O-Pad14)") (pinfunction "X_O") (pintype "bidirectional+no_connect"))
    (pad "15" smd rect (at -1.75 3.475 270) (size 0.28 0.85) (layers "F.Cu" "F.Paste" "F.Mask")
      (net 295 "/Ethernet/X_I") (pinfunction "X_I") (pintype "bidirectional"))
    (pad "16" smd rect (at -1.25 3.475 270) (size 0.28 0.85) (layers "F.Cu" "F.Paste" "F.Mask")
      (net 49 "/Ethernet/MIO76") (pinfunction "MDC") (pintype "input"))
    (pad "17" smd rect (at -0.75 3.475 270) (size 0.28 0.85) (layers "F.Cu" "F.Paste" "F.Mask")
      (net 50 "/Ethernet/MIO77") (pinfunction "MDIO") (pintype "bidirectional"))
    (pad "18" smd rect (at -0.25 3.475 270) (size 0.28 0.85) (layers "F.Cu" "F.Paste" "F.Mask")
      (net 726 "unconnected-(U30-CLK_OUT-Pad18)") (pinfunction "CLK_OUT") (pintype "output+no_connect"))
    (pad "19" smd rect (at 0.248 3.475 270) (size 0.28 0.85) (layers "F.Cu" "F.Paste" "F.Mask")
      (net 17 "PS_1V8") (pinfunction "VDDIO") (pintype "power_in"))
    (pad "20" smd rect (at 0.748 3.475 270) (size 0.28 0.85) (layers "F.Cu" "F.Paste" "F.Mask")
      (net 673 "Net-(U30-JTAG_CLK)") (pinfunction "JTAG_CLK") (pintype "input"))
    (pad "21" smd rect (at 1.249 3.475 270) (size 0.28 0.85) (layers "F.Cu" "F.Paste" "F.Mask")
      (net 727 "unconnected-(U30-JTAG_TDO-Pad21)") (pinfunction "JTAG_TDO") (pintype "output+no_connect"))
    (pad "22" smd rect (at 1.749 3.475 270) (size 0.28 0.85) (layers "F.Cu" "F.Paste" "F.Mask")
      (net 674 "Net-(U30-JTAG_TMS)") (pinfunction "JTAG_TMS") (pintype "input"))
    (pad "23" smd rect (at 2.249 3.475 270) (size 0.28 0.85) (layers "F.Cu" "F.Paste" "F.Mask")
      (net 672 "Net-(U30-JTAG_TDI)") (pinfunction "JTAG_TDI") (pintype "input"))
    (pad "24" smd rect (at 2.749 3.475 270) (size 0.28 0.85) (layers "F.Cu" "F.Paste" "F.Mask")
      (net 19 "PS_1V0") (pinfunction "VDD1P0") (pintype "power_in"))
    (pad "25" smd rect (at 3.475 2.749 270) (size 0.85 0.28) (layers "F.Cu" "F.Paste" "F.Mask")
      (net 33 "/Ethernet/MIO68") (pinfunction "TX_D3") (pintype "input"))
    (pad "26" smd rect (at 3.475 2.249 270) (size 0.85 0.28) (layers "F.Cu" "F.Paste" "F.Mask")
      (net 32 "/Ethernet/MIO67") (pinfunction "TX_D2") (pintype "input"))
    (pad "27" smd rect (at 3.475 1.749 270) (size 0.85 0.28) (layers "F.Cu" "F.Paste" "F.Mask")
      (net 36 "/Ethernet/MIO66") (pinfunction "TX_D1") (pintype "input"))
    (pad "28" smd rect (at 3.475 1.249 270) (size 0.85 0.28) (layers "F.Cu" "F.Paste" "F.Mask")
      (net 35 "/Ethernet/MIO65") (pinfunction "TX_D0") (pintype "input"))
    (pad "29" smd rect (at 3.475 0.748 270) (size 0.85 0.28) (layers "F.Cu" "F.Paste" "F.Mask")
      (net 25 "/Ethernet/MIO64") (pinfunction "GTX_CLK") (pintype "input"))
    (pad "30" smd rect (at 3.475 0.248 270) (size 0.85 0.28) (layers "F.Cu" "F.Paste" "F.Mask")
      (net 17 "PS_1V8") (pinfunction "VDDIO") (pintype "passive"))
    (pad "31" smd rect (at 3.475 -0.25 270) (size 0.85 0.28) (layers "F.Cu" "F.Paste" "F.Mask")
      (net 19 "PS_1V0") (pinfunction "VDD1P0") (pintype "passive"))
    (pad "32" smd rect (at 3.475 -0.75 270) (size 0.85 0.28) (layers "F.Cu" "F.Paste" "F.Mask")
      (net 29 "/Ethernet/MIO70") (pinfunction "RX_CLK") (pintype "output"))
    (pad "33" smd rect (at 3.475 -1.25 270) (size 0.85 0.28) (layers "F.Cu" "F.Paste" "F.Mask")
      (net 30 "/Ethernet/MIO71") (pinfunction "RX_D0") (pintype "output"))
    (pad "34" smd rect (at 3.475 -1.75 270) (size 0.85 0.28) (layers "F.Cu" "F.Paste" "F.Mask")
      (net 31 "/Ethernet/MIO72") (pinfunction "RX_D1") (pintype "output"))
    (pad "35" smd rect (at 3.475 -2.25 270) (size 0.85 0.28) (layers "F.Cu" "F.Paste" "F.Mask")
      (net 26 "/Ethernet/MIO73") (pinfunction "RX_D2") (pintype "output"))
    (pad "36" smd rect (at 3.475 -2.75 270) (size 0.85 0.28) (layers "F.Cu" "F.Paste" "F.Mask")
      (net 27 "/Ethernet/MIO74") (pinfunction "RX_D3") (pintype "output"))
    (pad "37" smd rect (at 2.749 -3.476 270) (size 0.28 0.85) (layers "F.Cu" "F.Paste" "F.Mask")
      (net 34 "/Ethernet/MIO69") (pinfunction "TX_EN_TX_CTRL") (pintype "input"))
    (pad "38" smd rect (at 2.249 -3.476 270) (size 0.28 0.85) (layers "F.Cu" "F.Paste" "F.Mask")
      (net 28 "/Ethernet/MIO75") (pinfunction "RX_DV_RX_CTRL") (pintype "output"))
    (pad "39" smd rect (at 1.749 -3.476 270) (size 0.28 0.85) (layers "F.Cu" "F.Paste" "F.Mask")
      (net 728 "unconnected-(U30-GPIO_0-Pad39)") (pinfunction "GPIO_0") (pintype "output+no_connect"))
    (pad "40" smd rect (at 1.249 -3.476 270) (size 0.28 0.85) (layers "F.Cu" "F.Paste" "F.Mask")
      (net 729 "unconnected-(U30-GPIO_1-Pad40)") (pinfunction "GPIO_1") (pintype "output+no_connect"))
    (pad "41" smd rect (at 0.748 -3.476 270) (size 0.28 0.85) (layers "F.Cu" "F.Paste" "F.Mask")
      (net 17 "PS_1V8") (pinfunction "VDDIO") (pintype "passive"))
    (pad "42" smd rect (at 0.248 -3.476 270) (size 0.28 0.85) (layers "F.Cu" "F.Paste" "F.Mask")
      (net 19 "PS_1V0") (pinfunction "VDD1P0") (pintype "passive"))
    (pad "43" smd rect (at -0.25 -3.476 270) (size 0.28 0.85) (layers "F.Cu" "F.Paste" "F.Mask")
      (net 176 "/Ethernet/~{ETH_RESET}") (pinfunction "RESET_N") (pintype "input"))
    (pad "44" smd rect (at -0.75 -3.476 270) (size 0.28 0.85) (layers "F.Cu" "F.Paste" "F.Mask")
      (net 670 "Net-(U30-INT_PWDN)") (pinfunction "INT_PWDN") (pintype "bidirectional"))
    (pad "45" smd rect (at -1.25 -3.476 270) (size 0.28 0.85) (layers "F.Cu" "F.Paste" "F.Mask")
      (net 51 "/Ethernet/LED2") (pinfunction "LED_2") (pintype "bidirectional"))
    (pad "46" smd rect (at -1.75 -3.476 270) (size 0.28 0.85) (layers "F.Cu" "F.Paste" "F.Mask")
      (net 730 "unconnected-(U30-LED_1-Pad46)") (pinfunction "LED_1") (pintype "bidirectional+no_connect"))
    (pad "47" smd rect (at -2.25 -3.476 270) (size 0.28 0.85) (layers "F.Cu" "F.Paste" "F.Mask")
      (net 364 "/Ethernet/LED0") (pinfunction "LED_0") (pintype "bidirectional"))
    (pad "48" smd rect (at -2.75 -3.476 270) (size 0.28 0.85) (layers "F.Cu" "F.Paste" "F.Mask")
      (net 731 "unconnected-(U30-VDDA1P8-Pad48)") (pinfunction "VDDA1P8") (pintype "power_in+no_connect"))
    (pad "49" smd rect (at 0 0 270) (size 5.15 5.15) (layers "F.Cu" "F.Mask")
      (net 1 "GND") (pinfunction "PAD") (pintype "power_in"))
  )

  (footprint "kria-k26-devboard-footprints:C_0402_1005Metric" (layer "F.Cu")
    (at 154.116622 89.167588)
    (descr "Capacitor SMD 0402")
    (tags "capacitor SMD 0402")
    (property "Author" "Antmicro")
    (property "Dielectric" "X5R")
    (property "License" "Apache-2.0")
    (property "MPN" "GRM155R61H104KE14D")
    (property "Manufacturer" "Murata")
    (property "Sheetfile" "eth.kicad_sch")
    (property "Sheetname" "Ethernet")
    (property "Val" "100n")
    (property "Voltage" "50V")
    (property "ki_description" " ")
    (attr smd)
    (fp_text reference "C108" (at 0.743378 -0.237588) (layer "F.SilkS")
        (effects (font (size 0.7 0.7) (thickness 0.15)) (justify left bottom))
    )
    (fp_text value "C_100n_0402" (at 0 1.4) (layer "F.Fab") hide
        (effects (font (size 0.7 0.7) (thickness 0.15)) (justify left bottom))
    )
    (fp_text user "${REFERENCE}" (at -0.932 3.168) (layer "F.Fab") hide
        (effects (font (size 0.7 0.7) (thickness 0.15)) (justify left bottom))
    )
    (fp_text user "License: Apache-2.0" (at -0.932 5.17) (layer "F.Fab") hide
        (effects (font (size 0.7 0.7) (thickness 0.15)) (justify left bottom))
    )
    (fp_text user "Author: Antmicro" (at -0.932 4.17) (layer "F.Fab") hide
        (effects (font (size 0.7 0.7) (thickness 0.15)) (justify left bottom))
    )
    (fp_rect (start -0.94 -0.47) (end 0.94 0.47)
      (stroke (width 0.05) (type solid)) (fill none) (layer "F.CrtYd"))
    (fp_rect (start -0.499 -0.249) (end 0.499 0.249)
      (stroke (width 0.15) (type solid)) (fill none) (layer "F.Fab"))
    (pad "1" smd roundrect (at -0.484 0) (size 0.59 0.64) (layers "F.Cu" "F.Paste" "F.Mask") (roundrect_rratio 0.25)
      (net 19 "PS_1V0") (pintype "passive"))
    (pad "2" smd roundrect (at 0.484 0) (size 0.59 0.64) (layers "F.Cu" "F.Paste" "F.Mask") (roundrect_rratio 0.25)
      (net 1 "GND") (pintype "passive"))
  )

  (footprint "kria-k26-devboard-footprints:Oscillator_SMD_ECS_2016MV_2x1.6x0.85mm" (layer "F.Cu")
    (at 142.719954 86.358222 90)
    (property "Author" "Antmicro")
    (property "License" "Apache-2.0")
    (property "MPN" "ECS-2016MV-250-CN-TR")
    (property "Manufacturer" "ECS Inc. International")
    (property "Sheetfile" "eth.kicad_sch")
    (property "Sheetname" "Ethernet")
    (property "VAL" "25 MHz")
    (property "Val" "25 MHz")
    (property "ki_description" "Oscillator, 25 MHz, HCMOS, SMD, 2mm x 1.6mm, MultiVolt ECS-2016MV Series")
    (property "ki_keywords" "OSCILLATOR")
    (attr smd)
    (fp_text reference "Y6" (at 1.118222 -1.419954) (layer "F.SilkS")
        (effects (font (size 0.7 0.7) (thickness 0.15)) (justify left bottom))
    )
    (fp_text value "Oscillator_25MHz_ESC_2016MV" (at 0 2.2 90) (layer "F.Fab") hide
        (effects (font (size 0.7 0.7) (thickness 0.15)) (justify left bottom))
    )
    (fp_text user "${REFERENCE}" (at -1.05 3.4 90) (layer "F.Fab") hide
        (effects (font (size 0.7 0.7) (thickness 0.15)) (justify left bottom))
    )
    (fp_text user "License: Apache-2.0" (at -1.05 5.8 90) (layer "F.Fab") hide
        (effects (font (size 0.7 0.7) (thickness 0.15)) (justify left bottom))
    )
    (fp_text user "Author: Antmicro" (at -1.05 4.6 90) (layer "F.Fab") hide
        (effects (font (size 0.7 0.7) (thickness 0.15)) (justify left bottom))
    )
    (fp_line (start -0.95 0.4) (end -0.95 -0.4)
      (stroke (width 0.15) (type solid)) (layer "F.SilkS"))
    (fp_line (start -0.4 -1.15) (end 0.4 -1.15)
      (stroke (width 0.15) (type solid)) (layer "F.SilkS"))
    (fp_line (start -0.4 1.15) (end 0.4 1.15)
      (stroke (width 0.15) (type solid)) (layer "F.SilkS"))
    (fp_line (start 0.95 0.4) (end 0.95 -0.4)
      (stroke (width 0.15) (type solid)) (layer "F.SilkS"))
    (fp_circle (center -0.95 -1.15) (end -0.9 -1.15)
      (stroke (width 0.15) (type solid)) (fill solid) (layer "F.SilkS"))
    (fp_rect (start -1.05 -1.25) (end 1.05 1.24)
      (stroke (width 0.05) (type solid)) (fill none) (layer "F.CrtYd"))
    (fp_rect (start -0.85 -1.054) (end 0.852 1.054)
      (stroke (width 0.15) (type solid)) (fill none) (layer "F.Fab"))
    (pad "1" smd rect (at -0.486 -0.637 90) (size 0.6858 0.7874) (layers "F.Cu" "F.Paste" "F.Mask")
      (net 803 "unconnected-(Y6-EN-Pad1)") (pinfunction "EN") (pintype "input+no_connect"))
    (pad "2" smd rect (at -0.486 0.636 90) (size 0.6858 0.7874) (layers "F.Cu" "F.Paste" "F.Mask")
      (net 1 "GND") (pinfunction "GND") (pintype "power_in"))
    (pad "3" smd rect (at 0.487 0.636 90) (size 0.6858 0.7874) (layers "F.Cu" "F.Paste" "F.Mask")
      (net 295 "/Ethernet/X_I") (pinfunction "OUT") (pintype "output"))
    (pad "4" smd rect (at 0.487 -0.637 90) (size 0.6858 0.7874) (layers "F.Cu" "F.Paste" "F.Mask")
      (net 17 "PS_1V8") (pinfunction "VDD") (pintype "power_in"))
  )

  (footprint "kria-k26-devboard-footprints:C_0402_1005Metric" (layer "F.Cu")
    (at 143.7 91.514035 180)
    (descr "Capacitor SMD 0402")
    (tags "capacitor SMD 0402")
    (property "Author" "Antmicro")
    (property "Dielectric" "X5R")
    (property "License" "Apache-2.0")
    (property "MPN" "GRM155R61H104KE14D")
    (property "Manufacturer" "Murata")
    (property "Sheetfile" "eth.kicad_sch")
    (property "Sheetname" "Ethernet")
    (property "Val" "100n")
    (property "Voltage" "50V")
    (property "ki_description" " ")
    (attr smd)
    (fp_text reference "C106" (at 1.42 -1.365965 180) (layer "F.SilkS")
        (effects (font (size 0.7 0.7) (thickness 0.15)) (justify left bottom))
    )
    (fp_text value "C_100n_0402" (at 0 1.4 180) (layer "F.Fab") hide
        (effects (font (size 0.7 0.7) (thickness 0.15)) (justify left bottom))
    )
    (fp_text user "${REFERENCE}" (at -0.932 3.168 180) (layer "F.Fab") hide
        (effects (font (size 0.7 0.7) (thickness 0.15)) (justify left bottom))
    )
    (fp_text user "License: Apache-2.0" (at -0.932 5.17 180) (layer "F.Fab") hide
        (effects (font (size 0.7 0.7) (thickness 0.15)) (justify left bottom))
    )
    (fp_text user "Author: Antmicro" (at -0.932 4.17 180) (layer "F.Fab") hide
        (effects (font (size 0.7 0.7) (thickness 0.15)) (justify left bottom))
    )
    (fp_rect (start -0.94 -0.47) (end 0.94 0.47)
      (stroke (width 0.05) (type solid)) (fill none) (layer "F.CrtYd"))
    (fp_rect (start -0.499 -0.249) (end 0.499 0.249)
      (stroke (width 0.15) (type solid)) (fill none) (layer "F.Fab"))
    (pad "1" smd roundrect (at -0.484 0 180) (size 0.59 0.64) (layers "F.Cu" "F.Paste" "F.Mask") (roundrect_rratio 0.25)
      (net 19 "PS_1V0") (pintype "passive"))
    (pad "2" smd roundrect (at 0.484 0 180) (size 0.59 0.64) (layers "F.Cu" "F.Paste" "F.Mask") (roundrect_rratio 0.25)
      (net 1 "GND") (pintype "passive"))
  )

  (footprint "kria-k26-devboard-footprints:R_0402_1005Metric" (layer "F.Cu")
    (at 154.161522 87.530152 180)
    (descr "Resistor SMD 0402")
    (tags "resistor SMD 0402")
    (property "Author" "Antmicro")
    (property "License" "Apache-2.0")
    (property "MPN" "CR0402-FX-2201GLF")
    (property "Manufacturer" "Bourns")
    (property "Sheetfile" "eth.kicad_sch")
    (property "Sheetname" "Ethernet")
    (property "Tolerance" "1%")
    (property "Val" "2k2")
    (property "ki_description" "2k2 resistor in 0402 package with 1% tolerance")
    (attr smd)
    (fp_text reference "R71" (at 0.681522 0.490152 180) (layer "F.SilkS")
        (effects (font (size 0.7 0.7) (thickness 0.15)) (justify left bottom))
    )
    (fp_text value "R_2k2_0402" (at 0 1.4 180) (layer "F.Fab") hide
        (effects (font (size 0.7 0.7) (thickness 0.15)) (justify left bottom))
    )
    (fp_text user "${REFERENCE}" (at -0.95 3.168 180) (layer "F.Fab") hide
        (effects (font (size 0.7 0.7) (thickness 0.15)) (justify left bottom))
    )
    (fp_text user "License: Apache-2.0" (at -0.95 5.169 180) (layer "F.Fab") hide
        (effects (font (size 0.7 0.7) (thickness 0.15)) (justify left bottom))
    )
    (fp_text user "Author: Antmicro" (at -0.95 4.169 180) (layer "F.Fab") hide
        (effects (font (size 0.7 0.7) (thickness 0.15)) (justify left bottom))
    )
    (fp_rect (start -0.93 -0.47) (end 0.93 0.47)
      (stroke (width 0.05) (type solid)) (fill none) (layer "F.CrtYd"))
    (fp_rect (start -0.5 -0.25) (end 0.5 0.25)
      (stroke (width 0.15) (type solid)) (fill none) (layer "F.Fab"))
    (pad "1" smd roundrect (at -0.485 0 180) (size 0.59 0.64) (layers "F.Cu" "F.Paste" "F.Mask") (roundrect_rratio 0.25)
      (net 17 "PS_1V8") (pintype "passive"))
    (pad "2" smd roundrect (at 0.485 0 180) (size 0.59 0.64) (layers "F.Cu" "F.Paste" "F.Mask") (roundrect_rratio 0.25)
      (net 670 "Net-(U30-INT_PWDN)") (pintype "passive"))
  )

  (footprint "kria-k26-devboard-footprints:R_0402_1005Metric" (layer "F.Cu")
    (at 145.24 83.95 90)
    (descr "Resistor SMD 0402")
    (tags "resistor SMD 0402")
    (property "Author" "Antmicro")
    (property "License" "Apache-2.0")
    (property "MPN" "CR0402-FX-1102GLF")
    (property "Manufacturer" "Bourns")
    (property "Sheetfile" "eth.kicad_sch")
    (property "Sheetname" "Ethernet")
    (property "Tolerance" "1%")
    (property "Val" "11k")
    (property "ki_description" "11k resistor in 0402 package with 1% tolerance")
    (attr smd)
    (fp_text reference "R72" (at -0.952159 -0.649464 90) (layer "F.SilkS")
        (effects (font (size 0.7 0.7) (thickness 0.15)) (justify left bottom))
    )
    (fp_text value "R_11k_0402" (at 0 1.4 90) (layer "F.Fab") hide
        (effects (font (size 0.7 0.7) (thickness 0.15)) (justify left bottom))
    )
    (fp_text user "License: Apache-2.0" (at -0.95 5.169 90) (layer "F.Fab") hide
        (effects (font (size 0.7 0.7) (thickness 0.15)) (justify left bottom))
    )
    (fp_text user "${REFERENCE}" (at -0.95 3.168 90) (layer "F.Fab") hide
        (effects (font (size 0.7 0.7) (thickness 0.15)) (justify left bottom))
    )
    (fp_text user "Author: Antmicro" (at -0.95 4.169 90) (layer "F.Fab") hide
        (effects (font (size 0.7 0.7) (thickness 0.15)) (justify left bottom))
    )
    (fp_rect (start -0.93 -0.47) (end 0.93 0.47)
      (stroke (width 0.05) (type solid)) (fill none) (layer "F.CrtYd"))
    (fp_rect (start -0.5 -0.25) (end 0.5 0.25)
      (stroke (width 0.15) (type solid)) (fill none) (layer "F.Fab"))
    (pad "1" smd roundrect (at -0.485 0 90) (size 0.59 0.64) (layers "F.Cu" "F.Paste" "F.Mask") (roundrect_rratio 0.25)
      (net 671 "Net-(U30-RBIAS)") (pintype "passive"))
    (pad "2" smd roundrect (at 0.485 0 90) (size 0.59 0.64) (layers "F.Cu" "F.Paste" "F.Mask") (roundrect_rratio 0.25)
      (net 1 "GND") (pintype "passive"))
  )

  (footprint "kria-k26-devboard-footprints:SOT-416" (layer "F.Cu")
    (at 154.73 70.1 90)
    (descr "SOT-416")
    (tags "SOT-416")
    (property "Author" "Antmicro")
    (property "License" "Apache-2.0")
    (property "MPN" "DTC014TEBTL")
    (property "Manufacturer" "ROHM Semiconductor")
    (property "Sheetfile" "eth.kicad_sch")
    (property "Sheetname" "Ethernet")
    (property "ki_description" "Digital NPN Transistor, 10k/NONE, EMT-3")
    (attr smd)
    (fp_text reference "Q4" (at -1.9 -0.84 180) (layer "F.SilkS")
        (effects (font (size 0.7 0.7) (thickness 0.15)) (justify left bottom))
    )
    (fp_text value "DTC014T_SOT-416" (at 0 2 90) (layer "F.Fab") hide
        (effects (font (size 0.7 0.7) (thickness 0.15)) (justify left bottom))
    )
    (fp_text user "${REFERENCE}" (at -1 3.4 90) (layer "F.Fab") hide
        (effects (font (size 0.7 0.7) (thickness 0.15)) (justify left bottom))
    )
    (fp_text user "License: Apache-2.0" (at -1 5.802 90) (layer "F.Fab") hide
        (effects (font (size 0.7 0.7) (thickness 0.15)) (justify left bottom))
    )
    (fp_text user "Author: Antmicro" (at -1 4.602 90) (layer "F.Fab") hide
        (effects (font (size 0.7 0.7) (thickness 0.15)) (justify left bottom))
    )
    (fp_line (start -0.5 -0.15) (end -0.5 0.15)
      (stroke (width 0.15) (type solid)) (layer "F.SilkS"))
    (fp_line (start 0.5 0.9) (end -0.5 0.9)
      (stroke (width 0.15) (type solid)) (layer "F.SilkS"))
    (fp_line (start 0.5 0.9) (end 0.5 0.7)
      (stroke (width 0.15) (type solid)) (layer "F.SilkS"))
    (fp_line (start 0.508 -0.9) (end -0.5 -0.9)
      (stroke (width 0.15) (type solid)) (layer "F.SilkS"))
    (fp_line (start 0.508 -0.9) (end 0.508 -0.592)
      (stroke (width 0.15) (type solid)) (layer "F.SilkS"))
    (fp_rect (start -1 -1.05) (end 1 1.05)
      (stroke (width 0.05) (type solid)) (fill none) (layer "F.CrtYd"))
    (fp_line (start -0.05 -0.9) (end -0.45 -0.5)
      (stroke (width 0.15) (type solid)) (layer "F.Fab"))
    (fp_rect (start 0.45 0.9) (end -0.45 -0.9)
      (stroke (width 0.15) (type solid)) (fill none) (layer "F.Fab"))
    (pad "1" smd rect (at -0.652 -0.5 90) (size 0.6 0.5) (layers "F.Cu" "F.Paste" "F.Mask")
      (net 364 "/Ethernet/LED0") (pinfunction "B") (pintype "input"))
    (pad "2" smd rect (at -0.652 0.498 90) (size 0.6 0.5) (layers "F.Cu" "F.Paste" "F.Mask")
      (net 1 "GND") (pinfunction "E") (pintype "passive"))
    (pad "3" smd rect (at 0.65 0 90) (size 0.6 0.5) (layers "F.Cu" "F.Paste" "F.Mask")
      (net 351 "Net-(J5-LED_GRN-)") (pinfunction "C") (pintype "passive"))
  )

  (footprint "kria-k26-devboard-footprints:SOT-416" (layer "F.Cu")
    (at 152.62 70.1 90)
    (descr "SOT-416")
    (tags "SOT-416")
    (property "Author" "Antmicro")
    (property "License" "Apache-2.0")
    (property "MPN" "DTC014TEBTL")
    (property "Manufacturer" "ROHM Semiconductor")
    (property "Sheetfile" "eth.kicad_sch")
    (property "Sheetname" "Ethernet")
    (property "ki_description" "Digital NPN Transistor, 10k/NONE, EMT-3")
    (attr smd)
    (fp_text reference "Q5" (at -1.88 -0.72 180) (layer "F.SilkS")
        (effects (font (size 0.7 0.7) (thickness 0.15)) (justify left bottom))
    )
    (fp_text value "DTC014T_SOT-416" (at 0 2 90) (layer "F.Fab") hide
        (effects (font (size 0.7 0.7) (thickness 0.15)) (justify left bottom))
    )
    (fp_text user "${REFERENCE}" (at -1 3.4 90) (layer "F.Fab") hide
        (effects (font (size 0.7 0.7) (thickness 0.15)) (justify left bottom))
    )
    (fp_text user "Author: Antmicro" (at -1 4.602 90) (layer "F.Fab") hide
        (effects (font (size 0.7 0.7) (thickness 0.15)) (justify left bottom))
    )
    (fp_text user "License: Apache-2.0" (at -1 5.802 90) (layer "F.Fab") hide
        (effects (font (size 0.7 0.7) (thickness 0.15)) (justify left bottom))
    )
    (fp_line (start -0.5 -0.15) (end -0.5 0.15)
      (stroke (width 0.15) (type solid)) (layer "F.SilkS"))
    (fp_line (start 0.5 0.9) (end -0.5 0.9)
      (stroke (width 0.15) (type solid)) (layer "F.SilkS"))
    (fp_line (start 0.5 0.9) (end 0.5 0.7)
      (stroke (width 0.15) (type solid)) (layer "F.SilkS"))
    (fp_line (start 0.508 -0.9) (end -0.5 -0.9)
      (stroke (width 0.15) (type solid)) (layer "F.SilkS"))
    (fp_line (start 0.508 -0.9) (end 0.508 -0.592)
      (stroke (width 0.15) (type solid)) (layer "F.SilkS"))
    (fp_rect (start -1 -1.05) (end 1 1.05)
      (stroke (width 0.05) (type solid)) (fill none) (layer "F.CrtYd"))
    (fp_line (start -0.05 -0.9) (end -0.45 -0.5)
      (stroke (width 0.15) (type solid)) (layer "F.Fab"))
    (fp_rect (start 0.45 0.9) (end -0.45 -0.9)
      (stroke (width 0.15) (type solid)) (fill none) (layer "F.Fab"))
    (pad "1" smd rect (at -0.652 -0.5 90) (size 0.6 0.5) (layers "F.Cu" "F.Paste" "F.Mask")
      (net 51 "/Ethernet/LED2") (pinfunction "B") (pintype "input"))
    (pad "2" smd rect (at -0.652 0.498 90) (size 0.6 0.5) (layers "F.Cu" "F.Paste" "F.Mask")
      (net 1 "GND") (pinfunction "E") (pintype "passive"))
    (pad "3" smd rect (at 0.65 0 90) (size 0.6 0.5) (layers "F.Cu" "F.Paste" "F.Mask")
      (net 353 "Net-(J5-LED_YEL-)") (pinfunction "C") (pintype "passive"))
  )

  (footprint "kria-k26-devboard-footprints:R_0402_1005Metric" (layer "F.Cu")
    (at 131.8 118)
    (descr "Resistor SMD 0402")
    (tags "resistor SMD 0402")
    (property "Author" "Antmicro")
    (property "License" "Apache-2.0")
    (property "MPN" "CR0402-FX-1002GLF")
    (property "Manufacturer" "Bourns")
    (property "Sheetfile" "pcie-m2-key-e.kicad_sch")
    (property "Sheetname" "PCIE M2 key E ")
    (property "Tolerance" "1%")
    (property "Val" "10k")
    (property "ki_description" "10k resistor in 0402 package with 1% tolerance")
    (attr smd)
    (fp_text reference "R151" (at -1.27 -1.56) (layer "F.SilkS")
        (effects (font (size 0.7 0.7) (thickness 0.15)) (justify left bottom))
    )
    (fp_text value "R_10k_0402" (at 0 1.4) (layer "F.Fab") hide
        (effects (font (size 0.7 0.7) (thickness 0.15)) (justify left bottom))
    )
    (fp_text user "Author: Antmicro" (at -0.95 4.169) (layer "F.Fab") hide
        (effects (font (size 0.7 0.7) (thickness 0.15)) (justify left bottom))
    )
    (fp_text user "License: Apache-2.0" (at -0.95 5.169) (layer "F.Fab") hide
        (effects (font (size 0.7 0.7) (thickness 0.15)) (justify left bottom))
    )
    (fp_text user "${REFERENCE}" (at -0.95 3.168) (layer "F.Fab") hide
        (effects (font (size 0.7 0.7) (thickness 0.15)) (justify left bottom))
    )
    (fp_rect (start -0.93 -0.47) (end 0.93 0.47)
      (stroke (width 0.05) (type solid)) (fill none) (layer "F.CrtYd"))
    (fp_rect (start -0.5 -0.25) (end 0.5 0.25)
      (stroke (width 0.15) (type solid)) (fill none) (layer "F.Fab"))
    (pad "1" smd roundrect (at -0.485 0) (size 0.59 0.64) (layers "F.Cu" "F.Paste" "F.Mask") (roundrect_rratio 0.25)
      (net 15 "PS_3V3") (pintype "passive"))
    (pad "2" smd roundrect (at 0.485 0) (size 0.59 0.64) (layers "F.Cu" "F.Paste" "F.Mask") (roundrect_rratio 0.25)
      (net 396 "Net-(J12-~{CLKREQ0})") (pintype "passive"))
  )

  (footprint "kria-k26-devboard-footprints:Nexperia_SOD128" (layer "F.Cu")
    (at 143.675 66.65 180)
    (property "Author" "Antmicro")
    (property "DNP" "DNP")
    (property "License" "Apache-2.0")
    (property "MPN" "PMEG3050EP,115")
    (property "Manufacturer" "Nexperia")
    (property "Sheetfile" "supply-oring.kicad_sch")
    (property "Sheetname" "Supply ORing")
    (property "dnp" "")
    (property "exclude_from_bom" "")
    (property "ki_description" "SCHOTTKY RECT 30V 5A, Vf=315 mV")
    (attr exclude_from_pos_files exclude_from_bom)
    (fp_text reference "D24" (at 2.235 -2.45 180) (layer "F.SilkS")
        (effects (font (size 0.7 0.7) (thickness 0.15)) (justify left bottom))
    )
    (fp_text value "PMEG3050EP,115" (at -4.37 2.5 180) (layer "F.Fab") hide
        (effects (font (size 0.7 0.7) (thickness 0.15)) (justify left bottom))
    )
    (fp_text user "${REFERENCE}" (at -4.37 6.9 180) (layer "F.Fab") hide
        (effects (font (size 0.7 0.7) (thickness 0.15)) (justify left bottom))
    )
    (fp_text user "Author: Antmicro" (at -4.37 4.5 180) (layer "F.Fab") hide
        (effects (font (size 0.7 0.7) (thickness 0.15)) (justify left bottom))
    )
    (fp_text user "License: Apache-2.0" (at -4.37 5.7 180) (layer "F.Fab") hide
        (effects (font (size 0.7 0.7) (thickness 0.15)) (justify left bottom))
    )
    (fp_line (start -2.121 -1.474) (end -2.121 -1.287)
      (stroke (width 0.15) (type solid)) (layer "F.SilkS"))
    (fp_line (start -2.121 1.284) (end -2.121 1.473)
      (stroke (width 0.15) (type solid)) (layer "F.SilkS"))
    (fp_line (start -2.121 1.473) (end 2.12 1.473)
      (stroke (width 0.15) (type solid)) (layer "F.SilkS"))
    (fp_line (start -1.6 -1.4) (end -1.6 1.4)
      (stroke (width 0.12) (type solid)) (layer "F.SilkS"))
    (fp_line (start 2.12 -1.474) (end -2.121 -1.474)
      (stroke (width 0.15) (type solid)) (layer "F.SilkS"))
    (fp_line (start 2.12 -1.287) (end 2.12 -1.474)
      (stroke (width 0.15) (type solid)) (layer "F.SilkS"))
    (fp_line (start 2.12 1.473) (end 2.12 1.284)
      (stroke (width 0.15) (type solid)) (layer "F.SilkS"))
    (fp_rect (start -2.8 -1.6) (end 2.8 1.6)
      (stroke (width 0.05) (type solid)) (fill none) (layer "F.CrtYd"))
    (fp_line (start -2.503 -0.954) (end -2.503 0.952)
      (stroke (width 0.15) (type solid)) (layer "F.Fab"))
    (fp_line (start -2.503 0.952) (end -1.994 0.952)
      (stroke (width 0.15) (type solid)) (layer "F.Fab"))
    (fp_line (start -1.994 -1.347) (end -1.994 1.346)
      (stroke (width 0.15) (type solid)) (layer "F.Fab"))
    (fp_line (start -1.994 -0.954) (end -2.503 -0.954)
      (stroke (width 0.15) (type solid)) (layer "F.Fab"))
    (fp_line (start -1.994 -0.675) (end -1.321 -1.347)
      (stroke (width 0.15) (type solid)) (layer "F.Fab"))
    (fp_line (start -1.994 0.673) (end -1.321 1.346)
      (stroke (width 0.15) (type solid)) (layer "F.Fab"))
    (fp_line (start -1.994 0.952) (end -1.994 -0.954)
      (stroke (width 0.15) (type solid)) (layer "F.Fab"))
    (fp_line (start -1.994 1.346) (end 1.993 1.346)
      (stroke (width 0.15) (type solid)) (layer "F.Fab"))
    (fp_line (start 1.993 -1.347) (end -1.994 -1.347)
      (stroke (width 0.15) (type solid)) (layer "F.Fab"))
    (fp_line (start 1.993 -0.954) (end 1.993 0.952)
      (stroke (width 0.15) (type solid)) (layer "F.Fab"))
    (fp_line (start 1.993 0.952) (end 2.5 0.952)
      (stroke (width 0.15) (type solid)) (layer "F.Fab"))
    (fp_line (start 1.993 1.346) (end 1.993 -1.347)
      (stroke (width 0.15) (type solid)) (layer "F.Fab"))
    (fp_line (start 2.5 -0.954) (end 1.993 -0.954)
      (stroke (width 0.15) (type solid)) (layer "F.Fab"))
    (fp_line (start 2.5 0.952) (end 2.5 -0.954)
      (stroke (width 0.15) (type solid)) (layer "F.Fab"))
    (pad "1" smd rect (at -2.298 0 180) (size 0.8096 1.905) (layers "F.Cu" "F.Paste" "F.Mask")
      (net 14 "/Power Supply/DC/DC conventers/DC_MAIN_BUS") (pinfunction "1") (pintype "passive"))
    (pad "2" smd rect (at 2.297 0 180) (size 0.8096 1.905) (layers "F.Cu" "F.Paste" "F.Mask")
      (net 228 "/Power Supply/Supply ORing/PD_VBUS") (pinfunction "2") (pintype "passive"))
  )

  (footprint "kria-k26-devboard-footprints:R_0402_1005Metric" (layer "F.Cu")
    (at 78.475 119.25 -90)
    (descr "Resistor SMD 0402")
    (tags "resistor SMD 0402")
    (property "Author" "Antmicro")
    (property "DNP" "DNP")
    (property "License" "Apache-2.0")
    (property "MPN" "CR0402-FX-1501GLF")
    (property "Manufacturer" "Bourns")
    (property "Sheetfile" "camera.kicad_sch")
    (property "Sheetname" "Camera interface")
    (property "Tolerance" "1%")
    (property "Val" "1k5")
    (property "dnp" "")
    (property "exclude_from_bom" "")
    (property "ki_description" "1k5 resistor in 0402 package with 1% tolerance")
    (attr exclude_from_pos_files exclude_from_bom)
    (fp_text reference "R25" (at -0.85 -0.355 -90) (layer "F.SilkS")
        (effects (font (size 0.7 0.7) (thickness 0.15)) (justify left bottom))
    )
    (fp_text value "R_1k5_0402" (at 0 1.4 -90) (layer "F.Fab") hide
        (effects (font (size 0.7 0.7) (thickness 0.15)) (justify left bottom))
    )
    (fp_text user "${REFERENCE}" (at -0.95 3.168 -90) (layer "F.Fab") hide
        (effects (font (size 0.7 0.7) (thickness 0.15)) (justify left bottom))
    )
    (fp_text user "Author: Antmicro" (at -0.95 4.169 -90) (layer "F.Fab") hide
        (effects (font (size 0.7 0.7) (thickness 0.15)) (justify left bottom))
    )
    (fp_text user "License: Apache-2.0" (at -0.95 5.169 -90) (layer "F.Fab") hide
        (effects (font (size 0.7 0.7) (thickness 0.15)) (justify left bottom))
    )
    (fp_rect (start -0.93 -0.47) (end 0.93 0.47)
      (stroke (width 0.05) (type solid)) (fill none) (layer "F.CrtYd"))
    (fp_rect (start -0.5 -0.25) (end 0.5 0.25)
      (stroke (width 0.15) (type solid)) (fill none) (layer "F.Fab"))
    (pad "1" smd roundrect (at -0.485 0 270) (size 0.59 0.64) (layers "F.Cu" "F.Paste" "F.Mask") (roundrect_rratio 0.25)
      (net 322 "PL_1V8") (pintype "passive"))
    (pad "2" smd roundrect (at 0.485 0 270) (size 0.59 0.64) (layers "F.Cu" "F.Paste" "F.Mask") (roundrect_rratio 0.25)
      (net 193 "/Camera interface/CCI1_I2C_SCL_3V3") (pintype "passive"))
  )

  (footprint "kria-k26-devboard-footprints:R_0402_1005Metric" (layer "F.Cu")
    (at 80.375 119.25 -90)
    (descr "Resistor SMD 0402")
    (tags "resistor SMD 0402")
    (property "Author" "Antmicro")
    (property "DNP" "DNP")
    (property "License" "Apache-2.0")
    (property "MPN" "CR0402-FX-1501GLF")
    (property "Manufacturer" "Bourns")
    (property "Sheetfile" "camera.kicad_sch")
    (property "Sheetname" "Camera interface")
    (property "Tolerance" "1%")
    (property "Val" "1k5")
    (property "dnp" "")
    (property "exclude_from_bom" "")
    (property "ki_description" "1k5 resistor in 0402 package with 1% tolerance")
    (attr exclude_from_pos_files exclude_from_bom)
    (fp_text reference "R26" (at -0.85 -0.355 -90) (layer "F.SilkS")
        (effects (font (size 0.7 0.7) (thickness 0.15)) (justify left bottom))
    )
    (fp_text value "R_1k5_0402" (at 0 1.4 -90) (layer "F.Fab") hide
        (effects (font (size 0.7 0.7) (thickness 0.15)) (justify left bottom))
    )
    (fp_text user "${REFERENCE}" (at -0.95 3.168 -90) (layer "F.Fab") hide
        (effects (font (size 0.7 0.7) (thickness 0.15)) (justify left bottom))
    )
    (fp_text user "Author: Antmicro" (at -0.95 4.169 -90) (layer "F.Fab") hide
        (effects (font (size 0.7 0.7) (thickness 0.15)) (justify left bottom))
    )
    (fp_text user "License: Apache-2.0" (at -0.95 5.169 -90) (layer "F.Fab") hide
        (effects (font (size 0.7 0.7) (thickness 0.15)) (justify left bottom))
    )
    (fp_rect (start -0.93 -0.47) (end 0.93 0.47)
      (stroke (width 0.05) (type solid)) (fill none) (layer "F.CrtYd"))
    (fp_rect (start -0.5 -0.25) (end 0.5 0.25)
      (stroke (width 0.15) (type solid)) (fill none) (layer "F.Fab"))
    (pad "1" smd roundrect (at -0.485 0 270) (size 0.59 0.64) (layers "F.Cu" "F.Paste" "F.Mask") (roundrect_rratio 0.25)
      (net 322 "PL_1V8") (pintype "passive"))
    (pad "2" smd roundrect (at 0.485 0 270) (size 0.59 0.64) (layers "F.Cu" "F.Paste" "F.Mask") (roundrect_rratio 0.25)
      (net 195 "/Camera interface/CCI0_I2C_SCL_3V3") (pintype "passive"))
  )

  (footprint "kria-k26-devboard-footprints:R_0402_1005Metric" (layer "F.Cu")
    (at 79.425 119.25 -90)
    (descr "Resistor SMD 0402")
    (tags "resistor SMD 0402")
    (property "Author" "Antmicro")
    (property "DNP" "DNP")
    (property "License" "Apache-2.0")
    (property "MPN" "CR0402-FX-1501GLF")
    (property "Manufacturer" "Bourns")
    (property "Sheetfile" "camera.kicad_sch")
    (property "Sheetname" "Camera interface")
    (property "Tolerance" "1%")
    (property "Val" "1k5")
    (property "dnp" "")
    (property "exclude_from_bom" "")
    (property "ki_description" "1k5 resistor in 0402 package with 1% tolerance")
    (attr exclude_from_pos_files exclude_from_bom)
    (fp_text reference "R27" (at -0.85 -0.355 -90) (layer "F.SilkS")
        (effects (font (size 0.7 0.7) (thickness 0.15)) (justify left bottom))
    )
    (fp_text value "R_1k5_0402" (at 0 1.4 -90) (layer "F.Fab") hide
        (effects (font (size 0.7 0.7) (thickness 0.15)) (justify left bottom))
    )
    (fp_text user "Author: Antmicro" (at -0.95 4.169 -90) (layer "F.Fab") hide
        (effects (font (size 0.7 0.7) (thickness 0.15)) (justify left bottom))
    )
    (fp_text user "${REFERENCE}" (at -0.95 3.168 -90) (layer "F.Fab") hide
        (effects (font (size 0.7 0.7) (thickness 0.15)) (justify left bottom))
    )
    (fp_text user "License: Apache-2.0" (at -0.95 5.169 -90) (layer "F.Fab") hide
        (effects (font (size 0.7 0.7) (thickness 0.15)) (justify left bottom))
    )
    (fp_rect (start -0.93 -0.47) (end 0.93 0.47)
      (stroke (width 0.05) (type solid)) (fill none) (layer "F.CrtYd"))
    (fp_rect (start -0.5 -0.25) (end 0.5 0.25)
      (stroke (width 0.15) (type solid)) (fill none) (layer "F.Fab"))
    (pad "1" smd roundrect (at -0.485 0 270) (size 0.59 0.64) (layers "F.Cu" "F.Paste" "F.Mask") (roundrect_rratio 0.25)
      (net 322 "PL_1V8") (pintype "passive"))
    (pad "2" smd roundrect (at 0.485 0 270) (size 0.59 0.64) (layers "F.Cu" "F.Paste" "F.Mask") (roundrect_rratio 0.25)
      (net 194 "/Camera interface/CCI1_I2C_SDA_3V3") (pintype "passive"))
  )

  (footprint "kria-k26-devboard-footprints:SOT-563" (layer "F.Cu")
    (at 113.22 74.26 90)
    (property "Author" "Antmicro")
    (property "License" "Apache-2.0")
    (property "MPN" "82400152")
    (property "Manufacturer" "Würth Elektronik")
    (property "Sheetfile" "usb.kicad_sch")
    (property "Sheetname" "USB")
    (property "ki_description" "TVS diode")
    (property "ki_keywords" "SMT, DIODE, IC, ESD, TVS")
    (attr smd)
    (fp_text reference "U26" (at -2.04 -1.21 180) (layer "F.SilkS")
        (effects (font (size 0.7 0.7) (thickness 0.15)) (justify left bottom))
    )
    (fp_text value "82400152" (at 0 2 90) (layer "F.Fab") hide
        (effects (font (size 0.7 0.7) (thickness 0.15)) (justify left bottom))
    )
    (fp_text user "Author: Antmicro" (at -1.299 6.124 90) (layer "F.Fab") hide
        (effects (font (size 0.7 0.7) (thickness 0.15)) (justify left bottom))
    )
    (fp_text user "License: Apache-2.0" (at -1.299 4.924 90) (layer "F.Fab") hide
        (effects (font (size 0.7 0.7) (thickness 0.15)) (justify left bottom))
    )
    (fp_text user "${REFERENCE}" (at -1.299 7.323 90) (layer "F.Fab") hide
        (effects (font (size 0.7 0.7) (thickness 0.15)) (justify left bottom))
    )
    (fp_line (start -0.778 0.776) (end -0.778 0.949)
      (stroke (width 0.15) (type solid)) (layer "F.SilkS"))
    (fp_line (start -0.778 0.949) (end -0.424 0.949)
      (stroke (width 0.15) (type solid)) (layer "F.SilkS"))
    (fp_line (start -0.499 -0.974) (end -0.724 -0.778)
      (stroke (width 0.15) (type solid)) (layer "F.SilkS"))
    (fp_line (start 0.776 -0.974) (end 0.526 -0.974)
      (stroke (width 0.15) (type solid)) (layer "F.SilkS"))
    (fp_line (start 0.776 -0.974) (end 0.776 -0.778)
      (stroke (width 0.15) (type solid)) (layer "F.SilkS"))
    (fp_line (start 0.776 0.776) (end 0.776 0.972)
      (stroke (width 0.15) (type solid)) (layer "F.SilkS"))
    (fp_line (start 0.776 0.972) (end 0.526 0.972)
      (stroke (width 0.15) (type solid)) (layer "F.SilkS"))
    (fp_circle (center -0.903 -0.999) (end -0.952 -0.95)
      (stroke (width 0.15) (type solid)) (fill solid) (layer "F.SilkS"))
    (fp_rect (start 1.19 -1.12) (end -1.2 1.1)
      (stroke (width 0.05) (type solid)) (fill none) (layer "F.CrtYd"))
    (fp_line (start -0.653 -0.678) (end -0.653 0.847)
      (stroke (width 0.15) (type solid)) (layer "F.Fab"))
    (fp_line (start -0.453 -0.849) (end -0.653 -0.678)
      (stroke (width 0.15) (type solid)) (layer "F.Fab"))
    (fp_line (start -0.453 -0.849) (end 0.651 -0.849)
      (stroke (width 0.15) (type solid)) (layer "F.Fab"))
    (fp_line (start 0.651 -0.849) (end 0.651 0.847)
      (stroke (width 0.15) (type solid)) (layer "F.Fab"))
    (fp_line (start 0.651 0.847) (end -0.653 0.847)
      (stroke (width 0.15) (type solid)) (layer "F.Fab"))
    (pad "1" smd roundrect (at -0.749 -0.499) (size 0.3 0.6) (layers "F.Cu" "F.Paste" "F.Mask") (roundrect_rratio 0.25)
      (net 78 "/USB/USB4_P") (pintype "passive"))
    (pad "2" smd roundrect (at -0.749 0.001) (size 0.3 0.6) (layers "F.Cu" "F.Paste" "F.Mask") (roundrect_rratio 0.25)
      (net 1 "GND") (pintype "passive"))
    (pad "3" smd roundrect (at -0.749 0.497) (size 0.3 0.6) (layers "F.Cu" "F.Paste" "F.Mask") (roundrect_rratio 0.25)
      (net 77 "/USB/USB4_N") (pintype "passive"))
    (pad "4" smd roundrect (at 0.747 0.497) (size 0.3 0.6) (layers "F.Cu" "F.Paste" "F.Mask") (roundrect_rratio 0.25)
      (net 292 "/USB/USB4_TVS_N") (pintype "passive"))
    (pad "5" smd roundrect (at 0.747 0.001) (size 0.3 0.6) (layers "F.Cu" "F.Paste" "F.Mask") (roundrect_rratio 0.25)
      (net 87 "/USB/USB4_VBUS") (pintype "passive"))
    (pad "6" smd roundrect (at 0.747 -0.499) (size 0.3 0.6) (layers "F.Cu" "F.Paste" "F.Mask") (roundrect_rratio 0.25)
      (net 293 "/USB/USB4_TVS_P") (pintype "passive"))
  )

  (footprint "kria-k26-devboard-footprints:DFN-14-1EP_4x3mm_P0.5mm" (layer "F.Cu")
    (at 145.525 66.25)
    (property "Author" "Antmicro")
    (property "License" "Apache-2.0")
    (property "MPN" "LTC4358CDE#PBF")
    (property "Manufacturer" "Analog Devices")
    (property "Sheetfile" "supply-oring.kicad_sch")
    (property "Sheetname" "Supply ORing")
    (property "ki_description" "Ideal diode")
    (property "ki_keywords" "SMT, PMIC, IC, POWER, MANAGEMENT, DIODE, CONTROLLER")
    (attr smd)
    (fp_text reference "U57" (at -1.245 3.16) (layer "F.SilkS")
        (effects (font (size 0.7 0.7) (thickness 0.15)) (justify left bottom))
    )
    (fp_text value "LTC4358CDE" (at 0 3.2) (layer "F.Fab") hide
        (effects (font (size 0.7 0.7) (thickness 0.15)) (justify left bottom))
    )
    (fp_text user "Author: Antmicro" (at -0.659 6.998) (layer "F.Fab") hide
        (effects (font (size 0.7 0.7) (thickness 0.15)) (justify left bottom))
    )
    (fp_text user "License: Apache-2.0" (at -0.659 8.198) (layer "F.Fab") hide
        (effects (font (size 0.7 0.7) (thickness 0.15)) (justify left bottom))
    )
    (fp_text user "${REFERENCE}" (at -0.659 5.797) (layer "F.Fab") hide
        (effects (font (size 0.7 0.7) (thickness 0.15)) (justify left bottom))
    )
    (fp_line (start -1.6 -2.045) (end 1.5995 -2.045)
      (stroke (width 0.15) (type solid)) (layer "F.SilkS"))
    (fp_line (start -1.6 2.044) (end 1.6 2.044)
      (stroke (width 0.15) (type solid)) (layer "F.SilkS"))
    (fp_circle (center -1.85 -1.9) (end -1.8 -1.9)
      (stroke (width 0.15) (type solid)) (fill solid) (layer "F.SilkS"))
    (fp_line (start -2.1 -1.87) (end -1.79 -1.87)
      (stroke (width 0.05) (type solid)) (layer "F.CrtYd"))
    (fp_line (start -2.1 1.9) (end -2.1 -1.87)
      (stroke (width 0.05) (type solid)) (layer "F.CrtYd"))
    (fp_line (start -1.79 -2.28) (end 1.81 -2.28)
      (stroke (width 0.05) (type solid)) (layer "F.CrtYd"))
    (fp_line (start -1.79 -1.87) (end -1.79 -2.28)
      (stroke (width 0.05) (type solid)) (layer "F.CrtYd"))
    (fp_line (start -1.79 1.9) (end -2.1 1.9)
      (stroke (width 0.05) (type solid)) (layer "F.CrtYd"))
    (fp_line (start -1.79 2.31) (end -1.79 1.9)
      (stroke (width 0.05) (type solid)) (layer "F.CrtYd"))
    (fp_line (start 1.81 -2.28) (end 1.81 -1.87)
      (stroke (width 0.05) (type solid)) (layer "F.CrtYd"))
    (fp_line (start 1.81 1.9) (end 1.81 2.31)
      (stroke (width 0.05) (type solid)) (layer "F.CrtYd"))
    (fp_line (start 1.81 2.31) (end -1.79 2.31)
      (stroke (width 0.05) (type solid)) (layer "F.CrtYd"))
    (fp_line (start 2.1 -1.87) (end 1.81 -1.87)
      (stroke (width 0.05) (type solid)) (layer "F.CrtYd"))
    (fp_line (start 2.1 -1.87) (end 2.1 1.9)
      (stroke (width 0.05) (type solid)) (layer "F.CrtYd"))
    (fp_line (start 2.1 1.9) (end 1.81 1.9)
      (stroke (width 0.05) (type solid)) (layer "F.CrtYd"))
    (fp_line (start -1.55 -2.045) (end -1.55 2.044)
      (stroke (width 0.15) (type solid)) (layer "F.Fab"))
    (fp_line (start -1.55 2.044) (end 1.549 2.044)
      (stroke (width 0.15) (type solid)) (layer "F.Fab"))
    (fp_line (start 1.549 -2.045) (end -1.55 -2.045)
      (stroke (width 0.15) (type solid)) (layer "F.Fab"))
    (fp_line (start 1.549 2.044) (end 1.549 -2.045)
      (stroke (width 0.15) (type solid)) (layer "F.Fab"))
    (pad "" smd roundrect (at 0 -0.8) (size 1.3 1.3) (layers "F.Paste") (roundrect_rratio 0.05))
    (pad "" smd roundrect (at 0 0.8) (size 1.3 1.3) (layers "F.Paste") (roundrect_rratio 0.05))
    (pad "1" smd roundrect (at -1.445 -1.499) (size 0.807999 0.2548) (layers "F.Cu" "F.Paste" "F.Mask") (roundrect_rratio 0.25)
      (net 228 "/Power Supply/Supply ORing/PD_VBUS") (pinfunction "IN") (pintype "input"))
    (pad "2" smd roundrect (at -1.445 -1.001) (size 0.807999 0.2548) (layers "F.Cu" "F.Paste" "F.Mask") (roundrect_rratio 0.25)
      (net 228 "/Power Supply/Supply ORing/PD_VBUS") (pinfunction "IN") (pintype "passive"))
    (pad "3" smd roundrect (at -1.445 -0.5) (size 0.807999 0.2548) (layers "F.Cu" "F.Paste" "F.Mask") (roundrect_rratio 0.25)
      (net 228 "/Power Supply/Supply ORing/PD_VBUS") (pinfunction "IN") (pintype "passive"))
    (pad "4" smd roundrect (at -1.445 0) (size 0.807999 0.2548) (layers "F.Cu" "F.Paste" "F.Mask") (roundrect_rratio 0.25)
      (net 228 "/Power Supply/Supply ORing/PD_VBUS") (pinfunction "IN") (pintype "passive"))
    (pad "5" smd roundrect (at -1.445 0.5) (size 0.807999 0.2548) (layers "F.Cu" "F.Paste" "F.Mask") (roundrect_rratio 0.25)
      (net 788 "unconnected-(U57-GATE-Pad5)") (pinfunction "GATE") (pintype "output+no_connect"))
    (pad "6" smd roundrect (at -1.445 1) (size 0.807999 0.2548) (layers "F.Cu" "F.Paste" "F.Mask") (roundrect_rratio 0.25)
      (net 789 "unconnected-(U57-NC-Pad6)") (pinfunction "NC") (pintype "no_connect"))
    (pad "7" smd roundrect (at -1.445 1.5) (size 0.807999 0.2548) (layers "F.Cu" "F.Paste" "F.Mask") (roundrect_rratio 0.25)
      (net 1 "GND") (pinfunction "GND") (pintype "power_in"))
    (pad "8" smd roundrect (at 1.445 1.5) (size 0.807999 0.2548) (layers "F.Cu" "F.Paste" "F.Mask") (roundrect_rratio 0.25)
      (net 14 "/Power Supply/DC/DC conventers/DC_MAIN_BUS") (pinfunction "VDD") (pintype "passive"))
    (pad "9" smd roundrect (at 1.445 1) (size 0.807999 0.2548) (layers "F.Cu" "F.Paste" "F.Mask") (roundrect_rratio 0.25)
      (net 14 "/Power Supply/DC/DC conventers/DC_MAIN_BUS") (pinfunction "OUT") (pintype "passive"))
    (pad "10" smd roundrect (at 1.445 0.5) (size 0.807999 0.2548) (layers "F.Cu" "F.Paste" "F.Mask") (roundrect_rratio 0.25)
      (net 790 "unconnected-(U57-NC-Pad10)") (pinfunction "NC") (pintype "no_connect"))
    (pad "11" smd roundrect (at 1.445 0) (size 0.807999 0.2548) (layers "F.Cu" "F.Paste" "F.Mask") (roundrect_rratio 0.25)
      (net 228 "/Power Supply/Supply ORing/PD_VBUS") (pinfunction "IN") (pintype "passive"))
    (pad "12" smd roundrect (at 1.445 -0.501) (size 0.807999 0.2548) (layers "F.Cu" "F.Paste" "F.Mask") (roundrect_rratio 0.25)
      (net 228 "/Power Supply/Supply ORing/PD_VBUS") (pinfunction "IN") (pintype "passive"))
    (pad "13" smd roundrect (at 1.445 -1.001) (size 0.807999 0.2548) (layers "F.Cu" "F.Paste" "F.Mask") (roundrect_rratio 0.25)
      (net 228 "/Power Supply/Supply ORing/PD_VBUS") (pinfunction "IN") (pintype "passive"))
    (pad "14" smd roundrect (at 1.445 -1.499) (size 0.807999 0.2548) (layers "F.Cu" "F.Paste" "F.Mask") (roundrect_rratio 0.25)
      (net 228 "/Power Supply/Supply ORing/PD_VBUS") (pinfunction "IN") (pintype "passive"))
    (pad "15" smd roundrect (at 0 0) (size 1.8034 3.4036) (layers "F.Cu" "F.Mask") (roundrect_rratio 0.05)
      (net 14 "/Power Supply/DC/DC conventers/DC_MAIN_BUS") (pinfunction "DRAIN") (pintype "passive"))
  )

  (footprint "kria-k26-devboard-footprints:C_0402_1005Metric" (layer "F.Cu")
    (at 106.39 104.2 90)
    (descr "Capacitor SMD 0402")
    (tags "capacitor SMD 0402")
    (property "Author" "Antmicro")
    (property "Dielectric" "X5R")
    (property "License" "Apache-2.0")
    (property "MPN" "GRM155R61H104KE14D")
    (property "Manufacturer" "Murata")
    (property "Sheetfile" "clock.kicad_sch")
    (property "Sheetname" "Clock distribution")
    (property "Val" "100n")
    (property "Voltage" "50V")
    (property "ki_description" " ")
    (attr smd)
    (fp_text reference "C27" (at 0.81 0.45 90) (layer "F.SilkS")
        (effects (font (size 0.7 0.7) (thickness 0.15)) (justify left bottom))
    )
    (fp_text value "C_100n_0402" (at 0 1.4 90) (layer "F.Fab") hide
        (effects (font (size 0.7 0.7) (thickness 0.15)) (justify left bottom))
    )
    (fp_text user "License: Apache-2.0" (at -0.932 5.17 90) (layer "F.Fab") hide
        (effects (font (size 0.7 0.7) (thickness 0.15)) (justify left bottom))
    )
    (fp_text user "${REFERENCE}" (at -0.932 3.168 90) (layer "F.Fab") hide
        (effects (font (size 0.7 0.7) (thickness 0.15)) (justify left bottom))
    )
    (fp_text user "Author: Antmicro" (at -0.932 4.17 90) (layer "F.Fab") hide
        (effects (font (size 0.7 0.7) (thickness 0.15)) (justify left bottom))
    )
    (fp_rect (start -0.94 -0.47) (end 0.94 0.47)
      (stroke (width 0.05) (type solid)) (fill none) (layer "F.CrtYd"))
    (fp_rect (start -0.499 -0.249) (end 0.499 0.249)
      (stroke (width 0.15) (type solid)) (fill none) (layer "F.Fab"))
    (pad "1" smd roundrect (at -0.484 0 90) (size 0.59 0.64) (layers "F.Cu" "F.Paste" "F.Mask") (roundrect_rratio 0.25)
      (net 15 "PS_3V3") (pintype "passive"))
    (pad "2" smd roundrect (at 0.484 0 90) (size 0.59 0.64) (layers "F.Cu" "F.Paste" "F.Mask") (roundrect_rratio 0.25)
      (net 1 "GND") (pintype "passive"))
  )

  (footprint "kria-k26-devboard-footprints:Oscillator_SMD_JU6_7x5mm_P2.54mm" (layer "F.Cu")
    (at 102.15 101.95 -90)
    (descr "SMD Crystal Oscillator IDT")
    (tags "SMD SMT crystal oscillator")
    (property "Author" "Antmicro")
    (property "License" "Apache-2.0")
    (property "MPN" "XLL736027.000000X")
    (property "Manufacturer" "Renesas")
    (property "Sheetfile" "clock.kicad_sch")
    (property "Sheetname" "Clock distribution")
    (property "Val" "27 MHz")
    (property "ki_description" "27 MHz XO (Standard) LVDS Oscillator 3.3V Enable/Disable 6-SMD, No Lead")
    (property "ki_keywords" "OSCILLATOR, LVDS")
    (attr smd)
    (fp_text reference "U9" (at 0.46 3.79 -90) (layer "F.SilkS")
        (effects (font (size 0.7 0.7) (thickness 0.15)) (justify left bottom))
    )
    (fp_text value "Oscillator_27MHz_JU6" (at -0.03 4.679 -90) (layer "F.Fab") hide
        (effects (font (size 0.7 0.7) (thickness 0.15)) (justify left bottom))
    )
    (fp_text user "${REFERENCE}" (at -2.61 6.679 -90) (layer "F.Fab") hide
        (effects (font (size 0.7 0.7) (thickness 0.15)) (justify left bottom))
    )
    (fp_text user "Author: Antmicro" (at -2.61 7.679 -90) (layer "F.Fab") hide
        (effects (font (size 0.7 0.7) (thickness 0.15)) (justify left bottom))
    )
    (fp_text user "License: Apache-2.0" (at -2.61 8.679 -90) (layer "F.Fab") hide
        (effects (font (size 0.7 0.7) (thickness 0.15)) (justify left bottom))
    )
    (fp_line (start -2.65 -3.625) (end 2.608 -3.621)
      (stroke (width 0.15) (type solid)) (layer "F.SilkS"))
    (fp_line (start -2.61 -1.101) (end -2.61 -1.44)
      (stroke (width 0.15) (type solid)) (layer "F.SilkS"))
    (fp_line (start -2.61 1.439) (end -2.61 1.1)
      (stroke (width 0.15) (type solid)) (layer "F.SilkS"))
    (fp_line (start 2.608 -1.44) (end 2.608 -1.101)
      (stroke (width 0.15) (type solid)) (layer "F.SilkS"))
    (fp_line (start 2.608 1.1) (end 2.608 1.439)
      (stroke (width 0.15) (type solid)) (layer "F.SilkS"))
    (fp_line (start 2.608 3.62) (end -2.61 3.62)
      (stroke (width 0.15) (type solid)) (layer "F.SilkS"))
    (fp_circle (center -3.15 -3.575) (end -3.1 -3.575)
      (stroke (width 0.15) (type solid)) (fill solid) (layer "F.SilkS"))
    (fp_rect (start -3.375 -3.75) (end 3.375 3.75)
      (stroke (width 0.05) (type solid)) (fill none) (layer "F.CrtYd"))
    (fp_line (start -2.5 -2.5) (end -2.5 3.499)
      (stroke (width 0.15) (type solid)) (layer "F.Fab"))
    (fp_line (start -2.5 3.499) (end 2.499 3.499)
      (stroke (width 0.15) (type solid)) (layer "F.Fab"))
    (fp_line (start -1.5 -3.5) (end -2.5 -2.5)
      (stroke (width 0.15) (type solid)) (layer "F.Fab"))
    (fp_line (start 2.499 -3.5) (end -1.5 -3.5)
      (stroke (width 0.15) (type solid)) (layer "F.Fab"))
    (fp_line (start 2.499 3.499) (end 2.499 -3.5)
      (stroke (width 0.15) (type solid)) (layer "F.Fab"))
    (pad "1" smd roundrect (at -2.101 -2.54 180) (size 1.8 2) (layers "F.Cu" "F.Paste" "F.Mask") (roundrect_rratio 0.25)
      (net 185 "/Clock distribution/PS_CLK_EN") (pinfunction "EN") (pintype "input"))
    (pad "2" smd roundrect (at -2.101 0 180) (size 1.8 2) (layers "F.Cu" "F.Paste" "F.Mask") (roundrect_rratio 0.25)
      (net 709 "unconnected-(U9-NC-Pad2)") (pinfunction "NC") (pintype "no_connect"))
    (pad "3" smd roundrect (at -2.101 2.539 180) (size 1.8 2) (layers "F.Cu" "F.Paste" "F.Mask") (roundrect_rratio 0.25)
      (net 1 "GND") (pinfunction "GND") (pintype "power_in"))
    (pad "4" smd roundrect (at 2.1 2.539 180) (size 1.8 2) (layers "F.Cu" "F.Paste" "F.Mask") (roundrect_rratio 0.25)
      (net 181 "/Clock distribution/GTR_REFCLK0_C2M_P") (pinfunction "OUT+") (pintype "output"))
    (pad "5" smd roundrect (at 2.1 0 180) (size 1.8 2) (layers "F.Cu" "F.Paste" "F.Mask") (roundrect_rratio 0.25)
      (net 182 "/Clock distribution/GTR_REFCLK0_C2M_N") (pinfunction "OUT-") (pintype "output"))
    (pad "6" smd roundrect (at 2.1 -2.54 180) (size 1.8 2) (layers "F.Cu" "F.Paste" "F.Mask") (roundrect_rratio 0.25)
      (net 15 "PS_3V3") (pinfunction "VCC") (pintype "power_in"))
  )

  (footprint "kria-k26-devboard-footprints:R_0603_1608Metric" (layer "F.Cu")
    (at 187.25 76.55 180)
    (descr "Resistor SMD 0603")
    (tags "resistor SMD 0603")
    (property "Author" "Antmicro")
    (property "License" "Apache-2.0")
    (property "MPN" "CR0603-FX-63R4ELF")
    (property "Manufacturer" "Bourns")
    (property "Sheetfile" "PoE.kicad_sch")
    (property "Sheetname" "PoE")
    (property "Tolerance" "1%")
    (property "Val" "63R4")
    (property "ki_description" "63R4 resistor in 0603 package with 1% tolerance")
    (attr smd)
    (fp_text reference "R116" (at 1.4 0.78 180) (layer "F.SilkS")
        (effects (font (size 0.7 0.7) (thickness 0.15)) (justify left bottom))
    )
    (fp_text value "R_63R4_0603" (at 0 1.6 180) (layer "F.Fab") hide
        (effects (font (size 0.7 0.7) (thickness 0.15)) (justify left bottom))
    )
    (fp_text user "Author: Antmicro" (at -1.25 4.9 180) (layer "F.Fab") hide
        (effects (font (size 0.7 0.7) (thickness 0.15)) (justify left bottom))
    )
    (fp_text user "License: Apache-2.0" (at -1.25 5.9 180) (layer "F.Fab") hide
        (effects (font (size 0.7 0.7) (thickness 0.15)) (justify left bottom))
    )
    (fp_text user "${REFERENCE}" (at -1.25 3.898 180) (layer "F.Fab") hide
        (effects (font (size 0.7 0.7) (thickness 0.15)) (justify left bottom))
    )
    (fp_line (start -0.3 -0.3) (end 0.3 -0.3)
      (stroke (width 0.15) (type solid)) (layer "F.SilkS"))
    (fp_line (start -0.3 0.3) (end 0.3 0.3)
      (stroke (width 0.15) (type solid)) (layer "F.SilkS"))
    (fp_rect (start -1.25 -0.7) (end 1.25 0.7)
      (stroke (width 0.05) (type solid)) (fill none) (layer "F.CrtYd"))
    (fp_rect (start -0.8 -0.4) (end 0.8 0.4)
      (stroke (width 0.15) (type solid)) (fill none) (layer "F.Fab"))
    (pad "1" smd roundrect (at -0.7 0 180) (size 0.6 0.8) (layers "F.Cu" "F.Paste" "F.Mask") (roundrect_rratio 0.2)
      (net 342 "Net-(IC1-CLS)") (pintype "passive"))
    (pad "2" smd roundrect (at 0.7 0 180) (size 0.6 0.8) (layers "F.Cu" "F.Paste" "F.Mask") (roundrect_rratio 0.2)
      (net 10 "/Power Supply/PoE/VSS_POE_IN") (pintype "passive"))
  )

  (footprint "kria-k26-devboard-footprints:C_0402_1005Metric" (layer "F.Cu")
    (at 189.85 67.6)
    (descr "Capacitor SMD 0402")
    (tags "capacitor SMD 0402")
    (property "Author" "Antmicro")
    (property "Dielectric" "X5R")
    (property "License" "Apache-2.0")
    (property "MPN" "GRM155R61H104KE14D")
    (property "Manufacturer" "Murata")
    (property "Sheetfile" "supply-oring.kicad_sch")
    (property "Sheetname" "Supply ORing")
    (property "Val" "100n")
    (property "Voltage" "50V")
    (property "ki_description" " ")
    (attr smd)
    (fp_text reference "C230" (at -3.6 0.35) (layer "F.SilkS")
        (effects (font (size 0.7 0.7) (thickness 0.15)) (justify left bottom))
    )
    (fp_text value "C_100n_0402" (at 0 1.4) (layer "F.Fab") hide
        (effects (font (size 0.7 0.7) (thickness 0.15)) (justify left bottom))
    )
    (fp_text user "License: Apache-2.0" (at -0.932 5.17) (layer "F.Fab") hide
        (effects (font (size 0.7 0.7) (thickness 0.15)) (justify left bottom))
    )
    (fp_text user "${REFERENCE}" (at -0.932 3.168) (layer "F.Fab") hide
        (effects (font (size 0.7 0.7) (thickness 0.15)) (justify left bottom))
    )
    (fp_text user "Author: Antmicro" (at -0.932 4.17) (layer "F.Fab") hide
        (effects (font (size 0.7 0.7) (thickness 0.15)) (justify left bottom))
    )
    (fp_rect (start -0.94 -0.47) (end 0.94 0.47)
      (stroke (width 0.05) (type solid)) (fill none) (layer "F.CrtYd"))
    (fp_rect (start -0.499 -0.249) (end 0.499 0.249)
      (stroke (width 0.15) (type solid)) (fill none) (layer "F.Fab"))
    (pad "1" smd roundrect (at -0.484 0) (size 0.59 0.64) (layers "F.Cu" "F.Paste" "F.Mask") (roundrect_rratio 0.25)
      (net 14 "/Power Supply/DC/DC conventers/DC_MAIN_BUS") (pintype "passive"))
    (pad "2" smd roundrect (at 0.484 0) (size 0.59 0.64) (layers "F.Cu" "F.Paste" "F.Mask") (roundrect_rratio 0.25)
      (net 331 "Net-(U58-GND)") (pintype "passive"))
  )

  (footprint "kria-k26-devboard-footprints:D_SOD-323F" (layer "F.Cu")
    (at 189.9 69.15 180)
    (property "Author" "Antmicro")
    (property "License" "Apache-2.0")
    (property "MPN" "1N4148WS")
    (property "Manufacturer" "ON Semiconductor")
    (property "Sheetfile" "supply-oring.kicad_sch")
    (property "Sheetname" "Supply ORing")
    (property "ki_description" "Small Signal Fast Switching Diode")
    (attr smd)
    (fp_text reference "D22" (at 1.12 -1.69 180) (layer "F.SilkS")
        (effects (font (size 0.7 0.7) (thickness 0.15)) (justify left bottom))
    )
    (fp_text value "1N4148WS" (at -1.7 1.9 180) (layer "F.Fab") hide
        (effects (font (size 0.7 0.7) (thickness 0.15)) (justify left bottom))
    )
    (fp_text user "${REFERENCE}" (at -1.8 3.2 180) (layer "F.Fab") hide
        (effects (font (size 0.7 0.7) (thickness 0.15)) (justify left bottom))
    )
    (fp_text user "License: Apache-2.0" (at -1.8 5.8 180) (layer "F.Fab") hide
        (effects (font (size 0.7 0.7) (thickness 0.15)) (justify left bottom))
    )
    (fp_text user "Author: Antmicro" (at -1.8 4.46 180) (layer "F.Fab") hide
        (effects (font (size 0.7 0.7) (thickness 0.15)) (justify left bottom))
    )
    (fp_line (start -0.975 -0.75) (end -0.975 -0.45)
      (stroke (width 0.15) (type solid)) (layer "F.SilkS"))
    (fp_line (start -0.975 0.748) (end -0.975 0.45)
      (stroke (width 0.15) (type solid)) (layer "F.SilkS"))
    (fp_line (start -0.625 -0.75) (end -0.975 -0.75)
      (stroke (width 0.15) (type solid)) (layer "F.SilkS"))
    (fp_line (start -0.625 0.748) (end -0.975 0.748)
      (stroke (width 0.15) (type solid)) (layer "F.SilkS"))
    (fp_line (start -0.5 -0.426) (end -0.5 0.424)
      (stroke (width 0.15) (type solid)) (layer "F.SilkS"))
    (fp_line (start 0.623 -0.75) (end 0.973 -0.75)
      (stroke (width 0.15) (type solid)) (layer "F.SilkS"))
    (fp_line (start 0.973 -0.75) (end 0.973 -0.45)
      (stroke (width 0.15) (type solid)) (layer "F.SilkS"))
    (fp_line (start 0.973 0.45) (end 0.973 0.748)
      (stroke (width 0.15) (type solid)) (layer "F.SilkS"))
    (fp_line (start 0.973 0.748) (end 0.623 0.748)
      (stroke (width 0.15) (type solid)) (layer "F.SilkS"))
    (fp_rect (start -1.6 -0.827) (end 1.599 0.825)
      (stroke (width 0.05) (type solid)) (fill none) (layer "F.CrtYd"))
    (fp_line (start -0.85 -0.625) (end 0.848 -0.625)
      (stroke (width 0.15) (type solid)) (layer "F.Fab"))
    (fp_line (start -0.85 0.623) (end -0.85 -0.625)
      (stroke (width 0.15) (type solid)) (layer "F.Fab"))
    (fp_line (start -0.85 0.623) (end 0.848 0.623)
      (stroke (width 0.15) (type solid)) (layer "F.Fab"))
    (fp_line (start 0.848 -0.625) (end 0.848 0.623)
      (stroke (width 0.15) (type solid)) (layer "F.Fab"))
    (pad "A" smd roundrect (at 1.05 0 180) (size 0.8 0.6) (layers "F.Cu" "F.Paste" "F.Mask") (roundrect_rratio 0.15)
      (net 331 "Net-(U58-GND)") (pinfunction "A") (pintype "passive"))
    (pad "K" smd roundrect (at -1.051 0 180) (size 0.8 0.6) (layers "F.Cu" "F.Paste" "F.Mask") (roundrect_rratio 0.15)
      (net 1 "GND") (pinfunction "K") (pintype "passive"))
  )

  (footprint "kria-k26-devboard-footprints:TP_SMD_0.75mm" (layer "F.Cu")
    (at 105.08 147.12)
    (property "Author" "Antmicro")
    (property "License" "Apache-2.0")
    (property "MPN" "")
    (property "Manufacturer" "")
    (property "Sheetfile" "reset.kicad_sch")
    (property "Sheetname" "Reset logic")
    (property "ki_description" "Test Point 0.75mm")
    (attr exclude_from_pos_files)
    (fp_text reference "TP14" (at -2.19 -0.51) (layer "F.SilkS")
        (effects (font (size 0.7 0.7) (thickness 0.15)) (justify left bottom))
    )
    (fp_text value "TP_0.75mm_SMD" (at 0 1.2) (layer "F.Fab") hide
        (effects (font (size 0.7 0.7) (thickness 0.15)) (justify left bottom))
    )
    (fp_text user "License: Apache-2.0" (at -0.4 5.101) (layer "F.Fab") hide
        (effects (font (size 0.7 0.7) (thickness 0.15)) (justify left bottom))
    )
    (fp_text user "Author: Antmicro" (at -0.4 3.901) (layer "F.Fab") hide
        (effects (font (size 0.7 0.7) (thickness 0.15)) (justify left bottom))
    )
    (fp_text user "${REFERENCE}" (at -0.4 2.7) (layer "F.Fab") hide
        (effects (font (size 0.7 0.7) (thickness 0.15)) (justify left bottom))
    )
    (pad "1" smd circle (at 0 0) (size 0.75 0.75) (layers "F.Cu" "F.Mask")
      (net 161 "/Reset logic/PS_RST") (pinfunction "1") (pintype "passive"))
  )

  (footprint "kria-k26-devboard-footprints:TP_SMD_0.75mm" (layer "F.Cu")
    (at 99.7 147.16)
    (property "Author" "Antmicro")
    (property "License" "Apache-2.0")
    (property "MPN" "")
    (property "Manufacturer" "")
    (property "Sheetfile" "reset.kicad_sch")
    (property "Sheetname" "Reset logic")
    (property "ki_description" "Test Point 0.75mm")
    (attr exclude_from_pos_files)
    (fp_text reference "TP15" (at -1.15 -0.49) (layer "F.SilkS")
        (effects (font (size 0.7 0.7) (thickness 0.15)) (justify left bottom))
    )
    (fp_text value "TP_0.75mm_SMD" (at 0 1.2) (layer "F.Fab") hide
        (effects (font (size 0.7 0.7) (thickness 0.15)) (justify left bottom))
    )
    (fp_text user "Author: Antmicro" (at -0.4 3.901) (layer "F.Fab") hide
        (effects (font (size 0.7 0.7) (thickness 0.15)) (justify left bottom))
    )
    (fp_text user "${REFERENCE}" (at -0.4 2.7) (layer "F.Fab") hide
        (effects (font (size 0.7 0.7) (thickness 0.15)) (justify left bottom))
    )
    (fp_text user "License: Apache-2.0" (at -0.4 5.101) (layer "F.Fab") hide
        (effects (font (size 0.7 0.7) (thickness 0.15)) (justify left bottom))
    )
    (pad "1" smd circle (at 0 0) (size 0.75 0.75) (layers "F.Cu" "F.Mask")
      (net 174 "/Reset logic/PL_RST") (pinfunction "1") (pintype "passive"))
  )

  (footprint "kria-k26-devboard-footprints:TP_SMD_0.75mm" (layer "F.Cu")
    (at 104.85 117.3)
    (property "Author" "Antmicro")
    (property "License" "Apache-2.0")
    (property "MPN" "")
    (property "Manufacturer" "")
    (property "Sheetfile" "reset.kicad_sch")
    (property "Sheetname" "Reset logic")
    (property "ki_description" "Test Point 0.75mm")
    (attr exclude_from_pos_files)
    (fp_text reference "TP16" (at -1.24 -0.45) (layer "F.SilkS")
        (effects (font (size 0.7 0.7) (thickness 0.15)) (justify left bottom))
    )
    (fp_text value "TP_0.75mm_SMD" (at 0 1.2) (layer "F.Fab") hide
        (effects (font (size 0.7 0.7) (thickness 0.15)) (justify left bottom))
    )
    (fp_text user "Author: Antmicro" (at -0.4 3.901) (layer "F.Fab") hide
        (effects (font (size 0.7 0.7) (thickness 0.15)) (justify left bottom))
    )
    (fp_text user "${REFERENCE}" (at -0.4 2.7) (layer "F.Fab") hide
        (effects (font (size 0.7 0.7) (thickness 0.15)) (justify left bottom))
    )
    (fp_text user "License: Apache-2.0" (at -0.4 5.101) (layer "F.Fab") hide
        (effects (font (size 0.7 0.7) (thickness 0.15)) (justify left bottom))
    )
    (pad "1" smd circle (at 0 0) (size 0.75 0.75) (layers "F.Cu" "F.Mask")
      (net 185 "/Clock distribution/PS_CLK_EN") (pinfunction "1") (pintype "passive"))
  )

  (footprint "kria-k26-devboard-footprints:R_0402_1005Metric" (layer "F.Cu")
    (at 190.7 64.065 -90)
    (descr "Resistor SMD 0402")
    (tags "resistor SMD 0402")
    (property "Author" "Antmicro")
    (property "License" "Apache-2.0")
    (property "MPN" "CR0402-FX-1000GLF")
    (property "Manufacturer" "Bourns")
    (property "Sheetfile" "supply-oring.kicad_sch")
    (property "Sheetname" "Supply ORing")
    (property "Tolerance" "1%")
    (property "Val" "100R")
    (property "ki_description" "100R resistor in 0402 package with 1% tolerance")
    (attr smd)
    (fp_text reference "R148" (at 0.685 -1.15 -90) (layer "F.SilkS")
        (effects (font (size 0.7 0.7) (thickness 0.15)) (justify left bottom))
    )
    (fp_text value "R_100R_0402" (at 0 1.4 -90) (layer "F.Fab") hide
        (effects (font (size 0.7 0.7) (thickness 0.15)) (justify left bottom))
    )
    (fp_text user "Author: Antmicro" (at -0.95 4.169 -90) (layer "F.Fab") hide
        (effects (font (size 0.7 0.7) (thickness 0.15)) (justify left bottom))
    )
    (fp_text user "${REFERENCE}" (at -0.95 3.168 -90) (layer "F.Fab") hide
        (effects (font (size 0.7 0.7) (thickness 0.15)) (justify left bottom))
    )
    (fp_text user "License: Apache-2.0" (at -0.95 5.169 -90) (layer "F.Fab") hide
        (effects (font (size 0.7 0.7) (thickness 0.15)) (justify left bottom))
    )
    (fp_rect (start -0.93 -0.47) (end 0.93 0.47)
      (stroke (width 0.05) (type solid)) (fill none) (layer "F.CrtYd"))
    (fp_rect (start -0.5 -0.25) (end 0.5 0.25)
      (stroke (width 0.15) (type solid)) (fill none) (layer "F.Fab"))
    (pad "1" smd roundrect (at -0.485 0 270) (size 0.59 0.64) (layers "F.Cu" "F.Paste" "F.Mask") (roundrect_rratio 0.25)
      (net 14 "/Power Supply/DC/DC conventers/DC_MAIN_BUS") (pintype "passive"))
    (pad "2" smd roundrect (at 0.485 0 270) (size 0.59 0.64) (layers "F.Cu" "F.Paste" "F.Mask") (roundrect_rratio 0.25)
      (net 328 "Net-(U58-VDD)") (pintype "passive"))
  )

  (footprint "kria-k26-devboard-footprints:D_SOD-323F" (layer "F.Cu")
    (at 186.6 69.15)
    (property "Author" "Antmicro")
    (property "License" "Apache-2.0")
    (property "MPN" "1N4148WS")
    (property "Manufacturer" "ON Semiconductor")
    (property "Sheetfile" "supply-oring.kicad_sch")
    (property "Sheetname" "Supply ORing")
    (property "ki_description" "Small Signal Fast Switching Diode")
    (attr smd)
    (fp_text reference "D21" (at -0.92 1.67) (layer "F.SilkS")
        (effects (font (size 0.7 0.7) (thickness 0.15)) (justify left bottom))
    )
    (fp_text value "1N4148WS" (at -1.7 1.9) (layer "F.Fab") hide
        (effects (font (size 0.7 0.7) (thickness 0.15)) (justify left bottom))
    )
    (fp_text user "${REFERENCE}" (at -1.8 3.2) (layer "F.Fab") hide
        (effects (font (size 0.7 0.7) (thickness 0.15)) (justify left bottom))
    )
    (fp_text user "Author: Antmicro" (at -1.8 4.46) (layer "F.Fab") hide
        (effects (font (size 0.7 0.7) (thickness 0.15)) (justify left bottom))
    )
    (fp_text user "License: Apache-2.0" (at -1.8 5.8) (layer "F.Fab") hide
        (effects (font (size 0.7 0.7) (thickness 0.15)) (justify left bottom))
    )
    (fp_line (start -0.975 -0.75) (end -0.975 -0.45)
      (stroke (width 0.15) (type solid)) (layer "F.SilkS"))
    (fp_line (start -0.975 0.748) (end -0.975 0.45)
      (stroke (width 0.15) (type solid)) (layer "F.SilkS"))
    (fp_line (start -0.625 -0.75) (end -0.975 -0.75)
      (stroke (width 0.15) (type solid)) (layer "F.SilkS"))
    (fp_line (start -0.625 0.748) (end -0.975 0.748)
      (stroke (width 0.15) (type solid)) (layer "F.SilkS"))
    (fp_line (start -0.5 -0.426) (end -0.5 0.424)
      (stroke (width 0.15) (type solid)) (layer "F.SilkS"))
    (fp_line (start 0.623 -0.75) (end 0.973 -0.75)
      (stroke (width 0.15) (type solid)) (layer "F.SilkS"))
    (fp_line (start 0.973 -0.75) (end 0.973 -0.45)
      (stroke (width 0.15) (type solid)) (layer "F.SilkS"))
    (fp_line (start 0.973 0.45) (end 0.973 0.748)
      (stroke (width 0.15) (type solid)) (layer "F.SilkS"))
    (fp_line (start 0.973 0.748) (end 0.623 0.748)
      (stroke (width 0.15) (type solid)) (layer "F.SilkS"))
    (fp_rect (start -1.6 -0.827) (end 1.599 0.825)
      (stroke (width 0.05) (type solid)) (fill none) (layer "F.CrtYd"))
    (fp_line (start -0.85 -0.625) (end 0.848 -0.625)
      (stroke (width 0.15) (type solid)) (layer "F.Fab"))
    (fp_line (start -0.85 0.623) (end -0.85 -0.625)
      (stroke (width 0.15) (type solid)) (layer "F.Fab"))
    (fp_line (start -0.85 0.623) (end 0.848 0.623)
      (stroke (width 0.15) (type solid)) (layer "F.Fab"))
    (fp_line (start 0.848 -0.625) (end 0.848 0.623)
      (stroke (width 0.15) (type solid)) (layer "F.Fab"))
    (pad "A" smd roundrect (at 1.05 0) (size 0.8 0.6) (layers "F.Cu" "F.Paste" "F.Mask") (roundrect_rratio 0.15)
      (net 331 "Net-(U58-GND)") (pinfunction "A") (pintype "passive"))
    (pad "K" smd roundrect (at -1.051 0) (size 0.8 0.6) (layers "F.Cu" "F.Paste" "F.Mask") (roundrect_rratio 0.15)
      (net 22 "/Power Supply/DC Input/DC_IN") (pinfunction "K") (pintype "passive"))
  )

  (footprint "kria-k26-devboard-footprints:TP_SMD_0.75mm" (layer "F.Cu")
    (at 118.6 92.35)
    (property "Author" "Antmicro")
    (property "License" "Apache-2.0")
    (property "MPN" "")
    (property "Manufacturer" "")
    (property "Sheetfile" "usb.kicad_sch")
    (property "Sheetname" "USB")
    (property "ki_description" "Test Point 0.75mm")
    (attr exclude_from_pos_files)
    (fp_text reference "TP10" (at -0.5 1.54 90) (layer "F.SilkS")
        (effects (font (size 0.7 0.7) (thickness 0.15)) (justify left bottom))
    )
    (fp_text value "TP_0.75mm_SMD" (at 0 1.2) (layer "F.Fab") hide
        (effects (font (size 0.7 0.7) (thickness 0.15)) (justify left bottom))
    )
    (fp_text user "Author: Antmicro" (at -0.4 3.901) (layer "F.Fab") hide
        (effects (font (size 0.7 0.7) (thickness 0.15)) (justify left bottom))
    )
    (fp_text user "License: Apache-2.0" (at -0.4 5.101) (layer "F.Fab") hide
        (effects (font (size 0.7 0.7) (thickness 0.15)) (justify left bottom))
    )
    (fp_text user "${REFERENCE}" (at -0.4 2.7) (layer "F.Fab") hide
        (effects (font (size 0.7 0.7) (thickness 0.15)) (justify left bottom))
    )
    (pad "1" smd circle (at 0 0) (size 0.75 0.75) (layers "F.Cu" "F.Mask")
      (net 275 "/USB/VBUS") (pinfunction "1") (pintype "passive"))
  )

  (footprint "kria-k26-devboard-footprints:TP_SMD_0.75mm" (layer "F.Cu")
    (at 106.11 147.11)
    (property "Author" "Antmicro")
    (property "License" "Apache-2.0")
    (property "MPN" "")
    (property "Manufacturer" "")
    (property "Sheetfile" "reset.kicad_sch")
    (property "Sheetname" "Reset logic")
    (property "ki_description" "Test Point 0.75mm")
    (attr exclude_from_pos_files)
    (fp_text reference "TP13" (at -0.51 -0.5) (layer "F.SilkS")
        (effects (font (size 0.7 0.7) (thickness 0.15)) (justify left bottom))
    )
    (fp_text value "TP_0.75mm_SMD" (at 0 1.2) (layer "F.Fab") hide
        (effects (font (size 0.7 0.7) (thickness 0.15)) (justify left bottom))
    )
    (fp_text user "License: Apache-2.0" (at -0.4 5.101) (layer "F.Fab") hide
        (effects (font (size 0.7 0.7) (thickness 0.15)) (justify left bottom))
    )
    (fp_text user "Author: Antmicro" (at -0.4 3.901) (layer "F.Fab") hide
        (effects (font (size 0.7 0.7) (thickness 0.15)) (justify left bottom))
    )
    (fp_text user "${REFERENCE}" (at -0.4 2.7) (layer "F.Fab") hide
        (effects (font (size 0.7 0.7) (thickness 0.15)) (justify left bottom))
    )
    (pad "1" smd circle (at 0 0) (size 0.75 0.75) (layers "F.Cu" "F.Mask")
      (net 151 "/Debug and JTAG/~{PS_POR}") (pinfunction "1") (pintype "passive"))
  )

  (footprint "kria-k26-devboard-footprints:C_0402_1005Metric" (layer "F.Cu")
    (at 125.55 92.91 90)
    (descr "Capacitor SMD 0402")
    (tags "capacitor SMD 0402")
    (property "Author" "Antmicro")
    (property "Dielectric" "X5R")
    (property "License" "Apache-2.0")
    (property "MPN" "GRM155R61H104KE14D")
    (property "Manufacturer" "Murata")
    (property "Sheetfile" "usb.kicad_sch")
    (property "Sheetname" "USB")
    (property "Val" "100n")
    (property "Voltage" "50V")
    (property "ki_description" " ")
    (attr smd)
    (fp_text reference "C55" (at -1.94 -3.25 90) (layer "F.SilkS")
        (effects (font (size 0.7 0.7) (thickness 0.15)) (justify left bottom))
    )
    (fp_text value "C_100n_0402" (at 0 1.4 90) (layer "F.Fab") hide
        (effects (font (size 0.7 0.7) (thickness 0.15)) (justify left bottom))
    )
    (fp_text user "Author: Antmicro" (at -0.932 4.17 90) (layer "F.Fab") hide
        (effects (font (size 0.7 0.7) (thickness 0.15)) (justify left bottom))
    )
    (fp_text user "${REFERENCE}" (at -0.932 3.168 90) (layer "F.Fab") hide
        (effects (font (size 0.7 0.7) (thickness 0.15)) (justify left bottom))
    )
    (fp_text user "License: Apache-2.0" (at -0.932 5.17 90) (layer "F.Fab") hide
        (effects (font (size 0.7 0.7) (thickness 0.15)) (justify left bottom))
    )
    (fp_rect (start -0.94 -0.47) (end 0.94 0.47)
      (stroke (width 0.05) (type solid)) (fill none) (layer "F.CrtYd"))
    (fp_rect (start -0.499 -0.249) (end 0.499 0.249)
      (stroke (width 0.15) (type solid)) (fill none) (layer "F.Fab"))
    (pad "1" smd roundrect (at -0.484 0 90) (size 0.59 0.64) (layers "F.Cu" "F.Paste" "F.Mask") (roundrect_rratio 0.25)
      (net 59 "/USB/GTR_DP2_M2C_N") (pintype "passive"))
    (pad "2" smd roundrect (at 0.484 0 90) (size 0.59 0.64) (layers "F.Cu" "F.Paste" "F.Mask") (roundrect_rratio 0.25)
      (net 321 "/USB/GTR_DP2_M2C_C_N") (pintype "passive"))
  )

  (footprint "kria-k26-devboard-footprints:C_0402_1005Metric" (layer "F.Cu")
    (at 124.6 92.91 90)
    (descr "Capacitor SMD 0402")
    (tags "capacitor SMD 0402")
    (property "Author" "Antmicro")
    (property "Dielectric" "X5R")
    (property "License" "Apache-2.0")
    (property "MPN" "GRM155R61H104KE14D")
    (property "Manufacturer" "Murata")
    (property "Sheetfile" "usb.kicad_sch")
    (property "Sheetname" "USB")
    (property "Val" "100n")
    (property "Voltage" "50V")
    (property "ki_description" " ")
    (attr smd)
    (fp_text reference "C54" (at -1.94 -3.25 90) (layer "F.SilkS")
        (effects (font (size 0.7 0.7) (thickness 0.15)) (justify left bottom))
    )
    (fp_text value "C_100n_0402" (at 0 1.4 90) (layer "F.Fab") hide
        (effects (font (size 0.7 0.7) (thickness 0.15)) (justify left bottom))
    )
    (fp_text user "License: Apache-2.0" (at -0.932 5.17 90) (layer "F.Fab") hide
        (effects (font (size 0.7 0.7) (thickness 0.15)) (justify left bottom))
    )
    (fp_text user "Author: Antmicro" (at -0.932 4.17 90) (layer "F.Fab") hide
        (effects (font (size 0.7 0.7) (thickness 0.15)) (justify left bottom))
    )
    (fp_text user "${REFERENCE}" (at -0.932 3.168 90) (layer "F.Fab") hide
        (effects (font (size 0.7 0.7) (thickness 0.15)) (justify left bottom))
    )
    (fp_rect (start -0.94 -0.47) (end 0.94 0.47)
      (stroke (width 0.05) (type solid)) (fill none) (layer "F.CrtYd"))
    (fp_rect (start -0.499 -0.249) (end 0.499 0.249)
      (stroke (width 0.15) (type solid)) (fill none) (layer "F.Fab"))
    (pad "1" smd roundrect (at -0.484 0 90) (size 0.59 0.64) (layers "F.Cu" "F.Paste" "F.Mask") (roundrect_rratio 0.25)
      (net 58 "/USB/GTR_DP2_M2C_P") (pintype "passive"))
    (pad "2" smd roundrect (at 0.484 0 90) (size 0.59 0.64) (layers "F.Cu" "F.Paste" "F.Mask") (roundrect_rratio 0.25)
      (net 320 "/USB/GTR_DP2_M2C_C_P") (pintype "passive"))
  )

  (footprint "kria-k26-devboard-footprints:XDFN4" (layer "F.Cu")
    (at 83.875 118.050001)
    (property "Author" "Antmicro")
    (property "License" "Apache-2.0")
    (property "MPN" "AP7340-18FS4-7")
    (property "Manufacturer" "Diodes Incorporated")
    (property "Sheetfile" "camera.kicad_sch")
    (property "Sheetname" "Camera interface")
    (property "dnp" "")
    (property "ki_description" "Linear voltage regulator")
    (property "ki_keywords" "SMT, PMIC, IC, VOLTAGE, LDO")
    (attr exclude_from_pos_files)
    (fp_text reference "U11" (at -1.055 -2.720001) (layer "F.SilkS")
        (effects (font (size 0.7 0.7) (thickness 0.15)) (justify left bottom))
    )
    (fp_text value "AP7340-18FS4-7" (at -1.73 1.92) (layer "F.Fab") hide
        (effects (font (size 0.7 0.7) (thickness 0.15)) (justify left bottom))
    )
    (fp_text user "${REFERENCE}" (at -1.73 6.32) (layer "F.Fab") hide
        (effects (font (size 0.7 0.7) (thickness 0.15)) (justify left bottom))
    )
    (fp_text user "License: Apache-2.0" (at -1.73 5.12) (layer "F.Fab") hide
        (effects (font (size 0.7 0.7) (thickness 0.15)) (justify left bottom))
    )
    (fp_text user "Author: Antmicro" (at -1.73 3.92) (layer "F.Fab") hide
        (effects (font (size 0.7 0.7) (thickness 0.15)) (justify left bottom))
    )
    (fp_poly
      (pts
        (xy -0.652 -0.452)
        (xy -0.18 -0.452)
        (xy -0.43 -0.202)
        (xy -0.652 -0.202)
      )

      (stroke (width 0.01) (type solid)) (fill solid) (layer "F.Paste"))
    (fp_poly
      (pts
        (xy -0.152 -0.152)
        (xy 0.15 -0.152)
        (xy 0.15 0.15)
        (xy -0.152 0.15)
      )

      (stroke (width 0.01) (type solid)) (fill solid) (layer "F.Paste"))
    (fp_poly
      (pts
        (xy -0.652 0.45)
        (xy -0.25 0.45)
        (xy -0.25 0.378)
        (xy -0.43 0.2)
        (xy -0.652 0.2)
      )

      (stroke (width 0.01) (type solid)) (fill solid) (layer "F.Paste"))
    (fp_poly
      (pts
        (xy 0.65 -0.452)
        (xy 0.248 -0.452)
        (xy 0.248 -0.38)
        (xy 0.428 -0.202)
        (xy 0.65 -0.202)
      )

      (stroke (width 0.01) (type solid)) (fill solid) (layer "F.Paste"))
    (fp_poly
      (pts
        (xy 0.65 0.45)
        (xy 0.248 0.45)
        (xy 0.248 0.378)
        (xy 0.428 0.2)
        (xy 0.65 0.2)
      )

      (stroke (width 0.01) (type solid)) (fill solid) (layer "F.Paste"))
    (fp_circle (center -0.75 -0.6) (end -0.699 -0.6)
      (stroke (width 0.15) (type solid)) (fill solid) (layer "F.SilkS"))
    (fp_rect (start -0.8 -0.8) (end 0.8 0.8)
      (stroke (width 0.05) (type solid)) (fill none) (layer "F.CrtYd"))
    (fp_line (start -0.5 -0.3) (end -0.3 -0.5)
      (stroke (width 0.15) (type solid)) (layer "F.Fab"))
    (fp_rect (start -0.5 -0.5) (end 0.498 0.498)
      (stroke (width 0.15) (type solid)) (fill none) (layer "F.Fab"))
    (pad "1" smd custom (at -0.452 -0.327) (size 0.1 0.1) (layers "F.Cu")
      (net 322 "PL_1V8") (pinfunction "VOUT") (pintype "power_out") (zone_connect 2)
      (options (clearance outline) (anchor rect))
      (primitives
        (gr_poly
          (pts
            (xy -0.2 -0.125)
            (xy 0.27 -0.125)
            (xy 0.02 0.125)
            (xy -0.2 0.125)
          )
          (width 0.01) (fill yes))
      ))
    (pad "2" smd custom (at -0.452 0.325) (size 0.1 0.1) (layers "F.Cu")
      (net 1 "GND") (pinfunction "GND") (pintype "power_in") (zone_connect 2)
      (options (clearance outline) (anchor rect))
      (primitives
        (gr_poly
          (pts
            (xy -0.2 0.125)
            (xy 0.2 0.125)
            (xy 0.2 0.055)
            (xy 0.02 -0.125)
            (xy -0.2 -0.125)
          )
          (width 0.01) (fill yes))
      ))
    (pad "3" smd custom (at 0.45 0.325) (size 0.1 0.1) (layers "F.Cu")
      (net 20 "PL_3V3") (pinfunction "EN") (pintype "input") (zone_connect 2)
      (options (clearance outline) (anchor rect))
      (primitives
        (gr_poly
          (pts
            (xy 0.2 0.125)
            (xy -0.2 0.125)
            (xy -0.2 0.055)
            (xy -0.02 -0.125)
            (xy 0.2 -0.125)
          )
          (width 0.01) (fill yes))
      ))
    (pad "4" smd custom (at 0.45 -0.327) (size 0.1 0.1) (layers "F.Cu")
      (net 20 "PL_3V3") (pinfunction "VIN") (pintype "power_in") (zone_connect 2)
      (options (clearance outline) (anchor rect))
      (primitives
        (gr_poly
          (pts
            (xy 0.2 -0.125)
            (xy -0.2 -0.125)
            (xy -0.2 -0.055)
            (xy -0.02 0.125)
            (xy 0.2 0.125)
          )
          (width 0.01) (fill yes))
      ))
    (pad "5" smd rect (at 0 0 45) (size 0.48 0.48) (layers "F.Cu" "F.Mask")
      (net 1 "GND") (pinfunction "EP") (pintype "passive") (zone_connect 2))
  )

  (footprint "kria-k26-devboard-footprints:C_0402_1005Metric" (layer "F.Cu")
    (at 82.28 117.84 -90)
    (descr "Capacitor SMD 0402")
    (tags "capacitor SMD 0402")
    (property "Author" "Antmicro")
    (property "DNP" "DNP")
    (property "Dielectric" "")
    (property "License" "Apache-2.0")
    (property "MPN" "C1005X5R1E474M050BB")
    (property "Manufacturer" "TDK")
    (property "Sheetfile" "camera.kicad_sch")
    (property "Sheetname" "Camera interface")
    (property "Val" "470n")
    (property "Voltage" "")
    (property "dnp" "")
    (property "exclude_from_bom" "")
    (property "ki_description" " ")
    (attr exclude_from_pos_files exclude_from_bom)
    (fp_text reference "C31" (at -0.86 -0.4 -90) (layer "F.SilkS")
        (effects (font (size 0.7 0.7) (thickness 0.15)) (justify left bottom))
    )
    (fp_text value "C_470n_0402" (at 0 1.4 -90) (layer "F.Fab") hide
        (effects (font (size 0.7 0.7) (thickness 0.15)) (justify left bottom))
    )
    (fp_text user "License: Apache-2.0" (at -0.932 5.17 -90) (layer "F.Fab") hide
        (effects (font (size 0.7 0.7) (thickness 0.15)) (justify left bottom))
    )
    (fp_text user "${REFERENCE}" (at -0.932 3.168 -90) (layer "F.Fab") hide
        (effects (font (size 0.7 0.7) (thickness 0.15)) (justify left bottom))
    )
    (fp_text user "Author: Antmicro" (at -0.932 4.17 -90) (layer "F.Fab") hide
        (effects (font (size 0.7 0.7) (thickness 0.15)) (justify left bottom))
    )
    (fp_rect (start -0.94 -0.47) (end 0.94 0.47)
      (stroke (width 0.05) (type solid)) (fill none) (layer "F.CrtYd"))
    (fp_rect (start -0.499 -0.249) (end 0.499 0.249)
      (stroke (width 0.15) (type solid)) (fill none) (layer "F.Fab"))
    (pad "1" smd roundrect (at -0.484 0 270) (size 0.59 0.64) (layers "F.Cu" "F.Paste" "F.Mask") (roundrect_rratio 0.25)
      (net 322 "PL_1V8") (pintype "passive"))
    (pad "2" smd roundrect (at 0.484 0 270) (size 0.59 0.64) (layers "F.Cu" "F.Paste" "F.Mask") (roundrect_rratio 0.25)
      (net 1 "GND") (pintype "passive"))
  )

  (footprint "kria-k26-devboard-footprints:C_0402_1005Metric" (layer "F.Cu")
    (at 83.874999 119.35 180)
    (descr "Capacitor SMD 0402")
    (tags "capacitor SMD 0402")
    (property "Author" "Antmicro")
    (property "DNP" "DNP")
    (property "Dielectric" "")
    (property "License" "Apache-2.0")
    (property "MPN" "C1005X5R1E474M050BB")
    (property "Manufacturer" "TDK")
    (property "Sheetfile" "camera.kicad_sch")
    (property "Sheetname" "Camera interface")
    (property "Val" "470n")
    (property "Voltage" "")
    (property "dnp" "")
    (property "exclude_from_bom" "")
    (property "ki_description" " ")
    (attr exclude_from_pos_files exclude_from_bom)
    (fp_text reference "C30" (at 1.044999 3.13 180) (layer "F.SilkS")
        (effects (font (size 0.7 0.7) (thickness 0.15)) (justify left bottom))
    )
    (fp_text value "C_470n_0402" (at 0 1.4 180) (layer "F.Fab") hide
        (effects (font (size 0.7 0.7) (thickness 0.15)) (justify left bottom))
    )
    (fp_text user "Author: Antmicro" (at -0.932 4.17 180) (layer "F.Fab") hide
        (effects (font (size 0.7 0.7) (thickness 0.15)) (justify left bottom))
    )
    (fp_text user "${REFERENCE}" (at -0.932 3.168 180) (layer "F.Fab") hide
        (effects (font (size 0.7 0.7) (thickness 0.15)) (justify left bottom))
    )
    (fp_text user "License: Apache-2.0" (at -0.932 5.17 180) (layer "F.Fab") hide
        (effects (font (size 0.7 0.7) (thickness 0.15)) (justify left bottom))
    )
    (fp_rect (start -0.94 -0.47) (end 0.94 0.47)
      (stroke (width 0.05) (type solid)) (fill none) (layer "F.CrtYd"))
    (fp_rect (start -0.499 -0.249) (end 0.499 0.249)
      (stroke (width 0.15) (type solid)) (fill none) (layer "F.Fab"))
    (pad "1" smd roundrect (at -0.484 0 180) (size 0.59 0.64) (layers "F.Cu" "F.Paste" "F.Mask") (roundrect_rratio 0.25)
      (net 20 "PL_3V3") (pintype "passive"))
    (pad "2" smd roundrect (at 0.484 0 180) (size 0.59 0.64) (layers "F.Cu" "F.Paste" "F.Mask") (roundrect_rratio 0.25)
      (net 1 "GND") (pintype "passive"))
  )

  (footprint "kria-k26-devboard-footprints:TP_SMD_0.75mm" (layer "F.Cu")
    (at 134.725 117.825)
    (property "Author" "Antmicro")
    (property "License" "Apache-2.0")
    (property "MPN" "")
    (property "Manufacturer" "")
    (property "Sheetfile" "pcie-m2-key-e.kicad_sch")
    (property "Sheetname" "PCIE M2 key E ")
    (property "ki_description" "Test Point 0.75mm")
    (attr exclude_from_pos_files)
    (fp_text reference "TP47" (at -1.345 1.225) (layer "F.SilkS")
        (effects (font (size 0.7 0.7) (thickness 0.15)) (justify left bottom))
    )
    (fp_text value "TP_0.75mm_SMD" (at 0 1.2) (layer "F.Fab") hide
        (effects (font (size 0.7 0.7) (thickness 0.15)) (justify left bottom))
    )
    (fp_text user "License: Apache-2.0" (at -0.4 5.101) (layer "F.Fab") hide
        (effects (font (size 0.7 0.7) (thickness 0.15)) (justify left bottom))
    )
    (fp_text user "${REFERENCE}" (at -0.4 2.7) (layer "F.Fab") hide
        (effects (font (size 0.7 0.7) (thickness 0.15)) (justify left bottom))
    )
    (fp_text user "Author: Antmicro" (at -0.4 3.901) (layer "F.Fab") hide
        (effects (font (size 0.7 0.7) (thickness 0.15)) (justify left bottom))
    )
    (pad "1" smd circle (at 0 0) (size 0.75 0.75) (layers "F.Cu" "F.Mask")
      (net 396 "Net-(J12-~{CLKREQ0})") (pinfunction "1") (pintype "passive"))
  )

  (footprint "kria-k26-devboard-footprints:TP_SMD_0.75mm" (layer "F.Cu")
    (at 134.725 116.85)
    (property "Author" "Antmicro")
    (property "License" "Apache-2.0")
    (property "MPN" "")
    (property "Manufacturer" "")
    (property "Sheetfile" "pcie-m2-key-e.kicad_sch")
    (property "Sheetname" "PCIE M2 key E ")
    (property "ki_description" "Test Point 0.75mm")
    (attr exclude_from_pos_files)
    (fp_text reference "TP48" (at -1.335 -0.33) (layer "F.SilkS")
        (effects (font (size 0.7 0.7) (thickness 0.15)) (justify left bottom))
    )
    (fp_text value "TP_0.75mm_SMD" (at 0 1.2) (layer "F.Fab") hide
        (effects (font (size 0.7 0.7) (thickness 0.15)) (justify left bottom))
    )
    (fp_text user "Author: Antmicro" (at -0.4 3.901) (layer "F.Fab") hide
        (effects (font (size 0.7 0.7) (thickness 0.15)) (justify left bottom))
    )
    (fp_text user "${REFERENCE}" (at -0.4 2.7) (layer "F.Fab") hide
        (effects (font (size 0.7 0.7) (thickness 0.15)) (justify left bottom))
    )
    (fp_text user "License: Apache-2.0" (at -0.4 5.101) (layer "F.Fab") hide
        (effects (font (size 0.7 0.7) (thickness 0.15)) (justify left bottom))
    )
    (pad "1" smd circle (at 0 0) (size 0.75 0.75) (layers "F.Cu" "F.Mask")
      (net 227 "/PCIE M2 key E /~{M2_PEWAKE}") (pinfunction "1") (pintype "passive"))
  )

  (footprint "kria-k26-devboard-footprints:TP_SMD_0.75mm" (layer "F.Cu")
    (at 126 117.625)
    (property "Author" "Antmicro")
    (property "License" "Apache-2.0")
    (property "MPN" "")
    (property "Manufacturer" "")
    (property "Sheetfile" "pcie-m2-key-e.kicad_sch")
    (property "Sheetname" "PCIE M2 key E ")
    (property "ki_description" "Test Point 0.75mm")
    (attr exclude_from_pos_files)
    (fp_text reference "TP49" (at -1.35 -0.375) (layer "F.SilkS")
        (effects (font (size 0.7 0.7) (thickness 0.15)) (justify left bottom))
    )
    (fp_text value "TP_0.75mm_SMD" (at 0 1.2) (layer "F.Fab") hide
        (effects (font (size 0.7 0.7) (thickness 0.15)) (justify left bottom))
    )
    (fp_text user "Author: Antmicro" (at -0.4 3.901) (layer "F.Fab") hide
        (effects (font (size 0.7 0.7) (thickness 0.15)) (justify left bottom))
    )
    (fp_text user "License: Apache-2.0" (at -0.4 5.101) (layer "F.Fab") hide
        (effects (font (size 0.7 0.7) (thickness 0.15)) (justify left bottom))
    )
    (fp_text user "${REFERENCE}" (at -0.4 2.7) (layer "F.Fab") hide
        (effects (font (size 0.7 0.7) (thickness 0.15)) (justify left bottom))
    )
    (pad "1" smd circle (at 0 0) (size 0.75 0.75) (layers "F.Cu" "F.Mask")
      (net 221 "/PCIE M2 key E /~{M2_PERST}") (pinfunction "1") (pintype "passive"))
  )

  (footprint "kria-k26-devboard-footprints:R_0402_1005Metric" (layer "F.Cu")
    (at 81.325 119.25 -90)
    (descr "Resistor SMD 0402")
    (tags "resistor SMD 0402")
    (property "Author" "Antmicro")
    (property "DNP" "DNP")
    (property "License" "Apache-2.0")
    (property "MPN" "CR0402-FX-1501GLF")
    (property "Manufacturer" "Bourns")
    (property "Sheetfile" "camera.kicad_sch")
    (property "Sheetname" "Camera interface")
    (property "Tolerance" "1%")
    (property "Val" "1k5")
    (property "dnp" "")
    (property "exclude_from_bom" "")
    (property "ki_description" "1k5 resistor in 0402 package with 1% tolerance")
    (attr exclude_from_pos_files exclude_from_bom)
    (fp_text reference "R28" (at -0.85 -0.355 -90) (layer "F.SilkS")
        (effects (font (size 0.7 0.7) (thickness 0.15)) (justify left bottom))
    )
    (fp_text value "R_1k5_0402" (at 0 1.4 -90) (layer "F.Fab") hide
        (effects (font (size 0.7 0.7) (thickness 0.15)) (justify left bottom))
    )
    (fp_text user "Author: Antmicro" (at -0.95 4.169 -90) (layer "F.Fab") hide
        (effects (font (size 0.7 0.7) (thickness 0.15)) (justify left bottom))
    )
    (fp_text user "${REFERENCE}" (at -0.95 3.168 -90) (layer "F.Fab") hide
        (effects (font (size 0.7 0.7) (thickness 0.15)) (justify left bottom))
    )
    (fp_text user "License: Apache-2.0" (at -0.95 5.169 -90) (layer "F.Fab") hide
        (effects (font (size 0.7 0.7) (thickness 0.15)) (justify left bottom))
    )
    (fp_rect (start -0.93 -0.47) (end 0.93 0.47)
      (stroke (width 0.05) (type solid)) (fill none) (layer "F.CrtYd"))
    (fp_rect (start -0.5 -0.25) (end 0.5 0.25)
      (stroke (width 0.15) (type solid)) (fill none) (layer "F.Fab"))
    (pad "1" smd roundrect (at -0.485 0 270) (size 0.59 0.64) (layers "F.Cu" "F.Paste" "F.Mask") (roundrect_rratio 0.25)
      (net 322 "PL_1V8") (pintype "passive"))
    (pad "2" smd roundrect (at 0.485 0 270) (size 0.59 0.64) (layers "F.Cu" "F.Paste" "F.Mask") (roundrect_rratio 0.25)
      (net 196 "/Camera interface/CCI0_I2C_SDA_3V3") (pintype "passive"))
  )

  (footprint "kria-k26-devboard-footprints:Oscillator_SMD_Abracon_AX3_3.2x2.5x1mm" (layer "F.Cu")
    (at 101.325 95.775 -90)
    (property "Author" "Antmicro")
    (property "License" "Apache-2.0")
    (property "MPN" "AX3DAF1-125.0000")
    (property "Manufacturer" "Abracon")
    (property "Sheetfile" "clock.kicad_sch")
    (property "Sheetname" "Clock distribution")
    (property "Val" "125 MHz")
    (property "ki_description" "125 MHz XO (Standard) LVDS Oscillator 3.3V Enable/Disable 6-SMD, No Lead")
    (property "ki_keywords" "OSCILLATOR, LVDS")
    (attr smd)
    (fp_text reference "Y3" (at 0.705 1.975 90) (layer "F.SilkS")
        (effects (font (size 0.7 0.7) (thickness 0.15)) (justify left bottom))
    )
    (fp_text value "Oscillator_125MHz_AX3DA" (at 0 2.8 90) (layer "F.Fab") hide
        (effects (font (size 0.7 0.7) (thickness 0.15)) (justify right bottom))
    )
    (fp_text user "Author: Antmicro" (at -1.6 5.3 90) (layer "F.Fab") hide
        (effects (font (size 0.7 0.7) (thickness 0.15)) (justify right bottom))
    )
    (fp_text user "License: Apache-2.0" (at -1.6 6.499 90) (layer "F.Fab") hide
        (effects (font (size 0.7 0.7) (thickness 0.15)) (justify right bottom))
    )
    (fp_text user "${REFERENCE}" (at -1.6 4.1 90) (layer "F.Fab") hide
        (effects (font (size 0.7 0.7) (thickness 0.15)) (justify right bottom))
    )
    (fp_line (start -1.5 -1.8) (end -1.5 -1.5)
      (stroke (width 0.12) (type solid)) (layer "F.SilkS"))
    (fp_line (start -1.5 1.5) (end -1.5 1.8)
      (stroke (width 0.12) (type solid)) (layer "F.SilkS"))
    (fp_line (start -1.5 1.8) (end 1.5 1.8)
      (stroke (width 0.12) (type solid)) (layer "F.SilkS"))
    (fp_line (start 1.5 -1.8) (end -1.5 -1.8)
      (stroke (width 0.12) (type solid)) (layer "F.SilkS"))
    (fp_line (start 1.5 -1.5) (end 1.5 -1.8)
      (stroke (width 0.12) (type solid)) (layer "F.SilkS"))
    (fp_line (start 1.5 1.8) (end 1.5 1.5)
      (stroke (width 0.12) (type solid)) (layer "F.SilkS"))
    (fp_circle (center -1.7 -1.9) (end -1.7 -1.85)
      (stroke (width 0.15) (type solid)) (fill solid) (layer "F.SilkS"))
    (fp_rect (start 1.6 -1.9) (end -1.6 1.9)
      (stroke (width 0.05) (type solid)) (fill none) (layer "F.CrtYd"))
    (fp_line (start -0.6 -1.6) (end -1.3 -0.9)
      (stroke (width 0.15) (type solid)) (layer "F.Fab"))
    (fp_rect (start 1.3 -1.601) (end -1.3 1.599)
      (stroke (width 0.15) (type solid)) (fill none) (layer "F.Fab"))
    (pad "1" smd rect (at -0.8 -1.199 180) (size 0.9 1.1) (layers "F.Cu" "F.Paste" "F.Mask")
      (net 185 "/Clock distribution/PS_CLK_EN") (pinfunction "EN") (pintype "input"))
    (pad "2" smd rect (at -0.8 0 180) (size 0.9 1.1) (layers "F.Cu" "F.Paste" "F.Mask")
      (net 797 "unconnected-(Y3-NC-Pad2)") (pinfunction "NC") (pintype "no_connect"))
    (pad "3" smd rect (at -0.8 1.199 180) (size 0.9 1.1) (layers "F.Cu" "F.Paste" "F.Mask")
      (net 1 "GND") (pinfunction "GND") (pintype "power_in"))
    (pad "4" smd rect (at 0.801 1.199 180) (size 0.9 1.1) (layers "F.Cu" "F.Paste" "F.Mask")
      (net 183 "/Clock distribution/GTR_REFCLK2_C2M_P") (pinfunction "OUT+") (pintype "output"))
    (pad "5" smd rect (at 0.801 0 180) (size 0.9 1.1) (layers "F.Cu" "F.Paste" "F.Mask")
      (net 184 "/Clock distribution/GTR_REFCLK2_C2M_N") (pinfunction "OUT-") (pintype "output"))
    (pad "6" smd rect (at 0.801 -1.199 180) (size 0.9 1.1) (layers "F.Cu" "F.Paste" "F.Mask")
      (net 15 "PS_3V3") (pinfunction "VCC") (pintype "power_in"))
  )

  (footprint "kria-k26-devboard-footprints:C_0402_1005Metric" (layer "F.Cu")
    (at 103.7 96.199999 90)
    (descr "Capacitor SMD 0402")
    (tags "capacitor SMD 0402")
    (property "Author" "Antmicro")
    (property "Dielectric" "X5R")
    (property "License" "Apache-2.0")
    (property "MPN" "GRM155R61H104KE14D")
    (property "Manufacturer" "Murata")
    (property "Sheetfile" "clock.kicad_sch")
    (property "Sheetname" "Clock distribution")
    (property "Val" "100n")
    (property "Voltage" "50V")
    (property "ki_description" " ")
    (attr smd)
    (fp_text reference "C28" (at 0.829999 0.489999 90) (layer "F.SilkS")
        (effects (font (size 0.7 0.7) (thickness 0.15)) (justify left bottom))
    )
    (fp_text value "C_100n_0402" (at 0 1.4 90) (layer "F.Fab") hide
        (effects (font (size 0.7 0.7) (thickness 0.15)) (justify left bottom))
    )
    (fp_text user "Author: Antmicro" (at -0.932 4.17 90) (layer "F.Fab") hide
        (effects (font (size 0.7 0.7) (thickness 0.15)) (justify left bottom))
    )
    (fp_text user "${REFERENCE}" (at -0.932 3.168 90) (layer "F.Fab") hide
        (effects (font (size 0.7 0.7) (thickness 0.15)) (justify left bottom))
    )
    (fp_text user "License: Apache-2.0" (at -0.932 5.17 90) (layer "F.Fab") hide
        (effects (font (size 0.7 0.7) (thickness 0.15)) (justify left bottom))
    )
    (fp_rect (start -0.94 -0.47) (end 0.94 0.47)
      (stroke (width 0.05) (type solid)) (fill none) (layer "F.CrtYd"))
    (fp_rect (start -0.499 -0.249) (end 0.499 0.249)
      (stroke (width 0.15) (type solid)) (fill none) (layer "F.Fab"))
    (pad "1" smd roundrect (at -0.484 0 90) (size 0.59 0.64) (layers "F.Cu" "F.Paste" "F.Mask") (roundrect_rratio 0.25)
      (net 15 "PS_3V3") (pintype "passive"))
    (pad "2" smd roundrect (at 0.484 0 90) (size 0.59 0.64) (layers "F.Cu" "F.Paste" "F.Mask") (roundrect_rratio 0.25)
      (net 1 "GND") (pintype "passive"))
  )

  (footprint "kria-k26-devboard-footprints:TP_SMD_0.75mm" (layer "F.Cu")
    (at 100 137.3)
    (property "Author" "Antmicro")
    (property "License" "Apache-2.0")
    (property "MPN" "")
    (property "Manufacturer" "")
    (property "Sheetfile" "i2c.kicad_sch")
    (property "Sheetname" "I2C ")
    (property "ki_description" "Test Point 0.75mm")
    (attr exclude_from_pos_files)
    (fp_text reference "TP9" (at 0.41 2.32 90) (layer "F.SilkS")
        (effects (font (size 0.7 0.7) (thickness 0.15)) (justify left bottom))
    )
    (fp_text value "TP_0.75mm_SMD" (at 0 1.2) (layer "F.Fab") hide
        (effects (font (size 0.7 0.7) (thickness 0.15)) (justify left bottom))
    )
    (fp_text user "License: Apache-2.0" (at -0.4 5.101) (layer "F.Fab") hide
        (effects (font (size 0.7 0.7) (thickness 0.15)) (justify left bottom))
    )
    (fp_text user "${REFERENCE}" (at -0.4 2.7) (layer "F.Fab") hide
        (effects (font (size 0.7 0.7) (thickness 0.15)) (justify left bottom))
    )
    (fp_text user "Author: Antmicro" (at -0.4 3.901) (layer "F.Fab") hide
        (effects (font (size 0.7 0.7) (thickness 0.15)) (justify left bottom))
    )
    (pad "1" smd circle (at 0 0) (size 0.75 0.75) (layers "F.Cu" "F.Mask")
      (net 163 "/I2C /I2C_SDA_3V3") (pinfunction "1") (pintype "passive"))
  )

  (footprint "kria-k26-devboard-footprints:TP_SMD_0.75mm" (layer "F.Cu")
    (at 177.65 115)
    (property "Author" "Antmicro")
    (property "License" "Apache-2.0")
    (property "MPN" "")
    (property "Manufacturer" "")
    (property "Sheetfile" "dc-dc-conventers.kicad_sch")
    (property "Sheetname" "DC/DC conventers")
    (property "ki_description" "Test Point 0.75mm")
    (attr exclude_from_pos_files)
    (fp_text reference "TP38" (at -1.21 -1.67) (layer "F.SilkS")
        (effects (font (size 0.7 0.7) (thickness 0.15)) (justify left bottom))
    )
    (fp_text value "TP_0.75mm_SMD" (at 0 1.2) (layer "F.Fab") hide
        (effects (font (size 0.7 0.7) (thickness 0.15)) (justify left bottom))
    )
    (fp_text user "${REFERENCE}" (at -0.4 2.7) (layer "F.Fab") hide
        (effects (font (size 0.7 0.7) (thickness 0.15)) (justify left bottom))
    )
    (fp_text user "License: Apache-2.0" (at -0.4 5.101) (layer "F.Fab") hide
        (effects (font (size 0.7 0.7) (thickness 0.15)) (justify left bottom))
    )
    (fp_text user "Author: Antmicro" (at -0.4 3.901) (layer "F.Fab") hide
        (effects (font (size 0.7 0.7) (thickness 0.15)) (justify left bottom))
    )
    (pad "1" smd circle (at 0 0) (size 0.75 0.75) (layers "F.Cu" "F.Mask")
      (net 767 "/Power Supply/DC/DC conventers/PS_1V8_OUT") (pinfunction "1") (pintype "passive"))
  )

  (footprint "kria-k26-devboard-footprints:SOT-416" (layer "F.Cu")
    (at 184.04 135.75 -90)
    (descr "SOT-416")
    (tags "SOT-416")
    (property "Author" "Antmicro")
    (property "License" "Apache-2.0")
    (property "MPN" "DTC014TEBTL")
    (property "Manufacturer" "ROHM Semiconductor")
    (property "Sheetfile" "dc-dc-conventers.kicad_sch")
    (property "Sheetname" "DC/DC conventers")
    (property "ki_description" "Digital NPN Transistor, 10k/NONE, EMT-3")
    (attr smd)
    (fp_text reference "Q15" (at -0.89 -0.06 -90) (layer "F.SilkS")
        (effects (font (size 0.7 0.7) (thickness 0.15)) (justify left bottom))
    )
    (fp_text value "DTC014T_SOT-416" (at 0 2 -90) (layer "F.Fab") hide
        (effects (font (size 0.7 0.7) (thickness 0.15)) (justify left bottom))
    )
    (fp_text user "License: Apache-2.0" (at -1 5.802 -90) (layer "F.Fab") hide
        (effects (font (size 0.7 0.7) (thickness 0.15)) (justify left bottom))
    )
    (fp_text user "Author: Antmicro" (at -1 4.602 -90) (layer "F.Fab") hide
        (effects (font (size 0.7 0.7) (thickness 0.15)) (justify left bottom))
    )
    (fp_text user "${REFERENCE}" (at -1 3.4 -90) (layer "F.Fab") hide
        (effects (font (size 0.7 0.7) (thickness 0.15)) (justify left bottom))
    )
    (fp_line (start -0.5 -0.15) (end -0.5 0.15)
      (stroke (width 0.15) (type solid)) (layer "F.SilkS"))
    (fp_line (start 0.5 0.9) (end -0.5 0.9)
      (stroke (width 0.15) (type solid)) (layer "F.SilkS"))
    (fp_line (start 0.5 0.9) (end 0.5 0.7)
      (stroke (width 0.15) (type solid)) (layer "F.SilkS"))
    (fp_line (start 0.508 -0.9) (end -0.5 -0.9)
      (stroke (width 0.15) (type solid)) (layer "F.SilkS"))
    (fp_line (start 0.508 -0.9) (end 0.508 -0.592)
      (stroke (width 0.15) (type solid)) (layer "F.SilkS"))
    (fp_rect (start -1 -1.05) (end 1 1.05)
      (stroke (width 0.05) (type solid)) (fill none) (layer "F.CrtYd"))
    (fp_line (start -0.05 -0.9) (end -0.45 -0.5)
      (stroke (width 0.15) (type solid)) (layer "F.Fab"))
    (fp_rect (start 0.45 0.9) (end -0.45 -0.9)
      (stroke (width 0.15) (type solid)) (fill none) (layer "F.Fab"))
    (pad "1" smd rect (at -0.652 -0.5 270) (size 0.6 0.5) (layers "F.Cu" "F.Paste" "F.Mask")
      (net 771 "/Power Supply/DC/DC conventers/PL_1V2_OUT") (pinfunction "B") (pintype "input"))
    (pad "2" smd rect (at -0.652 0.498 270) (size 0.6 0.5) (layers "F.Cu" "F.Paste" "F.Mask")
      (net 1 "GND") (pinfunction "E") (pintype "passive"))
    (pad "3" smd rect (at 0.65 0 270) (size 0.6 0.5) (layers "F.Cu" "F.Paste" "F.Mask")
      (net 340 "Net-(Q15-C)") (pinfunction "C") (pintype "passive"))
  )

  (footprint "kria-k26-devboard-footprints:TP_SMD_0.75mm" (layer "F.Cu")
    (at 164.45 116.95)
    (property "Author" "Antmicro")
    (property "License" "Apache-2.0")
    (property "MPN" "")
    (property "Manufacturer" "")
    (property "Sheetfile" "dc-dc-conventers.kicad_sch")
    (property "Sheetname" "DC/DC conventers")
    (property "ki_description" "Test Point 0.75mm")
    (attr exclude_from_pos_files)
    (fp_text reference "TP39" (at -1.29 1.19 90) (layer "F.SilkS")
        (effects (font (size 0.7 0.7) (thickness 0.15)) (justify left bottom))
    )
    (fp_text value "TP_0.75mm_SMD" (at 0 1.2) (layer "F.Fab") hide
        (effects (font (size 0.7 0.7) (thickness 0.15)) (justify left bottom))
    )
    (fp_text user "${REFERENCE}" (at -0.4 2.7) (layer "F.Fab") hide
        (effects (font (size 0.7 0.7) (thickness 0.15)) (justify left bottom))
    )
    (fp_text user "Author: Antmicro" (at -0.4 3.901) (layer "F.Fab") hide
        (effects (font (size 0.7 0.7) (thickness 0.15)) (justify left bottom))
    )
    (fp_text user "License: Apache-2.0" (at -0.4 5.101) (layer "F.Fab") hide
        (effects (font (size 0.7 0.7) (thickness 0.15)) (justify left bottom))
    )
    (pad "1" smd circle (at 0 0) (size 0.75 0.75) (layers "F.Cu" "F.Mask")
      (net 768 "/Power Supply/DC/DC conventers/PS_1V2_OUT") (pinfunction "1") (pintype "passive"))
  )

  (footprint "kria-k26-devboard-footprints:UQFN-10_1.4x1.8x0.5mm_P0.4mm" (layer "F.Cu")
    (at 107.975 144.175 -90)
    (property "Author" "Antmicro")
    (property "License" "Apache-2.0")
    (property "MPN" "SN74AVC2T245RSWR")
    (property "Manufacturer" "Texas Instruments")
    (property "Sheetfile" "reset.kicad_sch")
    (property "Sheetname" "Reset logic")
    (property "ki_description" "Transceiver Non Inverting, AVC Family, 2 Input, 12 mA, 2.4 ns, 1.2 V to 3.6 V, LFCSP-10")
    (property "ki_keywords" "SMT, LOGIC, IC, LEVEL-SHIFTER, VOLTAGE")
    (attr smd)
    (fp_text reference "U34" (at 0.815 1.705 -90) (layer "F.SilkS")
        (effects (font (size 0.7 0.7) (thickness 0.15)) (justify left bottom))
    )
    (fp_text value "SN74AVC2T245_UQFN" (at 0 2.4 -90) (layer "F.Fab") hide
        (effects (font (size 0.7 0.7) (thickness 0.15)) (justify left bottom))
    )
    (fp_text user "${REFERENCE}" (at -0.657 4.498 -90) (layer "F.Fab") hide
        (effects (font (size 0.7 0.7) (thickness 0.15)) (justify left bottom))
    )
    (fp_text user "License: Apache-2.0" (at -0.657 6.9 -90) (layer "F.Fab") hide
        (effects (font (size 0.7 0.7) (thickness 0.15)) (justify left bottom))
    )
    (fp_text user "Author: Antmicro" (at -0.657 5.7 -90) (layer "F.Fab") hide
        (effects (font (size 0.7 0.7) (thickness 0.15)) (justify left bottom))
    )
    (fp_line (start -0.7305 -0.552) (end -1.2005 -0.552)
      (stroke (width 0.15) (type solid)) (layer "F.SilkS"))
    (fp_line (start -0.7305 -0.552) (end -0.7305 -0.93)
      (stroke (width 0.15) (type solid)) (layer "F.SilkS"))
    (fp_circle (center -1.0515 -1.151) (end -0.9805 -1.151)
      (stroke (width 0.15) (type solid)) (fill none) (layer "F.SilkS"))
    (fp_rect (start -1.3 -1.5) (end 1.3 1.5)
      (stroke (width 0.05) (type solid)) (fill none) (layer "F.CrtYd"))
    (fp_line (start -0.7 -0.4) (end -0.175 -0.925)
      (stroke (width 0.15) (type solid)) (layer "F.Fab"))
    (fp_line (start -0.7 0.93) (end -0.7 -0.4)
      (stroke (width 0.15) (type solid)) (layer "F.Fab"))
    (fp_line (start -0.175 -0.925) (end 0.7295 -0.925)
      (stroke (width 0.15) (type solid)) (layer "F.Fab"))
    (fp_line (start 0.725 0.93) (end -0.7 0.93)
      (stroke (width 0.15) (type solid)) (layer "F.Fab"))
    (fp_line (start 0.7295 -0.925) (end 0.725 0.93)
      (stroke (width 0.15) (type solid)) (layer "F.Fab"))
    (pad "1" smd roundrect (at -0.6445 -0.2 270) (size 0.81 0.22) (layers "F.Cu" "F.Paste" "F.Mask") (roundrect_rratio 0.25)
      (net 1 "GND") (pinfunction "DIR_{2}") (pintype "input"))
    (pad "2" smd roundrect (at -0.6445 0.2 270) (size 0.81 0.22) (layers "F.Cu" "F.Paste" "F.Mask") (roundrect_rratio 0.25)
      (net 161 "/Reset logic/PS_RST") (pinfunction "~{OE}") (pintype "input"))
    (pad "3" smd roundrect (at -0.4015 0.844 180) (size 0.81 0.22) (layers "F.Cu" "F.Paste" "F.Mask") (roundrect_rratio 0.25)
      (net 1 "GND") (pinfunction "GND") (pintype "power_in"))
    (pad "4" smd roundrect (at 0.0005 0.844 180) (size 0.81 0.22) (layers "F.Cu" "F.Paste" "F.Mask") (roundrect_rratio 0.25)
      (net 1 "GND") (pinfunction "B_{2}") (pintype "bidirectional"))
    (pad "5" smd roundrect (at 0.3995 0.844 180) (size 0.81 0.22) (layers "F.Cu" "F.Paste" "F.Mask") (roundrect_rratio 0.25)
      (net 224 "/Reset logic/MIO41") (pinfunction "B_{1}") (pintype "bidirectional"))
    (pad "6" smd roundrect (at 0.6455 0.2 270) (size 0.81 0.22) (layers "F.Cu" "F.Paste" "F.Mask") (roundrect_rratio 0.25)
      (net 17 "PS_1V8") (pinfunction "V_{CCB}") (pintype "power_in"))
    (pad "7" smd roundrect (at 0.6455 -0.2 270) (size 0.81 0.22) (layers "F.Cu" "F.Paste" "F.Mask") (roundrect_rratio 0.25)
      (net 15 "PS_3V3") (pinfunction "V_{CCA}") (pintype "power_in"))
    (pad "8" smd roundrect (at 0.3995 -0.847 180) (size 0.81 0.22) (layers "F.Cu" "F.Paste" "F.Mask") (roundrect_rratio 0.25)
      (net 676 "Net-(U34-A_{1})") (pinfunction "A_{1}") (pintype "bidirectional"))
    (pad "9" smd roundrect (at 0.0005 -0.847 180) (size 0.81 0.22) (layers "F.Cu" "F.Paste" "F.Mask") (roundrect_rratio 0.25)
      (net 732 "unconnected-(U34-A_{2}-Pad9)") (pinfunction "A_{2}") (pintype "bidirectional+no_connect"))
    (pad "10" smd roundrect (at -0.4015 -0.847 180) (size 0.81 0.22) (layers "F.Cu" "F.Paste" "F.Mask") (roundrect_rratio 0.25)
      (net 1 "GND") (pinfunction "DIR_{1}") (pintype "input"))
  )

  (footprint "kria-k26-devboard-footprints:TP_SMD_0.75mm" (layer "F.Cu")
    (at 98.9 137.3)
    (property "Author" "Antmicro")
    (property "License" "Apache-2.0")
    (property "MPN" "")
    (property "Manufacturer" "")
    (property "Sheetfile" "i2c.kicad_sch")
    (property "Sheetname" "I2C ")
    (property "ki_description" "Test Point 0.75mm")
    (attr exclude_from_pos_files)
    (fp_text reference "TP8" (at 0.33 2.32 90) (layer "F.SilkS")
        (effects (font (size 0.7 0.7) (thickness 0.15)) (justify left bottom))
    )
    (fp_text value "TP_0.75mm_SMD" (at 0 1.2) (layer "F.Fab") hide
        (effects (font (size 0.7 0.7) (thickness 0.15)) (justify left bottom))
    )
    (fp_text user "${REFERENCE}" (at -0.4 2.7) (layer "F.Fab") hide
        (effects (font (size 0.7 0.7) (thickness 0.15)) (justify left bottom))
    )
    (fp_text user "License: Apache-2.0" (at -0.4 5.101) (layer "F.Fab") hide
        (effects (font (size 0.7 0.7) (thickness 0.15)) (justify left bottom))
    )
    (fp_text user "Author: Antmicro" (at -0.4 3.901) (layer "F.Fab") hide
        (effects (font (size 0.7 0.7) (thickness 0.15)) (justify left bottom))
    )
    (pad "1" smd circle (at 0 0) (size 0.75 0.75) (layers "F.Cu" "F.Mask")
      (net 162 "/I2C /I2C_SCK_3V3") (pinfunction "1") (pintype "passive"))
  )

  (footprint "kria-k26-devboard-footprints:C_0402_1005Metric" (layer "F.Cu")
    (at 148.1 66.915 90)
    (descr "Capacitor SMD 0402")
    (tags "capacitor SMD 0402")
    (property "Author" "Antmicro")
    (property "Dielectric" "X5R")
    (property "License" "Apache-2.0")
    (property "MPN" "GRM155R61H104KE14D")
    (property "Manufacturer" "Murata")
    (property "Sheetfile" "supply-oring.kicad_sch")
    (property "Sheetname" "Supply ORing")
    (property "Val" "100n")
    (property "Voltage" "50V")
    (property "ki_description" " ")
    (attr smd)
    (fp_text reference "C229" (at -3.715 0.39 90) (layer "F.SilkS")
        (effects (font (size 0.7 0.7) (thickness 0.15)) (justify left bottom))
    )
    (fp_text value "C_100n_0402" (at 0 1.4 90) (layer "F.Fab") hide
        (effects (font (size 0.7 0.7) (thickness 0.15)) (justify left bottom))
    )
    (fp_text user "Author: Antmicro" (at -0.932 4.17 90) (layer "F.Fab") hide
        (effects (font (size 0.7 0.7) (thickness 0.15)) (justify left bottom))
    )
    (fp_text user "${REFERENCE}" (at -0.932 3.168 90) (layer "F.Fab") hide
        (effects (font (size 0.7 0.7) (thickness 0.15)) (justify left bottom))
    )
    (fp_text user "License: Apache-2.0" (at -0.932 5.17 90) (layer "F.Fab") hide
        (effects (font (size 0.7 0.7) (thickness 0.15)) (justify left bottom))
    )
    (fp_rect (start -0.94 -0.47) (end 0.94 0.47)
      (stroke (width 0.05) (type solid)) (fill none) (layer "F.CrtYd"))
    (fp_rect (start -0.499 -0.249) (end 0.499 0.249)
      (stroke (width 0.15) (type solid)) (fill none) (layer "F.Fab"))
    (pad "1" smd roundrect (at -0.484 0 90) (size 0.59 0.64) (layers "F.Cu" "F.Paste" "F.Mask") (roundrect_rratio 0.25)
      (net 14 "/Power Supply/DC/DC conventers/DC_MAIN_BUS") (pintype "passive"))
    (pad "2" smd roundrect (at 0.484 0 90) (size 0.59 0.64) (layers "F.Cu" "F.Paste" "F.Mask") (roundrect_rratio 0.25)
      (net 1 "GND") (pintype "passive"))
  )

  (footprint "kria-k26-devboard-footprints:LED_0603_1608Metric_G" (layer "F.Cu")
    (at 176.775 137.9 180)
    (descr "LED SMD 0603 Green")
    (tags "LED SMD 0603 Green")
    (property "Author" "Antmicro")
    (property "Color" "Green")
    (property "License" "Apache-2.0")
    (property "MPN" "LG L29K-G2J1-24-Z")
    (property "Manufacturer" "OSRAM")
    (property "Sheetfile" "dc-dc-conventers.kicad_sch")
    (property "Sheetname" "DC/DC conventers")
    (property "ki_description" "LED, Green, SMT, 0603, 20 mA, 2.1 V, 570 nm")
    (property "ki_keywords" "0603, SMT, DIODE, SEMICONDUCTOR, UNICOLOR")
    (attr smd)
    (fp_text reference "D19" (at 1.215 -0.45) (layer "F.SilkS")
        (effects (font (size 0.7 0.7) (thickness 0.15)) (justify right bottom))
    )
    (fp_text value "LED_G_0603_LG_L29K-G2J1-24-Z" (at 0 1.6) (layer "F.Fab") hide
        (effects (font (size 0.7 0.7) (thickness 0.15)) (justify right bottom))
    )
    (fp_text user "License: Apache-2.0" (at -1.31 5.769) (layer "F.Fab") hide
        (effects (font (size 0.7 0.7) (thickness 0.15)) (justify right bottom))
    )
    (fp_text user "${REFERENCE}" (at -1.31 3.769) (layer "F.Fab") hide
        (effects (font (size 0.7 0.7) (thickness 0.15)) (justify right bottom))
    )
    (fp_text user "Author: Antmicro" (at -1.31 4.769) (layer "F.Fab") hide
        (effects (font (size 0.7 0.7) (thickness 0.15)) (justify right bottom))
    )
    (fp_line (start -0.27 -0.35) (end 0.27 -0.35)
      (stroke (width 0.15) (type solid)) (layer "F.SilkS"))
    (fp_line (start -0.27 0.351) (end 0.27 0.351)
      (stroke (width 0.15) (type solid)) (layer "F.SilkS"))
    (fp_line (start -0.106328 -0.200008) (end -0.106328 0.199992)
      (stroke (width 0.1) (type solid)) (layer "F.SilkS"))
    (fp_line (start -0.106328 -0.200008) (end 0.093672 -0.000008)
      (stroke (width 0.1) (type solid)) (layer "F.SilkS"))
    (fp_line (start -0.106328 -0.000008) (end -0.29 0)
      (stroke (width 0.1) (type solid)) (layer "F.SilkS"))
    (fp_line (start 0.093672 -0.200008) (end 0.093672 0.199992)
      (stroke (width 0.1) (type solid)) (layer "F.SilkS"))
    (fp_line (start 0.093672 -0.000008) (end -0.106328 0.199992)
      (stroke (width 0.1) (type solid)) (layer "F.SilkS"))
    (fp_line (start 0.093672 -0.000008) (end 0.293672 -0.000008)
      (stroke (width 0.1) (type solid)) (layer "F.SilkS"))
    (fp_line (start 1.25 0.32) (end 1.25 -0.32)
      (stroke (width 0.15) (type solid)) (layer "F.SilkS"))
    (fp_rect (start 1.26 0.65) (end -1.26 -0.65)
      (stroke (width 0.05) (type solid)) (fill none) (layer "F.CrtYd"))
    (fp_line (start -0.599 0) (end -0.201 0)
      (stroke (width 0.15) (type solid)) (layer "F.Fab"))
    (fp_line (start -0.201 -0.2) (end -0.201 0)
      (stroke (width 0.15) (type solid)) (layer "F.Fab"))
    (fp_line (start -0.201 0) (end -0.201 0.202)
      (stroke (width 0.15) (type solid)) (layer "F.Fab"))
    (fp_line (start -0.201 0.202) (end 0.101 0)
      (stroke (width 0.15) (type solid)) (layer "F.Fab"))
    (fp_line (start 0.101 0) (end -0.201 -0.2)
      (stroke (width 0.15) (type solid)) (layer "F.Fab"))
    (fp_line (start 0.199 -0.2) (end 0.199 -0.1)
      (stroke (width 0.15) (type solid)) (layer "F.Fab"))
    (fp_line (start 0.199 0) (end 0.597 0)
      (stroke (width 0.15) (type solid)) (layer "F.Fab"))
    (fp_line (start 0.199 0.202) (end 0.199 -0.1)
      (stroke (width 0.15) (type solid)) (layer "F.Fab"))
    (fp_rect (start -0.848 -0.4) (end 0.85 0.402)
      (stroke (width 0.15) (type solid)) (fill none) (layer "F.Fab"))
    (pad "1" smd rect (at -0.75 0) (size 0.8 0.8) (layers "F.Cu" "F.Paste" "F.Mask")
      (net 191 "Net-(D19-Pad1)") (pintype "passive"))
    (pad "2" smd rect (at 0.75 0) (size 0.8 0.8) (layers "F.Cu" "F.Paste" "F.Mask")
      (net 1 "GND") (pinfunction "2") (pintype "passive"))
  )

  (footprint "kria-k26-devboard-footprints:R_0402_1005Metric" (layer "F.Cu")
    (at 131.8 117)
    (descr "Resistor SMD 0402")
    (tags "resistor SMD 0402")
    (property "Author" "Antmicro")
    (property "License" "Apache-2.0")
    (property "MPN" "CR0402-FX-1002GLF")
    (property "Manufacturer" "Bourns")
    (property "Sheetfile" "pcie-m2-key-e.kicad_sch")
    (property "Sheetname" "PCIE M2 key E ")
    (property "Tolerance" "1%")
    (property "Val" "10k")
    (property "ki_description" "10k resistor in 0402 package with 1% tolerance")
    (attr smd)
    (fp_text reference "R152" (at -1.27 -1.56) (layer "F.SilkS")
        (effects (font (size 0.7 0.7) (thickness 0.15)) (justify left bottom))
    )
    (fp_text value "R_10k_0402" (at 0 1.4) (layer "F.Fab") hide
        (effects (font (size 0.7 0.7) (thickness 0.15)) (justify left bottom))
    )
    (fp_text user "${REFERENCE}" (at -0.95 3.168) (layer "F.Fab") hide
        (effects (font (size 0.7 0.7) (thickness 0.15)) (justify left bottom))
    )
    (fp_text user "License: Apache-2.0" (at -0.95 5.169) (layer "F.Fab") hide
        (effects (font (size 0.7 0.7) (thickness 0.15)) (justify left bottom))
    )
    (fp_text user "Author: Antmicro" (at -0.95 4.169) (layer "F.Fab") hide
        (effects (font (size 0.7 0.7) (thickness 0.15)) (justify left bottom))
    )
    (fp_rect (start -0.93 -0.47) (end 0.93 0.47)
      (stroke (width 0.05) (type solid)) (fill none) (layer "F.CrtYd"))
    (fp_rect (start -0.5 -0.25) (end 0.5 0.25)
      (stroke (width 0.15) (type solid)) (fill none) (layer "F.Fab"))
    (pad "1" smd roundrect (at -0.485 0) (size 0.59 0.64) (layers "F.Cu" "F.Paste" "F.Mask") (roundrect_rratio 0.25)
      (net 15 "PS_3V3") (pintype "passive"))
    (pad "2" smd roundrect (at 0.485 0) (size 0.59 0.64) (layers "F.Cu" "F.Paste" "F.Mask") (roundrect_rratio 0.25)
      (net 227 "/PCIE M2 key E /~{M2_PEWAKE}") (pintype "passive"))
  )

  (footprint "kria-k26-devboard-footprints:SOT-416" (layer "F.Cu")
    (at 136.4 124.874999 180)
    (descr "SOT-416")
    (tags "SOT-416")
    (property "Author" "Antmicro")
    (property "License" "Apache-2.0")
    (property "MPN" "DTC014TEBTL")
    (property "Manufacturer" "ROHM Semiconductor")
    (property "Sheetfile" "debug.kicad_sch")
    (property "Sheetname" "Debug and JTAG")
    (property "ki_description" "Digital NPN Transistor, 10k/NONE, EMT-3")
    (attr smd)
    (fp_text reference "Q11" (at 2.78 0.504999) (layer "F.SilkS")
        (effects (font (size 0.7 0.7) (thickness 0.15)) (justify left bottom))
    )
    (fp_text value "DTC014T_SOT-416" (at 0 2 180) (layer "F.Fab") hide
        (effects (font (size 0.7 0.7) (thickness 0.15)) (justify left bottom))
    )
    (fp_text user "License: Apache-2.0" (at -1 5.802 180) (layer "F.Fab") hide
        (effects (font (size 0.7 0.7) (thickness 0.15)) (justify left bottom))
    )
    (fp_text user "${REFERENCE}" (at -1 3.4 180) (layer "F.Fab") hide
        (effects (font (size 0.7 0.7) (thickness 0.15)) (justify left bottom))
    )
    (fp_text user "Author: Antmicro" (at -1 4.602 180) (layer "F.Fab") hide
        (effects (font (size 0.7 0.7) (thickness 0.15)) (justify left bottom))
    )
    (fp_line (start -0.5 -0.15) (end -0.5 0.15)
      (stroke (width 0.15) (type solid)) (layer "F.SilkS"))
    (fp_line (start 0.5 0.9) (end -0.5 0.9)
      (stroke (width 0.15) (type solid)) (layer "F.SilkS"))
    (fp_line (start 0.5 0.9) (end 0.5 0.7)
      (stroke (width 0.15) (type solid)) (layer "F.SilkS"))
    (fp_line (start 0.508 -0.9) (end -0.5 -0.9)
      (stroke (width 0.15) (type solid)) (layer "F.SilkS"))
    (fp_line (start 0.508 -0.9) (end 0.508 -0.592)
      (stroke (width 0.15) (type solid)) (layer "F.SilkS"))
    (fp_rect (start -1 -1.05) (end 1 1.05)
      (stroke (width 0.05) (type solid)) (fill none) (layer "F.CrtYd"))
    (fp_line (start -0.05 -0.9) (end -0.45 -0.5)
      (stroke (width 0.15) (type solid)) (layer "F.Fab"))
    (fp_rect (start 0.45 0.9) (end -0.45 -0.9)
      (stroke (width 0.15) (type solid)) (fill none) (layer "F.Fab"))
    (pad "1" smd rect (at -0.652 -0.5 180) (size 0.6 0.5) (layers "F.Cu" "F.Paste" "F.Mask")
      (net 220 "/Debug and JTAG/CONN_GND") (pinfunction "B") (pintype "input"))
    (pad "2" smd rect (at -0.652 0.498 180) (size 0.6 0.5) (layers "F.Cu" "F.Paste" "F.Mask")
      (net 1 "GND") (pinfunction "E") (pintype "passive"))
    (pad "3" smd rect (at 0.65 0 180) (size 0.6 0.5) (layers "F.Cu" "F.Paste" "F.Mask")
      (net 160 "/Debug and JTAG/~{LS_OE}") (pinfunction "C") (pintype "passive"))
  )

  (footprint "kria-k26-devboard-footprints:R_0402_1005Metric" (layer "F.Cu")
    (at 136.595 123.23 180)
    (descr "Resistor SMD 0402")
    (tags "resistor SMD 0402")
    (property "Author" "Antmicro")
    (property "License" "Apache-2.0")
    (property "MPN" "CR0402-FX-1002GLF")
    (property "Manufacturer" "Bourns")
    (property "Sheetfile" "debug.kicad_sch")
    (property "Sheetname" "Debug and JTAG")
    (property "Tolerance" "1%")
    (property "Val" "10k")
    (property "ki_description" "10k resistor in 0402 package with 1% tolerance")
    (attr smd)
    (fp_text reference "R112" (at 3.675 -0.2 180) (layer "F.SilkS")
        (effects (font (size 0.7 0.7) (thickness 0.15)) (justify left bottom))
    )
    (fp_text value "R_10k_0402" (at 0 1.4 180) (layer "F.Fab") hide
        (effects (font (size 0.7 0.7) (thickness 0.15)) (justify left bottom))
    )
    (fp_text user "${REFERENCE}" (at -0.95 3.168 180) (layer "F.Fab") hide
        (effects (font (size 0.7 0.7) (thickness 0.15)) (justify left bottom))
    )
    (fp_text user "License: Apache-2.0" (at -0.95 5.169 180) (layer "F.Fab") hide
        (effects (font (size 0.7 0.7) (thickness 0.15)) (justify left bottom))
    )
    (fp_text user "Author: Antmicro" (at -0.95 4.169 180) (layer "F.Fab") hide
        (effects (font (size 0.7 0.7) (thickness 0.15)) (justify left bottom))
    )
    (fp_rect (start -0.93 -0.47) (end 0.93 0.47)
      (stroke (width 0.05) (type solid)) (fill none) (layer "F.CrtYd"))
    (fp_rect (start -0.5 -0.25) (end 0.5 0.25)
      (stroke (width 0.15) (type solid)) (fill none) (layer "F.Fab"))
    (pad "1" smd roundrect (at -0.485 0 180) (size 0.59 0.64) (layers "F.Cu" "F.Paste" "F.Mask") (roundrect_rratio 0.25)
      (net 138 "/Debug and JTAG/USB_3V3") (pintype "passive"))
    (pad "2" smd roundrect (at 0.485 0 180) (size 0.59 0.64) (layers "F.Cu" "F.Paste" "F.Mask") (roundrect_rratio 0.25)
      (net 160 "/Debug and JTAG/~{LS_OE}") (pintype "passive"))
  )

  (footprint "kria-k26-devboard-footprints:R_0402_1005Metric" (layer "F.Cu")
    (at 136.595 126.53 180)
    (descr "Resistor SMD 0402")
    (tags "resistor SMD 0402")
    (property "Author" "Antmicro")
    (property "License" "Apache-2.0")
    (property "MPN" "CR0402-FX-1002GLF")
    (property "Manufacturer" "Bourns")
    (property "Sheetfile" "debug.kicad_sch")
    (property "Sheetname" "Debug and JTAG")
    (property "Tolerance" "1%")
    (property "Val" "10k")
    (property "ki_description" "10k resistor in 0402 package with 1% tolerance")
    (attr smd)
    (fp_text reference "R111" (at 3.655 -0.4 180) (layer "F.SilkS")
        (effects (font (size 0.7 0.7) (thickness 0.15)) (justify left bottom))
    )
    (fp_text value "R_10k_0402" (at 0 1.4 180) (layer "F.Fab") hide
        (effects (font (size 0.7 0.7) (thickness 0.15)) (justify left bottom))
    )
    (fp_text user "Author: Antmicro" (at -0.95 4.169 180) (layer "F.Fab") hide
        (effects (font (size 0.7 0.7) (thickness 0.15)) (justify left bottom))
    )
    (fp_text user "License: Apache-2.0" (at -0.95 5.169 180) (layer "F.Fab") hide
        (effects (font (size 0.7 0.7) (thickness 0.15)) (justify left bottom))
    )
    (fp_text user "${REFERENCE}" (at -0.95 3.168 180) (layer "F.Fab") hide
        (effects (font (size 0.7 0.7) (thickness 0.15)) (justify left bottom))
    )
    (fp_rect (start -0.93 -0.47) (end 0.93 0.47)
      (stroke (width 0.05) (type solid)) (fill none) (layer "F.CrtYd"))
    (fp_rect (start -0.5 -0.25) (end 0.5 0.25)
      (stroke (width 0.15) (type solid)) (fill none) (layer "F.Fab"))
    (pad "1" smd roundrect (at -0.485 0 180) (size 0.59 0.64) (layers "F.Cu" "F.Paste" "F.Mask") (roundrect_rratio 0.25)
      (net 138 "/Debug and JTAG/USB_3V3") (pintype "passive"))
    (pad "2" smd roundrect (at 0.485 0 180) (size 0.59 0.64) (layers "F.Cu" "F.Paste" "F.Mask") (roundrect_rratio 0.25)
      (net 220 "/Debug and JTAG/CONN_GND") (pintype "passive"))
  )

  (footprint "kria-k26-devboard-footprints:R_0402_1005Metric" (layer "F.Cu")
    (at 129.28 117.32 -90)
    (descr "Resistor SMD 0402")
    (tags "resistor SMD 0402")
    (property "Author" "Antmicro")
    (property "Current" "1A")
    (property "License" "Apache-2.0")
    (property "MPN" "ERJ2GE0R00X")
    (property "Manufacturer" "Panasonic")
    (property "Sheetfile" "pcie-m2-key-e.kicad_sch")
    (property "Sheetname" "PCIE M2 key E ")
    (property "Tolerance" "")
    (property "Val" "0R")
    (property "ki_description" "0R resistor in 0402 package with unspecified tolerance")
    (attr smd)
    (fp_text reference "R150" (at 1.45 -1.24 -90) (layer "F.SilkS")
        (effects (font (size 0.7 0.7) (thickness 0.15)) (justify left bottom))
    )
    (fp_text value "R_0R_0402" (at 0 1.4 -90) (layer "F.Fab") hide
        (effects (font (size 0.7 0.7) (thickness 0.15)) (justify left bottom))
    )
    (fp_text user "Author: Antmicro" (at -0.95 4.169 -90) (layer "F.Fab") hide
        (effects (font (size 0.7 0.7) (thickness 0.15)) (justify left bottom))
    )
    (fp_text user "${REFERENCE}" (at -0.95 3.168 -90) (layer "F.Fab") hide
        (effects (font (size 0.7 0.7) (thickness 0.15)) (justify left bottom))
    )
    (fp_text user "License: Apache-2.0" (at -0.95 5.169 -90) (layer "F.Fab") hide
        (effects (font (size 0.7 0.7) (thickness 0.15)) (justify left bottom))
    )
    (fp_rect (start -0.93 -0.47) (end 0.93 0.47)
      (stroke (width 0.05) (type solid)) (fill none) (layer "F.CrtYd"))
    (fp_rect (start -0.5 -0.25) (end 0.5 0.25)
      (stroke (width 0.15) (type solid)) (fill none) (layer "F.Fab"))
    (pad "1" smd roundrect (at -0.485 0 270) (size 0.59 0.64) (layers "F.Cu" "F.Paste" "F.Mask") (roundrect_rratio 0.25)
      (net 226 "/Clock distribution/~{M2_CLKREQ}") (pintype "passive"))
    (pad "2" smd roundrect (at 0.485 0 270) (size 0.59 0.64) (layers "F.Cu" "F.Paste" "F.Mask") (roundrect_rratio 0.25)
      (net 396 "Net-(J12-~{CLKREQ0})") (pintype "passive"))
  )

  (footprint "kria-k26-devboard-footprints:C_0402_1005Metric" (layer "F.Cu")
    (at 168.5 132.2 180)
    (descr "Capacitor SMD 0402")
    (tags "capacitor SMD 0402")
    (property "Author" "Antmicro")
    (property "Dielectric" "X5R")
    (property "License" "Apache-2.0")
    (property "MPN" "GRM155R61H104KE14D")
    (property "Manufacturer" "Murata")
    (property "Sheetfile" "dc-dc-conventers.kicad_sch")
    (property "Sheetname" "DC/DC conventers")
    (property "Val" "100n")
    (property "Voltage" "50V")
    (property "ki_description" " ")
    (attr smd)
    (fp_text reference "C206" (at 3.68 -0.4 180) (layer "F.SilkS")
        (effects (font (size 0.7 0.7) (thickness 0.15)) (justify left bottom))
    )
    (fp_text value "C_100n_0402" (at 0 1.4 180) (layer "F.Fab") hide
        (effects (font (size 0.7 0.7) (thickness 0.15)) (justify left bottom))
    )
    (fp_text user "Author: Antmicro" (at -0.932 4.17 180) (layer "F.Fab") hide
        (effects (font (size 0.7 0.7) (thickness 0.15)) (justify left bottom))
    )
    (fp_text user "${REFERENCE}" (at -0.932 3.168 180) (layer "F.Fab") hide
        (effects (font (size 0.7 0.7) (thickness 0.15)) (justify left bottom))
    )
    (fp_text user "License: Apache-2.0" (at -0.932 5.17 180) (layer "F.Fab") hide
        (effects (font (size 0.7 0.7) (thickness 0.15)) (justify left bottom))
    )
    (fp_rect (start -0.94 -0.47) (end 0.94 0.47)
      (stroke (width 0.05) (type solid)) (fill none) (layer "F.CrtYd"))
    (fp_rect (start -0.499 -0.249) (end 0.499 0.249)
      (stroke (width 0.15) (type solid)) (fill none) (layer "F.Fab"))
    (pad "1" smd roundrect (at -0.484 0 180) (size 0.59 0.64) (layers "F.Cu" "F.Paste" "F.Mask") (roundrect_rratio 0.25)
      (net 257 "Net-(U49-BST)") (pintype "passive"))
    (pad "2" smd roundrect (at 0.484 0 180) (size 0.59 0.64) (layers "F.Cu" "F.Paste" "F.Mask") (roundrect_rratio 0.25)
      (net 309 "/Power Supply/DC/DC conventers/SW_PS_3V3") (pintype "passive"))
  )

  (footprint "kria-k26-devboard-footprints:SOT-416" (layer "F.Cu")
    (at 173.65 116.35 90)
    (descr "SOT-416")
    (tags "SOT-416")
    (property "Author" "Antmicro")
    (property "License" "Apache-2.0")
    (property "MPN" "DTC014TEBTL")
    (property "Manufacturer" "ROHM Semiconductor")
    (property "Sheetfile" "dc-dc-conventers.kicad_sch")
    (property "Sheetname" "DC/DC conventers")
    (property "ki_description" "Digital NPN Transistor, 10k/NONE, EMT-3")
    (attr smd)
    (fp_text reference "Q13" (at 1.13 -0.84 180) (layer "F.SilkS")
        (effects (font (size 0.7 0.7) (thickness 0.15)) (justify left bottom))
    )
    (fp_text value "DTC014T_SOT-416" (at 0 2 90) (layer "F.Fab") hide
        (effects (font (size 0.7 0.7) (thickness 0.15)) (justify left bottom))
    )
    (fp_text user "Author: Antmicro" (at -1 4.602 90) (layer "F.Fab") hide
        (effects (font (size 0.7 0.7) (thickness 0.15)) (justify left bottom))
    )
    (fp_text user "License: Apache-2.0" (at -1 5.802 90) (layer "F.Fab") hide
        (effects (font (size 0.7 0.7) (thickness 0.15)) (justify left bottom))
    )
    (fp_text user "${REFERENCE}" (at -1 3.4 90) (layer "F.Fab") hide
        (effects (font (size 0.7 0.7) (thickness 0.15)) (justify left bottom))
    )
    (fp_line (start -0.5 -0.15) (end -0.5 0.15)
      (stroke (width 0.15) (type solid)) (layer "F.SilkS"))
    (fp_line (start 0.5 0.9) (end -0.5 0.9)
      (stroke (width 0.15) (type solid)) (layer "F.SilkS"))
    (fp_line (start 0.5 0.9) (end 0.5 0.7)
      (stroke (width 0.15) (type solid)) (layer "F.SilkS"))
    (fp_line (start 0.508 -0.9) (end -0.5 -0.9)
      (stroke (width 0.15) (type solid)) (layer "F.SilkS"))
    (fp_line (start 0.508 -0.9) (end 0.508 -0.592)
      (stroke (width 0.15) (type solid)) (layer "F.SilkS"))
    (fp_rect (start -1 -1.05) (end 1 1.05)
      (stroke (width 0.05) (type solid)) (fill none) (layer "F.CrtYd"))
    (fp_line (start -0.05 -0.9) (end -0.45 -0.5)
      (stroke (width 0.15) (type solid)) (layer "F.Fab"))
    (fp_rect (start 0.45 0.9) (end -0.45 -0.9)
      (stroke (width 0.15) (type solid)) (fill none) (layer "F.Fab"))
    (pad "1" smd rect (at -0.652 -0.5 90) (size 0.6 0.5) (layers "F.Cu" "F.Paste" "F.Mask")
      (net 768 "/Power Supply/DC/DC conventers/PS_1V2_OUT") (pinfunction "B") (pintype "input"))
    (pad "2" smd rect (at -0.652 0.498 90) (size 0.6 0.5) (layers "F.Cu" "F.Paste" "F.Mask")
      (net 1 "GND") (pinfunction "E") (pintype "passive"))
    (pad "3" smd rect (at 0.65 0 90) (size 0.6 0.5) (layers "F.Cu" "F.Paste" "F.Mask")
      (net 338 "Net-(Q13-C)") (pinfunction "C") (pintype "passive"))
  )

  (footprint "kria-k26-devboard-footprints:LED_0603_1608Metric_G" (layer "F.Cu")
    (at 171.1 115.425)
    (descr "LED SMD 0603 Green")
    (tags "LED SMD 0603 Green")
    (property "Author" "Antmicro")
    (property "Color" "Green")
    (property "License" "Apache-2.0")
    (property "MPN" "LG L29K-G2J1-24-Z")
    (property "Manufacturer" "OSRAM")
    (property "Sheetfile" "dc-dc-conventers.kicad_sch")
    (property "Sheetname" "DC/DC conventers")
    (property "ki_description" "LED, Green, SMT, 0603, 20 mA, 2.1 V, 570 nm")
    (property "ki_keywords" "0603, SMT, DIODE, SEMICONDUCTOR, UNICOLOR")
    (attr smd)
    (fp_text reference "D17" (at 1.43 -1.025) (layer "F.SilkS")
        (effects (font (size 0.7 0.7) (thickness 0.15)) (justify left bottom))
    )
    (fp_text value "LED_G_0603_LG_L29K-G2J1-24-Z" (at 0 1.6) (layer "F.Fab") hide
        (effects (font (size 0.7 0.7) (thickness 0.15)) (justify left bottom))
    )
    (fp_text user "${REFERENCE}" (at -1.31 3.769) (layer "F.Fab") hide
        (effects (font (size 0.7 0.7) (thickness 0.15)) (justify left bottom))
    )
    (fp_text user "License: Apache-2.0" (at -1.31 5.769) (layer "F.Fab") hide
        (effects (font (size 0.7 0.7) (thickness 0.15)) (justify left bottom))
    )
    (fp_text user "Author: Antmicro" (at -1.31 4.769) (layer "F.Fab") hide
        (effects (font (size 0.7 0.7) (thickness 0.15)) (justify left bottom))
    )
    (fp_line (start -0.27 -0.35) (end 0.27 -0.35)
      (stroke (width 0.15) (type solid)) (layer "F.SilkS"))
    (fp_line (start -0.27 0.351) (end 0.27 0.351)
      (stroke (width 0.15) (type solid)) (layer "F.SilkS"))
    (fp_line (start -0.106328 -0.200008) (end -0.106328 0.199992)
      (stroke (width 0.1) (type solid)) (layer "F.SilkS"))
    (fp_line (start -0.106328 -0.200008) (end 0.093672 -0.000008)
      (stroke (width 0.1) (type solid)) (layer "F.SilkS"))
    (fp_line (start -0.106328 -0.000008) (end -0.29 0)
      (stroke (width 0.1) (type solid)) (layer "F.SilkS"))
    (fp_line (start 0.093672 -0.200008) (end 0.093672 0.199992)
      (stroke (width 0.1) (type solid)) (layer "F.SilkS"))
    (fp_line (start 0.093672 -0.000008) (end -0.106328 0.199992)
      (stroke (width 0.1) (type solid)) (layer "F.SilkS"))
    (fp_line (start 0.093672 -0.000008) (end 0.293672 -0.000008)
      (stroke (width 0.1) (type solid)) (layer "F.SilkS"))
    (fp_line (start 1.25 0.32) (end 1.25 -0.32)
      (stroke (width 0.15) (type solid)) (layer "F.SilkS"))
    (fp_rect (start 1.26 0.65) (end -1.26 -0.65)
      (stroke (width 0.05) (type solid)) (fill none) (layer "F.CrtYd"))
    (fp_line (start -0.599 0) (end -0.201 0)
      (stroke (width 0.15) (type solid)) (layer "F.Fab"))
    (fp_line (start -0.201 -0.2) (end -0.201 0)
      (stroke (width 0.15) (type solid)) (layer "F.Fab"))
    (fp_line (start -0.201 0) (end -0.201 0.202)
      (stroke (width 0.15) (type solid)) (layer "F.Fab"))
    (fp_line (start -0.201 0.202) (end 0.101 0)
      (stroke (width 0.15) (type solid)) (layer "F.Fab"))
    (fp_line (start 0.101 0) (end -0.201 -0.2)
      (stroke (width 0.15) (type solid)) (layer "F.Fab"))
    (fp_line (start 0.199 -0.2) (end 0.199 -0.1)
      (stroke (width 0.15) (type solid)) (layer "F.Fab"))
    (fp_line (start 0.199 0) (end 0.597 0)
      (stroke (width 0.15) (type solid)) (layer "F.Fab"))
    (fp_line (start 0.199 0.202) (end 0.199 -0.1)
      (stroke (width 0.15) (type solid)) (layer "F.Fab"))
    (fp_rect (start -0.848 -0.4) (end 0.85 0.402)
      (stroke (width 0.15) (type solid)) (fill none) (layer "F.Fab"))
    (pad "1" smd rect (at -0.75 0 180) (size 0.8 0.8) (layers "F.Cu" "F.Paste" "F.Mask")
      (net 242 "Net-(D17-Pad1)") (pintype "passive"))
    (pad "2" smd rect (at 0.75 0 180) (size 0.8 0.8) (layers "F.Cu" "F.Paste" "F.Mask")
      (net 338 "Net-(Q13-C)") (pinfunction "2") (pintype "passive"))
  )

  (footprint "kria-k26-devboard-footprints:R_0402_1005Metric" (layer "F.Cu")
    (at 168.75 115.675)
    (descr "Resistor SMD 0402")
    (tags "resistor SMD 0402")
    (property "Author" "Antmicro")
    (property "License" "Apache-2.0")
    (property "MPN" "CR0402-FX-1001GLF")
    (property "Manufacturer" "Bourns")
    (property "Sheetfile" "dc-dc-conventers.kicad_sch")
    (property "Sheetname" "DC/DC conventers")
    (property "Tolerance" "1%")
    (property "Val" "1k")
    (property "ki_description" "1k resistor in 0402 package with 1% tolerance")
    (attr smd)
    (fp_text reference "R130" (at -3.26 -1.055) (layer "F.SilkS")
        (effects (font (size 0.7 0.7) (thickness 0.15)) (justify left bottom))
    )
    (fp_text value "R_1k_0402" (at 0 1.4) (layer "F.Fab") hide
        (effects (font (size 0.7 0.7) (thickness 0.15)) (justify left bottom))
    )
    (fp_text user "Author: Antmicro" (at -0.95 4.169) (layer "F.Fab") hide
        (effects (font (size 0.7 0.7) (thickness 0.15)) (justify left bottom))
    )
    (fp_text user "${REFERENCE}" (at -0.95 3.168) (layer "F.Fab") hide
        (effects (font (size 0.7 0.7) (thickness 0.15)) (justify left bottom))
    )
    (fp_text user "License: Apache-2.0" (at -0.95 5.169) (layer "F.Fab") hide
        (effects (font (size 0.7 0.7) (thickness 0.15)) (justify left bottom))
    )
    (fp_rect (start -0.93 -0.47) (end 0.93 0.47)
      (stroke (width 0.05) (type solid)) (fill none) (layer "F.CrtYd"))
    (fp_rect (start -0.5 -0.25) (end 0.5 0.25)
      (stroke (width 0.15) (type solid)) (fill none) (layer "F.Fab"))
    (pad "1" smd roundrect (at -0.485 0) (size 0.59 0.64) (layers "F.Cu" "F.Paste" "F.Mask") (roundrect_rratio 0.25)
      (net 765 "/Power Supply/DC/DC conventers/PS_3V3_OUT") (pintype "passive"))
    (pad "2" smd roundrect (at 0.485 0) (size 0.59 0.64) (layers "F.Cu" "F.Paste" "F.Mask") (roundrect_rratio 0.25)
      (net 242 "Net-(D17-Pad1)") (pintype "passive"))
  )

  (footprint "kria-k26-devboard-footprints:L_0806_2016Metric" (layer "F.Cu")
    (at 169.646999 117.3 180)
    (property "Author" "Antmicro")
    (property "IMax" "")
    (property "ISat" "")
    (property "License" "Apache-2.0")
    (property "MPN" "SRP2010-1R0M")
    (property "Manufacturer" "Bourns")
    (property "Sheetfile" "dc-dc-conventers.kicad_sch")
    (property "Sheetname" "DC/DC conventers")
    (property "Size" "2.0x1.6")
    (property "Val" "1u/2.6A")
    (attr smd)
    (fp_text reference "L6" (at -2.183001 -1.98 180) (layer "F.SilkS")
        (effects (font (size 0.7 0.7) (thickness 0.15)) (justify left bottom))
    )
    (fp_text value "L_1u_2.6A_0806" (at 0 2 180) (layer "F.Fab") hide
        (effects (font (size 0.7 0.7) (thickness 0.15)) (justify left bottom))
    )
    (fp_text user "Author: Antmicro" (at -1.9 4.4 180) (layer "F.Fab") hide
        (effects (font (size 0.7 0.7) (thickness 0.15)) (justify left bottom))
    )
    (fp_text user "${REFERENCE}" (at -1.9 3.1 180) (layer "F.Fab") hide
        (effects (font (size 0.7 0.7) (thickness 0.15)) (justify left bottom))
    )
    (fp_text user "License: Apache-2.0" (at -1.9 5.75 180) (layer "F.Fab") hide
        (effects (font (size 0.7 0.7) (thickness 0.15)) (justify left bottom))
    )
    (fp_line (start -0.301 0.9) (end 0.299 0.9)
      (stroke (width 0.15) (type solid)) (layer "F.SilkS"))
    (fp_line (start -0.3 -0.9) (end 0.298 -0.9)
      (stroke (width 0.15) (type solid)) (layer "F.SilkS"))
    (fp_rect (start -1.75 -1.05) (end 1.75 1.05)
      (stroke (width 0.05) (type solid)) (fill none) (layer "F.CrtYd"))
    (fp_rect (start -0.951 -0.882) (end 0.949 0.875)
      (stroke (width 0.15) (type solid)) (fill none) (layer "F.Fab"))
    (pad "1" smd roundrect (at -1.1 -0.001 180) (size 1 1.8) (layers "F.Cu" "F.Paste" "F.Mask") (roundrect_rratio 0.15)
      (net 312 "/Power Supply/DC/DC conventers/SW_PS_1V2") (pintype "passive"))
    (pad "2" smd roundrect (at 1.1 -0.001 180) (size 1 1.8) (layers "F.Cu" "F.Paste" "F.Mask") (roundrect_rratio 0.15)
      (net 768 "/Power Supply/DC/DC conventers/PS_1V2_OUT") (pintype "passive"))
  )

  (footprint "kria-k26-devboard-footprints:R_0402_1005Metric" (layer "F.Cu")
    (at 174.125 120.95)
    (descr "Resistor SMD 0402")
    (tags "resistor SMD 0402")
    (property "Author" "Antmicro")
    (property "License" "Apache-2.0")
    (property "MPN" "CR0402-FX-1002GLF")
    (property "Manufacturer" "Bourns")
    (property "Sheetfile" "dc-dc-conventers.kicad_sch")
    (property "Sheetname" "DC/DC conventers")
    (property "Tolerance" "1%")
    (property "Val" "10k")
    (property "ki_description" "10k resistor in 0402 package with 1% tolerance")
    (attr smd)
    (fp_text reference "R138" (at -0.755 1.19) (layer "F.SilkS")
        (effects (font (size 0.7 0.7) (thickness 0.15)) (justify left bottom))
    )
    (fp_text value "R_10k_0402" (at 0 1.4) (layer "F.Fab") hide
        (effects (font (size 0.7 0.7) (thickness 0.15)) (justify left bottom))
    )
    (fp_text user "Author: Antmicro" (at -0.95 4.169) (layer "F.Fab") hide
        (effects (font (size 0.7 0.7) (thickness 0.15)) (justify left bottom))
    )
    (fp_text user "${REFERENCE}" (at -0.95 3.168) (layer "F.Fab") hide
        (effects (font (size 0.7 0.7) (thickness 0.15)) (justify left bottom))
    )
    (fp_text user "License: Apache-2.0" (at -0.95 5.169) (layer "F.Fab") hide
        (effects (font (size 0.7 0.7) (thickness 0.15)) (justify left bottom))
    )
    (fp_rect (start -0.93 -0.47) (end 0.93 0.47)
      (stroke (width 0.05) (type solid)) (fill none) (layer "F.CrtYd"))
    (fp_rect (start -0.5 -0.25) (end 0.5 0.25)
      (stroke (width 0.15) (type solid)) (fill none) (layer "F.Fab"))
    (pad "1" smd roundrect (at -0.485 0) (size 0.59 0.64) (layers "F.Cu" "F.Paste" "F.Mask") (roundrect_rratio 0.25)
      (net 691 "Net-(U52-FB)") (pintype "passive"))
    (pad "2" smd roundrect (at 0.485 0) (size 0.59 0.64) (layers "F.Cu" "F.Paste" "F.Mask") (roundrect_rratio 0.25)
      (net 1 "GND") (pintype "passive"))
  )

  (footprint "kria-k26-devboard-footprints:R_0402_1005Metric" (layer "F.Cu")
    (at 172.7 120.48 -90)
    (descr "Resistor SMD 0402")
    (tags "resistor SMD 0402")
    (property "Author" "Antmicro")
    (property "License" "Apache-2.0")
    (property "MPN" "CR0402-FX-4991GLF")
    (property "Manufacturer" "Bourns")
    (property "Sheetfile" "dc-dc-conventers.kicad_sch")
    (property "Sheetname" "DC/DC conventers")
    (property "Tolerance" "1%")
    (property "Val" "4k99")
    (property "ki_description" "4k99 resistor in 0402 package with 1% tolerance")
    (attr smd)
    (fp_text reference "R137" (at -0.43 -0.31) (layer "F.SilkS")
        (effects (font (size 0.7 0.7) (thickness 0.15)) (justify left bottom))
    )
    (fp_text value "R_4k99_0402" (at 0 1.4 -90) (layer "F.Fab") hide
        (effects (font (size 0.7 0.7) (thickness 0.15)) (justify left bottom))
    )
    (fp_text user "${REFERENCE}" (at -0.95 3.168 -90) (layer "F.Fab") hide
        (effects (font (size 0.7 0.7) (thickness 0.15)) (justify left bottom))
    )
    (fp_text user "Author: Antmicro" (at -0.95 4.169 -90) (layer "F.Fab") hide
        (effects (font (size 0.7 0.7) (thickness 0.15)) (justify left bottom))
    )
    (fp_text user "License: Apache-2.0" (at -0.95 5.169 -90) (layer "F.Fab") hide
        (effects (font (size 0.7 0.7) (thickness 0.15)) (justify left bottom))
    )
    (fp_rect (start -0.93 -0.47) (end 0.93 0.47)
      (stroke (width 0.05) (type solid)) (fill none) (layer "F.CrtYd"))
    (fp_rect (start -0.5 -0.25) (end 0.5 0.25)
      (stroke (width 0.15) (type solid)) (fill none) (layer "F.Fab"))
    (pad "1" smd roundrect (at -0.485 0 270) (size 0.59 0.64) (layers "F.Cu" "F.Paste" "F.Mask") (roundrect_rratio 0.25)
      (net 768 "/Power Supply/DC/DC conventers/PS_1V2_OUT") (pintype "passive"))
    (pad "2" smd roundrect (at 0.485 0 270) (size 0.59 0.64) (layers "F.Cu" "F.Paste" "F.Mask") (roundrect_rratio 0.25)
      (net 691 "Net-(U52-FB)") (pintype "passive"))
  )

  (footprint "kria-k26-devboard-footprints:C_0603_1608Metric" (layer "F.Cu")
    (at 167.185 117.455 -90)
    (descr "Capacitor SMD 0603")
    (tags "capacitor 0603")
    (property "Author" "Antmicro")
    (property "Dielectric" "")
    (property "License" "Apache-2.0")
    (property "MPN" "GRM188R60J226MEA0D")
    (property "Manufacturer" "Murata")
    (property "Sheetfile" "dc-dc-conventers.kicad_sch")
    (property "Sheetname" "DC/DC conventers")
    (property "Val" "22u")
    (property "Voltage" "")
    (property "ki_description" " ")
    (attr smd)
    (fp_text reference "C218" (at 2.75 1.93 -90) (layer "F.SilkS")
        (effects (font (size 0.7 0.7) (thickness 0.15)) (justify left bottom))
    )
    (fp_text value "C_22u_0603" (at 0 1.6 -90) (layer "F.Fab") hide
        (effects (font (size 0.7 0.7) (thickness 0.15)) (justify left bottom))
    )
    (fp_text user "Author: Antmicro" (at -1.682 4.894 -90) (layer "F.Fab") hide
        (effects (font (size 0.7 0.7) (thickness 0.15)) (justify left bottom))
    )
    (fp_text user "${REFERENCE}" (at -1.682 3.895 -90) (layer "F.Fab") hide
        (effects (font (size 0.7 0.7) (thickness 0.15)) (justify left bottom))
    )
    (fp_text user "License: Apache-2.0" (at -1.682 5.895 -90) (layer "F.Fab") hide
        (effects (font (size 0.7 0.7) (thickness 0.15)) (justify left bottom))
    )
    (fp_line (start -0.3 -0.3) (end 0.3 -0.3)
      (stroke (width 0.15) (type solid)) (layer "F.SilkS"))
    (fp_line (start -0.3 0.3) (end 0.3 0.3)
      (stroke (width 0.15) (type solid)) (layer "F.SilkS"))
    (fp_rect (start -1.24 -0.7) (end 1.24 0.7)
      (stroke (width 0.05) (type solid)) (fill none) (layer "F.CrtYd"))
    (fp_rect (start -0.8 -0.4) (end 0.8 0.4)
      (stroke (width 0.15) (type solid)) (fill none) (layer "F.Fab"))
    (pad "1" smd roundrect (at -0.7 0 270) (size 0.6 0.8) (layers "F.Cu" "F.Paste" "F.Mask") (roundrect_rratio 0.2)
      (net 768 "/Power Supply/DC/DC conventers/PS_1V2_OUT") (pintype "passive"))
    (pad "2" smd roundrect (at 0.7 0 270) (size 0.6 0.8) (layers "F.Cu" "F.Paste" "F.Mask") (roundrect_rratio 0.2)
      (net 1 "GND") (pintype "passive"))
  )

  (footprint "kria-k26-devboard-footprints:C_0603_1608Metric" (layer "F.Cu")
    (at 165.77 117.45 -90)
    (descr "Capacitor SMD 0603")
    (tags "capacitor 0603")
    (property "Author" "Antmicro")
    (property "Dielectric" "")
    (property "License" "Apache-2.0")
    (property "MPN" "GRM188R60J226MEA0D")
    (property "Manufacturer" "Murata")
    (property "Sheetfile" "dc-dc-conventers.kicad_sch")
    (property "Sheetname" "DC/DC conventers")
    (property "Val" "22u")
    (property "Voltage" "")
    (property "ki_description" " ")
    (attr smd)
    (fp_text reference "C214" (at 2.79 1.42 -90) (layer "F.SilkS")
        (effects (font (size 0.7 0.7) (thickness 0.15)) (justify left bottom))
    )
    (fp_text value "C_22u_0603" (at 0 1.6 -90) (layer "F.Fab") hide
        (effects (font (size 0.7 0.7) (thickness 0.15)) (justify left bottom))
    )
    (fp_text user "${REFERENCE}" (at -1.682 3.895 -90) (layer "F.Fab") hide
        (effects (font (size 0.7 0.7) (thickness 0.15)) (justify left bottom))
    )
    (fp_text user "License: Apache-2.0" (at -1.682 5.895 -90) (layer "F.Fab") hide
        (effects (font (size 0.7 0.7) (thickness 0.15)) (justify left bottom))
    )
    (fp_text user "Author: Antmicro" (at -1.682 4.894 -90) (layer "F.Fab") hide
        (effects (font (size 0.7 0.7) (thickness 0.15)) (justify left bottom))
    )
    (fp_line (start -0.3 -0.3) (end 0.3 -0.3)
      (stroke (width 0.15) (type solid)) (layer "F.SilkS"))
    (fp_line (start -0.3 0.3) (end 0.3 0.3)
      (stroke (width 0.15) (type solid)) (layer "F.SilkS"))
    (fp_rect (start -1.24 -0.7) (end 1.24 0.7)
      (stroke (width 0.05) (type solid)) (fill none) (layer "F.CrtYd"))
    (fp_rect (start -0.8 -0.4) (end 0.8 0.4)
      (stroke (width 0.15) (type solid)) (fill none) (layer "F.Fab"))
    (pad "1" smd roundrect (at -0.7 0 270) (size 0.6 0.8) (layers "F.Cu" "F.Paste" "F.Mask") (roundrect_rratio 0.2)
      (net 768 "/Power Supply/DC/DC conventers/PS_1V2_OUT") (pintype "passive"))
    (pad "2" smd roundrect (at 0.7 0 270) (size 0.6 0.8) (layers "F.Cu" "F.Paste" "F.Mask") (roundrect_rratio 0.2)
      (net 1 "GND") (pintype "passive"))
  )

  (footprint "kria-k26-devboard-footprints:C_0603_1608Metric" (layer "F.Cu")
    (at 167.25 120.3 90)
    (descr "Capacitor SMD 0603")
    (tags "capacitor 0603")
    (property "Author" "Antmicro")
    (property "Dielectric" "")
    (property "License" "Apache-2.0")
    (property "MPN" "C1608X5R1E106M080AC")
    (property "Manufacturer" "TDK")
    (property "Sheetfile" "dc-dc-conventers.kicad_sch")
    (property "Sheetname" "DC/DC conventers")
    (property "Val" "10u/25V")
    (property "Voltage" "")
    (property "ki_description" " ")
    (attr smd)
    (fp_text reference "C204" (at -1.47 -0.81 90) (layer "F.SilkS")
        (effects (font (size 0.7 0.7) (thickness 0.15)) (justify left bottom))
    )
    (fp_text value "C_10u_25V_0603" (at 0 1.6 90) (layer "F.Fab") hide
        (effects (font (size 0.7 0.7) (thickness 0.15)) (justify left bottom))
    )
    (fp_text user "Author: Antmicro" (at -1.682 4.894 90) (layer "F.Fab") hide
        (effects (font (size 0.7 0.7) (thickness 0.15)) (justify left bottom))
    )
    (fp_text user "License: Apache-2.0" (at -1.682 5.895 90) (layer "F.Fab") hide
        (effects (font (size 0.7 0.7) (thickness 0.15)) (justify left bottom))
    )
    (fp_text user "${REFERENCE}" (at -1.682 3.895 90) (layer "F.Fab") hide
        (effects (font (size 0.7 0.7) (thickness 0.15)) (justify left bottom))
    )
    (fp_line (start -0.3 -0.3) (end 0.3 -0.3)
      (stroke (width 0.15) (type solid)) (layer "F.SilkS"))
    (fp_line (start -0.3 0.3) (end 0.3 0.3)
      (stroke (width 0.15) (type solid)) (layer "F.SilkS"))
    (fp_rect (start -1.24 -0.7) (end 1.24 0.7)
      (stroke (width 0.05) (type solid)) (fill none) (layer "F.CrtYd"))
    (fp_rect (start -0.8 -0.4) (end 0.8 0.4)
      (stroke (width 0.15) (type solid)) (fill none) (layer "F.Fab"))
    (pad "1" smd roundrect (at -0.7 0 90) (size 0.6 0.8) (layers "F.Cu" "F.Paste" "F.Mask") (roundrect_rratio 0.2)
      (net 14 "/Power Supply/DC/DC conventers/DC_MAIN_BUS") (pintype "passive"))
    (pad "2" smd roundrect (at 0.7 0 90) (size 0.6 0.8) (layers "F.Cu" "F.Paste" "F.Mask") (roundrect_rratio 0.2)
      (net 1 "GND") (pintype "passive"))
  )

  (footprint "kria-k26-devboard-footprints:TSOT23-6" (layer "F.Cu")
    (at 170.1 120.15 -90)
    (property "Author" "Antmicro")
    (property "License" "Apache-2.0")
    (property "MPN" "AP62301WU-7")
    (property "Manufacturer" "Diodes Incorporated")
    (property "Sheetfile" "dc-dc-conventers.kicad_sch")
    (property "Sheetname" "DC/DC conventers")
    (property "ki_description" "DC-DC Switching Synchronous Buck Regulator, Adjustable, 4.2V-18Vin, 0.8V-7V/3A out, TSOT-26-6")
    (property "ki_keywords" "SMT, PMIC, IC, VOLTAGE")
    (attr smd)
    (fp_text reference "U52" (at 2.24 2.91 180) (layer "F.SilkS")
        (effects (font (size 0.7 0.7) (thickness 0.15)) (justify left bottom))
    )
    (fp_text value "AP62301_TSOT" (at -0.005 2.6 -90) (layer "F.Fab") hide
        (effects (font (size 0.7 0.7) (thickness 0.15)) (justify left bottom))
    )
    (fp_text user "Author: Antmicro" (at -1.893 7.368 -90) (layer "F.Fab") hide
        (effects (font (size 0.7 0.7) (thickness 0.15)) (justify left bottom))
    )
    (fp_text user "License: Apache-2.0" (at -1.893 4.967 -90) (layer "F.Fab") hide
        (effects (font (size 0.7 0.7) (thickness 0.15)) (justify left bottom))
    )
    (fp_text user "${REFERENCE}" (at -1.893 6.168 -90) (layer "F.Fab") hide
        (effects (font (size 0.7 0.7) (thickness 0.15)) (justify left bottom))
    )
    (fp_line (start -1.4805 0.725) (end -1.4795 -0.725)
      (stroke (width 0.15) (type solid)) (layer "F.SilkS"))
    (fp_line (start -1.4805 0.725) (end -1.3905 0.725)
      (stroke (width 0.15) (type solid)) (layer "F.SilkS"))
    (fp_line (start -1.4795 -0.725) (end -1.3905 -0.725)
      (stroke (width 0.15) (type solid)) (layer "F.SilkS"))
    (fp_line (start 1.479 0.73) (end 1.38 0.73)
      (stroke (width 0.15) (type solid)) (layer "F.SilkS"))
    (fp_line (start 1.48 -0.72) (end 1.38 -0.72)
      (stroke (width 0.15) (type solid)) (layer "F.SilkS"))
    (fp_line (start 1.48 -0.72) (end 1.479 0.73)
      (stroke (width 0.15) (type solid)) (layer "F.SilkS"))
    (fp_circle (center -1.499 1.236) (end -1.45 1.236)
      (stroke (width 0.15) (type solid)) (fill solid) (layer "F.SilkS"))
    (fp_rect (start -1.65 -1.61) (end 1.65 1.61)
      (stroke (width 0.05) (type solid)) (fill none) (layer "F.CrtYd"))
    (fp_line (start -1.527 -0.833) (end 1.523 -0.833)
      (stroke (width 0.15) (type solid)) (layer "F.Fab"))
    (fp_line (start -1.527 0.491) (end -1.527 -0.833)
      (stroke (width 0.15) (type solid)) (layer "F.Fab"))
    (fp_line (start -1.527 0.491) (end -1.102 0.916)
      (stroke (width 0.15) (type solid)) (layer "F.Fab"))
    (fp_line (start -1.102 0.916) (end 1.523 0.916)
      (stroke (width 0.15) (type solid)) (layer "F.Fab"))
    (fp_line (start 1.523 -0.833) (end 1.523 0.916)
      (stroke (width 0.15) (type solid)) (layer "F.Fab"))
    (pad "1" smd rect (at -0.952 1.18 270) (size 0.7 0.8) (layers "F.Cu" "F.Paste" "F.Mask")
      (net 1 "GND") (pinfunction "GND") (pintype "power_in"))
    (pad "2" smd rect (at -0.001 1.18 270) (size 0.7 0.8) (layers "F.Cu" "F.Paste" "F.Mask")
      (net 312 "/Power Supply/DC/DC conventers/SW_PS_1V2") (pinfunction "SW") (pintype "power_out"))
    (pad "3" smd rect (at 0.947 1.18 270) (size 0.7 0.8) (layers "F.Cu" "F.Paste" "F.Mask")
      (net 14 "/Power Supply/DC/DC conventers/DC_MAIN_BUS") (pinfunction "VIN") (pintype "power_in"))
    (pad "4" smd rect (at 0.947 -1.18 270) (size 0.7 0.8) (layers "F.Cu" "F.Paste" "F.Mask")
      (net 691 "Net-(U52-FB)") (pinfunction "FB") (pintype "input"))
    (pad "5" smd rect (at -0.001 -1.18 270) (size 0.7 0.8) (layers "F.Cu" "F.Paste" "F.Mask")
      (net 23 "/Power Supply/VCCOEN_PS_M2C") (pinfunction "EN") (pintype "input"))
    (pad "6" smd rect (at -0.952 -1.18 270) (size 0.7 0.8) (layers "F.Cu" "F.Paste" "F.Mask")
      (net 314 "Net-(U52-BST)") (pinfunction "BST") (pintype "output"))
  )

  (footprint "kria-k26-devboard-footprints:TSOT23-6" (layer "F.Cu")
    (at 179.699999 120.175 -90)
    (property "Author" "Antmicro")
    (property "License" "Apache-2.0")
    (property "MPN" "AP62301WU-7")
    (property "Manufacturer" "Diodes Incorporated")
    (property "Sheetfile" "dc-dc-conventers.kicad_sch")
    (property "Sheetname" "DC/DC conventers")
    (property "ki_description" "DC-DC Switching Synchronous Buck Regulator, Adjustable, 4.2V-18Vin, 0.8V-7V/3A out, TSOT-26-6")
    (property "ki_keywords" "SMT, PMIC, IC, VOLTAGE")
    (attr smd)
    (fp_text reference "U51" (at 3.755 -0.470001 90) (layer "F.SilkS")
        (effects (font (size 0.7 0.7) (thickness 0.15)) (justify left bottom))
    )
    (fp_text value "AP62301_TSOT" (at -0.005 2.6 -90) (layer "F.Fab") hide
        (effects (font (size 0.7 0.7) (thickness 0.15)) (justify left bottom))
    )
    (fp_text user "Author: Antmicro" (at -1.893 7.368 -90) (layer "F.Fab") hide
        (effects (font (size 0.7 0.7) (thickness 0.15)) (justify left bottom))
    )
    (fp_text user "License: Apache-2.0" (at -1.893 4.967 -90) (layer "F.Fab") hide
        (effects (font (size 0.7 0.7) (thickness 0.15)) (justify left bottom))
    )
    (fp_text user "${REFERENCE}" (at -1.893 6.168 -90) (layer "F.Fab") hide
        (effects (font (size 0.7 0.7) (thickness 0.15)) (justify left bottom))
    )
    (fp_line (start -1.4805 0.725) (end -1.4795 -0.725)
      (stroke (width 0.15) (type solid)) (layer "F.SilkS"))
    (fp_line (start -1.4805 0.725) (end -1.3905 0.725)
      (stroke (width 0.15) (type solid)) (layer "F.SilkS"))
    (fp_line (start -1.4795 -0.725) (end -1.3905 -0.725)
      (stroke (width 0.15) (type solid)) (layer "F.SilkS"))
    (fp_line (start 1.479 0.73) (end 1.38 0.73)
      (stroke (width 0.15) (type solid)) (layer "F.SilkS"))
    (fp_line (start 1.48 -0.72) (end 1.38 -0.72)
      (stroke (width 0.15) (type solid)) (layer "F.SilkS"))
    (fp_line (start 1.48 -0.72) (end 1.479 0.73)
      (stroke (width 0.15) (type solid)) (layer "F.SilkS"))
    (fp_circle (center -1.499 1.236) (end -1.45 1.236)
      (stroke (width 0.15) (type solid)) (fill solid) (layer "F.SilkS"))
    (fp_rect (start -1.65 -1.61) (end 1.65 1.61)
      (stroke (width 0.05) (type solid)) (fill none) (layer "F.CrtYd"))
    (fp_line (start -1.527 -0.833) (end 1.523 -0.833)
      (stroke (width 0.15) (type solid)) (layer "F.Fab"))
    (fp_line (start -1.527 0.491) (end -1.527 -0.833)
      (stroke (width 0.15) (type solid)) (layer "F.Fab"))
    (fp_line (start -1.527 0.491) (end -1.102 0.916)
      (stroke (width 0.15) (type solid)) (layer "F.Fab"))
    (fp_line (start -1.102 0.916) (end 1.523 0.916)
      (stroke (width 0.15) (type solid)) (layer "F.Fab"))
    (fp_line (start 1.523 -0.833) (end 1.523 0.916)
      (stroke (width 0.15) (type solid)) (layer "F.Fab"))
    (pad "1" smd rect (at -0.952 1.18 270) (size 0.7 0.8) (layers "F.Cu" "F.Paste" "F.Mask")
      (net 1 "GND") (pinfunction "GND") (pintype "power_in"))
    (pad "2" smd rect (at -0.001 1.18 270) (size 0.7 0.8) (layers "F.Cu" "F.Paste" "F.Mask")
      (net 311 "/Power Supply/DC/DC conventers/SW_PS_1V8") (pinfunction "SW") (pintype "power_out"))
    (pad "3" smd rect (at 0.947 1.18 270) (size 0.7 0.8) (layers "F.Cu" "F.Paste" "F.Mask")
      (net 14 "/Power Supply/DC/DC conventers/DC_MAIN_BUS") (pinfunction "VIN") (pintype "power_in"))
    (pad "4" smd rect (at 0.947 -1.18 270) (size 0.7 0.8) (layers "F.Cu" "F.Paste" "F.Mask")
      (net 690 "Net-(U51-FB)") (pinfunction "FB") (pintype "input"))
    (pad "5" smd rect (at -0.001 -1.18 270) (size 0.7 0.8) (layers "F.Cu" "F.Paste" "F.Mask")
      (net 23 "/Power Supply/VCCOEN_PS_M2C") (pinfunction "EN") (pintype "input"))
    (pad "6" smd rect (at -0.952 -1.18 270) (size 0.7 0.8) (layers "F.Cu" "F.Paste" "F.Mask")
      (net 276 "Net-(U51-BST)") (pinfunction "BST") (pintype "output"))
  )

  (footprint "kria-k26-devboard-footprints:R_0402_1005Metric" (layer "F.Cu")
    (at 178.5 115.875)
    (descr "Resistor SMD 0402")
    (tags "resistor SMD 0402")
    (property "Author" "Antmicro")
    (property "License" "Apache-2.0")
    (property "MPN" "CR0402-FX-1001GLF")
    (property "Manufacturer" "Bourns")
    (property "Sheetfile" "dc-dc-conventers.kicad_sch")
    (property "Sheetname" "DC/DC conventers")
    (property "Tolerance" "1%")
    (property "Val" "1k")
    (property "ki_description" "1k resistor in 0402 package with 1% tolerance")
    (attr smd)
    (fp_text reference "R129" (at 3.67 -0.575) (layer "F.SilkS")
        (effects (font (size 0.7 0.7) (thickness 0.15)) (justify left bottom))
    )
    (fp_text value "R_1k_0402" (at 0 1.4) (layer "F.Fab") hide
        (effects (font (size 0.7 0.7) (thickness 0.15)) (justify left bottom))
    )
    (fp_text user "${REFERENCE}" (at -0.95 3.168) (layer "F.Fab") hide
        (effects (font (size 0.7 0.7) (thickness 0.15)) (justify left bottom))
    )
    (fp_text user "License: Apache-2.0" (at -0.95 5.169) (layer "F.Fab") hide
        (effects (font (size 0.7 0.7) (thickness 0.15)) (justify left bottom))
    )
    (fp_text user "Author: Antmicro" (at -0.95 4.169) (layer "F.Fab") hide
        (effects (font (size 0.7 0.7) (thickness 0.15)) (justify left bottom))
    )
    (fp_rect (start -0.93 -0.47) (end 0.93 0.47)
      (stroke (width 0.05) (type solid)) (fill none) (layer "F.CrtYd"))
    (fp_rect (start -0.5 -0.25) (end 0.5 0.25)
      (stroke (width 0.15) (type solid)) (fill none) (layer "F.Fab"))
    (pad "1" smd roundrect (at -0.485 0) (size 0.59 0.64) (layers "F.Cu" "F.Paste" "F.Mask") (roundrect_rratio 0.25)
      (net 765 "/Power Supply/DC/DC conventers/PS_3V3_OUT") (pintype "passive"))
    (pad "2" smd roundrect (at 0.485 0) (size 0.59 0.64) (layers "F.Cu" "F.Paste" "F.Mask") (roundrect_rratio 0.25)
      (net 241 "Net-(D16-Pad1)") (pintype "passive"))
  )

  (footprint "kria-k26-devboard-footprints:R_0402_1005Metric" (layer "F.Cu")
    (at 181.2 122.55 180)
    (descr "Resistor SMD 0402")
    (tags "resistor SMD 0402")
    (property "Author" "Antmicro")
    (property "License" "Apache-2.0")
    (property "MPN" "CR0402-FX-1002GLF")
    (property "Manufacturer" "Bourns")
    (property "Sheetfile" "dc-dc-conventers.kicad_sch")
    (property "Sheetname" "DC/DC conventers")
    (property "Tolerance" "1%")
    (property "Val" "10k")
    (property "ki_description" "10k resistor in 0402 package with 1% tolerance")
    (attr smd)
    (fp_text reference "R136" (at -0.87 -3.28 270) (layer "F.SilkS")
        (effects (font (size 0.7 0.7) (thickness 0.15)) (justify left bottom))
    )
    (fp_text value "R_10k_0402" (at 0 1.4 180) (layer "F.Fab") hide
        (effects (font (size 0.7 0.7) (thickness 0.15)) (justify left bottom))
    )
    (fp_text user "License: Apache-2.0" (at -0.95 5.169 180) (layer "F.Fab") hide
        (effects (font (size 0.7 0.7) (thickness 0.15)) (justify left bottom))
    )
    (fp_text user "Author: Antmicro" (at -0.95 4.169 180) (layer "F.Fab") hide
        (effects (font (size 0.7 0.7) (thickness 0.15)) (justify left bottom))
    )
    (fp_text user "${REFERENCE}" (at -0.95 3.168 180) (layer "F.Fab") hide
        (effects (font (size 0.7 0.7) (thickness 0.15)) (justify left bottom))
    )
    (fp_rect (start -0.93 -0.47) (end 0.93 0.47)
      (stroke (width 0.05) (type solid)) (fill none) (layer "F.CrtYd"))
    (fp_rect (start -0.5 -0.25) (end 0.5 0.25)
      (stroke (width 0.15) (type solid)) (fill none) (layer "F.Fab"))
    (pad "1" smd roundrect (at -0.485 0 180) (size 0.59 0.64) (layers "F.Cu" "F.Paste" "F.Mask") (roundrect_rratio 0.25)
      (net 690 "Net-(U51-FB)") (pintype "passive"))
    (pad "2" smd roundrect (at 0.485 0 180) (size 0.59 0.64) (layers "F.Cu" "F.Paste" "F.Mask") (roundrect_rratio 0.25)
      (net 1 "GND") (pintype "passive"))
  )

  (footprint "kria-k26-devboard-footprints:R_0402_1005Metric" (layer "F.Cu")
    (at 182.6 121.375 -90)
    (descr "Resistor SMD 0402")
    (tags "resistor SMD 0402")
    (property "Author" "Antmicro")
    (property "License" "Apache-2.0")
    (property "MPN" "CR0402-FX-1242GLF")
    (property "Manufacturer" "Bourns")
    (property "Sheetfile" "dc-dc-conventers.kicad_sch")
    (property "Sheetname" "DC/DC conventers")
    (property "Tolerance" "1%")
    (property "Val" "12k4")
    (property "ki_description" "12k4 resistor in 0402 package with 1% tolerance")
    (attr smd)
    (fp_text reference "R135" (at 3.675 -0.46 -90) (layer "F.SilkS")
        (effects (font (size 0.7 0.7) (thickness 0.15)) (justify left bottom))
    )
    (fp_text value "R_12k4_0402" (at 0 1.4 -90) (layer "F.Fab") hide
        (effects (font (size 0.7 0.7) (thickness 0.15)) (justify left bottom))
    )
    (fp_text user "Author: Antmicro" (at -0.95 4.169 -90) (layer "F.Fab") hide
        (effects (font (size 0.7 0.7) (thickness 0.15)) (justify left bottom))
    )
    (fp_text user "${REFERENCE}" (at -0.95 3.168 -90) (layer "F.Fab") hide
        (effects (font (size 0.7 0.7) (thickness 0.15)) (justify left bottom))
    )
    (fp_text user "License: Apache-2.0" (at -0.95 5.169 -90) (layer "F.Fab") hide
        (effects (font (size 0.7 0.7) (thickness 0.15)) (justify left bottom))
    )
    (fp_rect (start -0.93 -0.47) (end 0.93 0.47)
      (stroke (width 0.05) (type solid)) (fill none) (layer "F.CrtYd"))
    (fp_rect (start -0.5 -0.25) (end 0.5 0.25)
      (stroke (width 0.15) (type solid)) (fill none) (layer "F.Fab"))
    (pad "1" smd roundrect (at -0.485 0 270) (size 0.59 0.64) (layers "F.Cu" "F.Paste" "F.Mask") (roundrect_rratio 0.25)
      (net 767 "/Power Supply/DC/DC conventers/PS_1V8_OUT") (pintype "passive"))
    (pad "2" smd roundrect (at 0.485 0 270) (size 0.59 0.64) (layers "F.Cu" "F.Paste" "F.Mask") (roundrect_rratio 0.25)
      (net 690 "Net-(U51-FB)") (pintype "passive"))
  )

  (footprint "kria-k26-devboard-footprints:LED_0603_1608Metric_G" (layer "F.Cu")
    (at 180.925 115.425)
    (descr "LED SMD 0603 Green")
    (tags "LED SMD 0603 Green")
    (property "Author" "Antmicro")
    (property "Color" "Green")
    (property "License" "Apache-2.0")
    (property "MPN" "LG L29K-G2J1-24-Z")
    (property "Manufacturer" "OSRAM")
    (property "Sheetfile" "dc-dc-conventers.kicad_sch")
    (property "Sheetname" "DC/DC conventers")
    (property "ki_description" "LED, Green, SMT, 0603, 20 mA, 2.1 V, 570 nm")
    (property "ki_keywords" "0603, SMT, DIODE, SEMICONDUCTOR, UNICOLOR")
    (attr smd)
    (fp_text reference "D16" (at 1.215 0.745) (layer "F.SilkS")
        (effects (font (size 0.7 0.7) (thickness 0.15)) (justify left bottom))
    )
    (fp_text value "LED_G_0603_LG_L29K-G2J1-24-Z" (at 0 1.6) (layer "F.Fab") hide
        (effects (font (size 0.7 0.7) (thickness 0.15)) (justify left bottom))
    )
    (fp_text user "${REFERENCE}" (at -1.31 3.769) (layer "F.Fab") hide
        (effects (font (size 0.7 0.7) (thickness 0.15)) (justify left bottom))
    )
    (fp_text user "License: Apache-2.0" (at -1.31 5.769) (layer "F.Fab") hide
        (effects (font (size 0.7 0.7) (thickness 0.15)) (justify left bottom))
    )
    (fp_text user "Author: Antmicro" (at -1.31 4.769) (layer "F.Fab") hide
        (effects (font (size 0.7 0.7) (thickness 0.15)) (justify left bottom))
    )
    (fp_line (start -0.27 -0.35) (end 0.27 -0.35)
      (stroke (width 0.15) (type solid)) (layer "F.SilkS"))
    (fp_line (start -0.27 0.351) (end 0.27 0.351)
      (stroke (width 0.15) (type solid)) (layer "F.SilkS"))
    (fp_line (start -0.106328 -0.200008) (end -0.106328 0.199992)
      (stroke (width 0.1) (type solid)) (layer "F.SilkS"))
    (fp_line (start -0.106328 -0.200008) (end 0.093672 -0.000008)
      (stroke (width 0.1) (type solid)) (layer "F.SilkS"))
    (fp_line (start -0.106328 -0.000008) (end -0.29 0)
      (stroke (width 0.1) (type solid)) (layer "F.SilkS"))
    (fp_line (start 0.093672 -0.200008) (end 0.093672 0.199992)
      (stroke (width 0.1) (type solid)) (layer "F.SilkS"))
    (fp_line (start 0.093672 -0.000008) (end -0.106328 0.199992)
      (stroke (width 0.1) (type solid)) (layer "F.SilkS"))
    (fp_line (start 0.093672 -0.000008) (end 0.293672 -0.000008)
      (stroke (width 0.1) (type solid)) (layer "F.SilkS"))
    (fp_line (start 1.25 0.32) (end 1.25 -0.32)
      (stroke (width 0.15) (type solid)) (layer "F.SilkS"))
    (fp_rect (start 1.26 0.65) (end -1.26 -0.65)
      (stroke (width 0.05) (type solid)) (fill none) (layer "F.CrtYd"))
    (fp_line (start -0.599 0) (end -0.201 0)
      (stroke (width 0.15) (type solid)) (layer "F.Fab"))
    (fp_line (start -0.201 -0.2) (end -0.201 0)
      (stroke (width 0.15) (type solid)) (layer "F.Fab"))
    (fp_line (start -0.201 0) (end -0.201 0.202)
      (stroke (width 0.15) (type solid)) (layer "F.Fab"))
    (fp_line (start -0.201 0.202) (end 0.101 0)
      (stroke (width 0.15) (type solid)) (layer "F.Fab"))
    (fp_line (start 0.101 0) (end -0.201 -0.2)
      (stroke (width 0.15) (type solid)) (layer "F.Fab"))
    (fp_line (start 0.199 -0.2) (end 0.199 -0.1)
      (stroke (width 0.15) (type solid)) (layer "F.Fab"))
    (fp_line (start 0.199 0) (end 0.597 0)
      (stroke (width 0.15) (type solid)) (layer "F.Fab"))
    (fp_line (start 0.199 0.202) (end 0.199 -0.1)
      (stroke (width 0.15) (type solid)) (layer "F.Fab"))
    (fp_rect (start -0.848 -0.4) (end 0.85 0.402)
      (stroke (width 0.15) (type solid)) (fill none) (layer "F.Fab"))
    (pad "1" smd rect (at -0.75 0 180) (size 0.8 0.8) (layers "F.Cu" "F.Paste" "F.Mask")
      (net 241 "Net-(D16-Pad1)") (pintype "passive"))
    (pad "2" smd rect (at 0.75 0 180) (size 0.8 0.8) (layers "F.Cu" "F.Paste" "F.Mask")
      (net 337 "Net-(Q18-C)") (pinfunction "2") (pintype "passive"))
  )

  (footprint "kria-k26-devboard-footprints:C_0603_1608Metric" (layer "F.Cu")
    (at 175.75 117.6 -90)
    (descr "Capacitor SMD 0603")
    (tags "capacitor 0603")
    (property "Author" "Antmicro")
    (property "Dielectric" "")
    (property "License" "Apache-2.0")
    (property "MPN" "GRM188R60J226MEA0D")
    (property "Manufacturer" "Murata")
    (property "Sheetfile" "dc-dc-conventers.kicad_sch")
    (property "Sheetname" "DC/DC conventers")
    (property "Val" "22u")
    (property "Voltage" "")
    (property "ki_description" " ")
    (attr smd)
    (fp_text reference "C217" (at -4.11 0.87 90) (layer "F.SilkS")
        (effects (font (size 0.7 0.7) (thickness 0.15)) (justify left bottom))
    )
    (fp_text value "C_22u_0603" (at 0 1.6 -90) (layer "F.Fab") hide
        (effects (font (size 0.7 0.7) (thickness 0.15)) (justify left bottom))
    )
    (fp_text user "Author: Antmicro" (at -1.682 4.894 -90) (layer "F.Fab") hide
        (effects (font (size 0.7 0.7) (thickness 0.15)) (justify left bottom))
    )
    (fp_text user "${REFERENCE}" (at -1.682 3.895 -90) (layer "F.Fab") hide
        (effects (font (size 0.7 0.7) (thickness 0.15)) (justify left bottom))
    )
    (fp_text user "License: Apache-2.0" (at -1.682 5.895 -90) (layer "F.Fab") hide
        (effects (font (size 0.7 0.7) (thickness 0.15)) (justify left bottom))
    )
    (fp_line (start -0.3 -0.3) (end 0.3 -0.3)
      (stroke (width 0.15) (type solid)) (layer "F.SilkS"))
    (fp_line (start -0.3 0.3) (end 0.3 0.3)
      (stroke (width 0.15) (type solid)) (layer "F.SilkS"))
    (fp_rect (start -1.24 -0.7) (end 1.24 0.7)
      (stroke (width 0.05) (type solid)) (fill none) (layer "F.CrtYd"))
    (fp_rect (start -0.8 -0.4) (end 0.8 0.4)
      (stroke (width 0.15) (type solid)) (fill none) (layer "F.Fab"))
    (pad "1" smd roundrect (at -0.7 0 270) (size 0.6 0.8) (layers "F.Cu" "F.Paste" "F.Mask") (roundrect_rratio 0.2)
      (net 767 "/Power Supply/DC/DC conventers/PS_1V8_OUT") (pintype "passive"))
    (pad "2" smd roundrect (at 0.7 0 270) (size 0.6 0.8) (layers "F.Cu" "F.Paste" "F.Mask") (roundrect_rratio 0.2)
      (net 1 "GND") (pintype "passive"))
  )

  (footprint "kria-k26-devboard-footprints:C_0603_1608Metric" (layer "F.Cu")
    (at 176.95 117.6 -90)
    (descr "Capacitor SMD 0603")
    (tags "capacitor 0603")
    (property "Author" "Antmicro")
    (property "Dielectric" "")
    (property "License" "Apache-2.0")
    (property "MPN" "GRM188R60J226MEA0D")
    (property "Manufacturer" "Murata")
    (property "Sheetfile" "dc-dc-conventers.kicad_sch")
    (property "Sheetname" "DC/DC conventers")
    (property "Val" "22u")
    (property "Voltage" "")
    (property "ki_description" " ")
    (attr smd)
    (fp_text reference "C213" (at -4.1 1.18 90) (layer "F.SilkS")
        (effects (font (size 0.7 0.7) (thickness 0.15)) (justify left bottom))
    )
    (fp_text value "C_22u_0603" (at 0 1.6 -90) (layer "F.Fab") hide
        (effects (font (size 0.7 0.7) (thickness 0.15)) (justify left bottom))
    )
    (fp_text user "Author: Antmicro" (at -1.682 4.894 -90) (layer "F.Fab") hide
        (effects (font (size 0.7 0.7) (thickness 0.15)) (justify left bottom))
    )
    (fp_text user "License: Apache-2.0" (at -1.682 5.895 -90) (layer "F.Fab") hide
        (effects (font (size 0.7 0.7) (thickness 0.15)) (justify left bottom))
    )
    (fp_text user "${REFERENCE}" (at -1.682 3.895 -90) (layer "F.Fab") hide
        (effects (font (size 0.7 0.7) (thickness 0.15)) (justify left bottom))
    )
    (fp_line (start -0.3 -0.3) (end 0.3 -0.3)
      (stroke (width 0.15) (type solid)) (layer "F.SilkS"))
    (fp_line (start -0.3 0.3) (end 0.3 0.3)
      (stroke (width 0.15) (type solid)) (layer "F.SilkS"))
    (fp_rect (start -1.24 -0.7) (end 1.24 0.7)
      (stroke (width 0.05) (type solid)) (fill none) (layer "F.CrtYd"))
    (fp_rect (start -0.8 -0.4) (end 0.8 0.4)
      (stroke (width 0.15) (type solid)) (fill none) (layer "F.Fab"))
    (pad "1" smd roundrect (at -0.7 0 270) (size 0.6 0.8) (layers "F.Cu" "F.Paste" "F.Mask") (roundrect_rratio 0.2)
      (net 767 "/Power Supply/DC/DC conventers/PS_1V8_OUT") (pintype "passive"))
    (pad "2" smd roundrect (at 0.7 0 270) (size 0.6 0.8) (layers "F.Cu" "F.Paste" "F.Mask") (roundrect_rratio 0.2)
      (net 1 "GND") (pintype "passive"))
  )

  (footprint "kria-k26-devboard-footprints:C_0402_1005Metric" (layer "F.Cu")
    (at 181.65 117.475 90)
    (descr "Capacitor SMD 0402")
    (tags "capacitor SMD 0402")
    (property "Author" "Antmicro")
    (property "Dielectric" "X5R")
    (property "License" "Apache-2.0")
    (property "MPN" "GRM155R61H104KE14D")
    (property "Manufacturer" "Murata")
    (property "Sheetfile" "dc-dc-conventers.kicad_sch")
    (property "Sheetname" "DC/DC conventers")
    (property "Val" "100n")
    (property "Voltage" "50V")
    (property "ki_description" " ")
    (attr smd)
    (fp_text reference "C208" (at -4.655 2.37 90) (layer "F.SilkS")
        (effects (font (size 0.7 0.7) (thickness 0.15)) (justify left bottom))
    )
    (fp_text value "C_100n_0402" (at 0 1.4 90) (layer "F.Fab") hide
        (effects (font (size 0.7 0.7) (thickness 0.15)) (justify left bottom))
    )
    (fp_text user "Author: Antmicro" (at -0.932 4.17 90) (layer "F.Fab") hide
        (effects (font (size 0.7 0.7) (thickness 0.15)) (justify left bottom))
    )
    (fp_text user "${REFERENCE}" (at -0.932 3.168 90) (layer "F.Fab") hide
        (effects (font (size 0.7 0.7) (thickness 0.15)) (justify left bottom))
    )
    (fp_text user "License: Apache-2.0" (at -0.932 5.17 90) (layer "F.Fab") hide
        (effects (font (size 0.7 0.7) (thickness 0.15)) (justify left bottom))
    )
    (fp_rect (start -0.94 -0.47) (end 0.94 0.47)
      (stroke (width 0.05) (type solid)) (fill none) (layer "F.CrtYd"))
    (fp_rect (start -0.499 -0.249) (end 0.499 0.249)
      (stroke (width 0.15) (type solid)) (fill none) (layer "F.Fab"))
    (pad "1" smd roundrect (at -0.484 0 90) (size 0.59 0.64) (layers "F.Cu" "F.Paste" "F.Mask") (roundrect_rratio 0.25)
      (net 276 "Net-(U51-BST)") (pintype "passive"))
    (pad "2" smd roundrect (at 0.484 0 90) (size 0.59 0.64) (layers "F.Cu" "F.Paste" "F.Mask") (roundrect_rratio 0.25)
      (net 311 "/Power Supply/DC/DC conventers/SW_PS_1V8") (pintype "passive"))
  )

  (footprint "kria-k26-devboard-footprints:C_0603_1608Metric" (layer "F.Cu")
    (at 177 120.275 90)
    (descr "Capacitor SMD 0603")
    (tags "capacitor 0603")
    (property "Author" "Antmicro")
    (property "Dielectric" "")
    (property "License" "Apache-2.0")
    (property "MPN" "C1608X5R1E106M080AC")
    (property "Manufacturer" "TDK")
    (property "Sheetfile" "dc-dc-conventers.kicad_sch")
    (property "Sheetname" "DC/DC conventers")
    (property "Val" "10u/25V")
    (property "Voltage" "")
    (property "ki_description" " ")
    (attr smd)
    (fp_text reference "C203" (at -3.975 1.82 90) (layer "F.SilkS")
        (effects (font (size 0.7 0.7) (thickness 0.15)) (justify left bottom))
    )
    (fp_text value "C_10u_25V_0603" (at 0 1.6 90) (layer "F.Fab") hide
        (effects (font (size 0.7 0.7) (thickness 0.15)) (justify left bottom))
    )
    (fp_text user "License: Apache-2.0" (at -1.682 5.895 90) (layer "F.Fab") hide
        (effects (font (size 0.7 0.7) (thickness 0.15)) (justify left bottom))
    )
    (fp_text user "${REFERENCE}" (at -1.682 3.895 90) (layer "F.Fab") hide
        (effects (font (size 0.7 0.7) (thickness 0.15)) (justify left bottom))
    )
    (fp_text user "Author: Antmicro" (at -1.682 4.894 90) (layer "F.Fab") hide
        (effects (font (size 0.7 0.7) (thickness 0.15)) (justify left bottom))
    )
    (fp_line (start -0.3 -0.3) (end 0.3 -0.3)
      (stroke (width 0.15) (type solid)) (layer "F.SilkS"))
    (fp_line (start -0.3 0.3) (end 0.3 0.3)
      (stroke (width 0.15) (type solid)) (layer "F.SilkS"))
    (fp_rect (start -1.24 -0.7) (end 1.24 0.7)
      (stroke (width 0.05) (type solid)) (fill none) (layer "F.CrtYd"))
    (fp_rect (start -0.8 -0.4) (end 0.8 0.4)
      (stroke (width 0.15) (type solid)) (fill none) (layer "F.Fab"))
    (pad "1" smd roundrect (at -0.7 0 90) (size 0.6 0.8) (layers "F.Cu" "F.Paste" "F.Mask") (roundrect_rratio 0.2)
      (net 14 "/Power Supply/DC/DC conventers/DC_MAIN_BUS") (pintype "passive"))
    (pad "2" smd roundrect (at 0.7 0 90) (size 0.6 0.8) (layers "F.Cu" "F.Paste" "F.Mask") (roundrect_rratio 0.2)
      (net 1 "GND") (pintype "passive"))
  )

  (footprint "kria-k26-devboard-footprints:L_0806_2016Metric" (layer "F.Cu")
    (at 179.41 117.41 180)
    (property "Author" "Antmicro")
    (property "IMax" "")
    (property "ISat" "")
    (property "License" "Apache-2.0")
    (property "MPN" "SRP2010-1R0M")
    (property "Manufacturer" "Bourns")
    (property "Sheetfile" "dc-dc-conventers.kicad_sch")
    (property "Sheetname" "DC/DC conventers")
    (property "Size" "2.0x1.6")
    (property "Val" "1u/2.6A")
    (attr smd)
    (fp_text reference "L5" (at -2.75 -3.52 270) (layer "F.SilkS")
        (effects (font (size 0.7 0.7) (thickness 0.15)) (justify left bottom))
    )
    (fp_text value "L_1u_2.6A_0806" (at 0 2 180) (layer "F.Fab") hide
        (effects (font (size 0.7 0.7) (thickness 0.15)) (justify left bottom))
    )
    (fp_text user "${REFERENCE}" (at -1.9 3.1 180) (layer "F.Fab") hide
        (effects (font (size 0.7 0.7) (thickness 0.15)) (justify left bottom))
    )
    (fp_text user "License: Apache-2.0" (at -1.9 5.75 180) (layer "F.Fab") hide
        (effects (font (size 0.7 0.7) (thickness 0.15)) (justify left bottom))
    )
    (fp_text user "Author: Antmicro" (at -1.9 4.4 180) (layer "F.Fab") hide
        (effects (font (size 0.7 0.7) (thickness 0.15)) (justify left bottom))
    )
    (fp_line (start -0.301 0.9) (end 0.299 0.9)
      (stroke (width 0.15) (type solid)) (layer "F.SilkS"))
    (fp_line (start -0.3 -0.9) (end 0.298 -0.9)
      (stroke (width 0.15) (type solid)) (layer "F.SilkS"))
    (fp_rect (start -1.75 -1.05) (end 1.75 1.05)
      (stroke (width 0.05) (type solid)) (fill none) (layer "F.CrtYd"))
    (fp_rect (start -0.951 -0.882) (end 0.949 0.875)
      (stroke (width 0.15) (type solid)) (fill none) (layer "F.Fab"))
    (pad "1" smd roundrect (at -1.1 -0.001 180) (size 1 1.8) (layers "F.Cu" "F.Paste" "F.Mask") (roundrect_rratio 0.15)
      (net 311 "/Power Supply/DC/DC conventers/SW_PS_1V8") (pintype "passive"))
    (pad "2" smd roundrect (at 1.1 -0.001 180) (size 1 1.8) (layers "F.Cu" "F.Paste" "F.Mask") (roundrect_rratio 0.15)
      (net 767 "/Power Supply/DC/DC conventers/PS_1V8_OUT") (pintype "passive"))
  )

  (footprint "kria-k26-devboard-footprints:C_0402_1005Metric" (layer "F.Cu")
    (at 171.87 117.3 90)
    (descr "Capacitor SMD 0402")
    (tags "capacitor SMD 0402")
    (property "Author" "Antmicro")
    (property "Dielectric" "X5R")
    (property "License" "Apache-2.0")
    (property "MPN" "GRM155R61H104KE14D")
    (property "Manufacturer" "Murata")
    (property "Sheetfile" "dc-dc-conventers.kicad_sch")
    (property "Sheetname" "DC/DC conventers")
    (property "Val" "100n")
    (property "Voltage" "50V")
    (property "ki_description" " ")
    (attr smd)
    (fp_text reference "C209" (at -1.05 0.37 180) (layer "F.SilkS")
        (effects (font (size 0.7 0.7) (thickness 0.15)) (justify left bottom))
    )
    (fp_text value "C_100n_0402" (at 0 1.4 90) (layer "F.Fab") hide
        (effects (font (size 0.7 0.7) (thickness 0.15)) (justify left bottom))
    )
    (fp_text user "${REFERENCE}" (at -0.932 3.168 90) (layer "F.Fab") hide
        (effects (font (size 0.7 0.7) (thickness 0.15)) (justify left bottom))
    )
    (fp_text user "Author: Antmicro" (at -0.932 4.17 90) (layer "F.Fab") hide
        (effects (font (size 0.7 0.7) (thickness 0.15)) (justify left bottom))
    )
    (fp_text user "License: Apache-2.0" (at -0.932 5.17 90) (layer "F.Fab") hide
        (effects (font (size 0.7 0.7) (thickness 0.15)) (justify left bottom))
    )
    (fp_rect (start -0.94 -0.47) (end 0.94 0.47)
      (stroke (width 0.05) (type solid)) (fill none) (layer "F.CrtYd"))
    (fp_rect (start -0.499 -0.249) (end 0.499 0.249)
      (stroke (width 0.15) (type solid)) (fill none) (layer "F.Fab"))
    (pad "1" smd roundrect (at -0.484 0 90) (size 0.59 0.64) (layers "F.Cu" "F.Paste" "F.Mask") (roundrect_rratio 0.25)
      (net 314 "Net-(U52-BST)") (pintype "passive"))
    (pad "2" smd roundrect (at 0.484 0 90) (size 0.59 0.64) (layers "F.Cu" "F.Paste" "F.Mask") (roundrect_rratio 0.25)
      (net 312 "/Power Supply/DC/DC conventers/SW_PS_1V2") (pintype "passive"))
  )

  (footprint "kria-k26-devboard-footprints:R_0402_1005Metric" (layer "F.Cu")
    (at 168.5 131.25)
    (descr "Resistor SMD 0402")
    (tags "resistor SMD 0402")
    (property "Author" "Antmicro")
    (property "License" "Apache-2.0")
    (property "MPN" "CR0402-FX-1001GLF")
    (property "Manufacturer" "Bourns")
    (property "Sheetfile" "dc-dc-conventers.kicad_sch")
    (property "Sheetname" "DC/DC conventers")
    (property "Tolerance" "1%")
    (property "Val" "1k")
    (property "ki_description" "1k resistor in 0402 package with 1% tolerance")
    (attr smd)
    (fp_text reference "R126" (at -3.68 0.38) (layer "F.SilkS")
        (effects (font (size 0.7 0.7) (thickness 0.15)) (justify left bottom))
    )
    (fp_text value "R_1k_0402" (at 0 1.4) (layer "F.Fab") hide
        (effects (font (size 0.7 0.7) (thickness 0.15)) (justify left bottom))
    )
    (fp_text user "Author: Antmicro" (at -0.95 4.169) (layer "F.Fab") hide
        (effects (font (size 0.7 0.7) (thickness 0.15)) (justify left bottom))
    )
    (fp_text user "License: Apache-2.0" (at -0.95 5.169) (layer "F.Fab") hide
        (effects (font (size 0.7 0.7) (thickness 0.15)) (justify left bottom))
    )
    (fp_text user "${REFERENCE}" (at -0.95 3.168) (layer "F.Fab") hide
        (effects (font (size 0.7 0.7) (thickness 0.15)) (justify left bottom))
    )
    (fp_rect (start -0.93 -0.47) (end 0.93 0.47)
      (stroke (width 0.05) (type solid)) (fill none) (layer "F.CrtYd"))
    (fp_rect (start -0.5 -0.25) (end 0.5 0.25)
      (stroke (width 0.15) (type solid)) (fill none) (layer "F.Fab"))
    (pad "1" smd roundrect (at -0.485 0) (size 0.59 0.64) (layers "F.Cu" "F.Paste" "F.Mask") (roundrect_rratio 0.25)
      (net 765 "/Power Supply/DC/DC conventers/PS_3V3_OUT") (pintype "passive"))
    (pad "2" smd roundrect (at 0.485 0) (size 0.59 0.64) (layers "F.Cu" "F.Paste" "F.Mask") (roundrect_rratio 0.25)
      (net 239 "Net-(D14-Pad1)") (pintype "passive"))
  )

  (footprint "kria-k26-devboard-footprints:TSOT23-6" (layer "F.Cu")
    (at 178 133 90)
    (property "Author" "Antmicro")
    (property "License" "Apache-2.0")
    (property "MPN" "AP62301WU-7")
    (property "Manufacturer" "Diodes Incorporated")
    (property "Sheetfile" "dc-dc-conventers.kicad_sch")
    (property "Sheetname" "DC/DC conventers")
    (property "ki_description" "DC-DC Switching Synchronous Buck Regulator, Adjustable, 4.2V-18Vin, 0.8V-7V/3A out, TSOT-26-6")
    (property "ki_keywords" "SMT, PMIC, IC, VOLTAGE")
    (attr smd)
    (fp_text reference "U54" (at -1.84 -1.67 270) (layer "F.SilkS")
        (effects (font (size 0.7 0.7) (thickness 0.15)) (justify left bottom))
    )
    (fp_text value "AP62301_TSOT" (at -0.005 2.6 90) (layer "F.Fab") hide
        (effects (font (size 0.7 0.7) (thickness 0.15)) (justify left bottom))
    )
    (fp_text user "${REFERENCE}" (at -1.893 6.168 90) (layer "F.Fab") hide
        (effects (font (size 0.7 0.7) (thickness 0.15)) (justify left bottom))
    )
    (fp_text user "License: Apache-2.0" (at -1.893 4.967 90) (layer "F.Fab") hide
        (effects (font (size 0.7 0.7) (thickness 0.15)) (justify left bottom))
    )
    (fp_text user "Author: Antmicro" (at -1.893 7.368 90) (layer "F.Fab") hide
        (effects (font (size 0.7 0.7) (thickness 0.15)) (justify left bottom))
    )
    (fp_line (start -1.4805 0.725) (end -1.4795 -0.725)
      (stroke (width 0.15) (type solid)) (layer "F.SilkS"))
    (fp_line (start -1.4805 0.725) (end -1.3905 0.725)
      (stroke (width 0.15) (type solid)) (layer "F.SilkS"))
    (fp_line (start -1.4795 -0.725) (end -1.3905 -0.725)
      (stroke (width 0.15) (type solid)) (layer "F.SilkS"))
    (fp_line (start 1.479 0.73) (end 1.38 0.73)
      (stroke (width 0.15) (type solid)) (layer "F.SilkS"))
    (fp_line (start 1.48 -0.72) (end 1.38 -0.72)
      (stroke (width 0.15) (type solid)) (layer "F.SilkS"))
    (fp_line (start 1.48 -0.72) (end 1.479 0.73)
      (stroke (width 0.15) (type solid)) (layer "F.SilkS"))
    (fp_circle (center -1.499 1.236) (end -1.45 1.236)
      (stroke (width 0.15) (type solid)) (fill solid) (layer "F.SilkS"))
    (fp_rect (start -1.65 -1.61) (end 1.65 1.61)
      (stroke (width 0.05) (type solid)) (fill none) (layer "F.CrtYd"))
    (fp_line (start -1.527 -0.833) (end 1.523 -0.833)
      (stroke (width 0.15) (type solid)) (layer "F.Fab"))
    (fp_line (start -1.527 0.491) (end -1.527 -0.833)
      (stroke (width 0.15) (type solid)) (layer "F.Fab"))
    (fp_line (start -1.527 0.491) (end -1.102 0.916)
      (stroke (width 0.15) (type solid)) (layer "F.Fab"))
    (fp_line (start -1.102 0.916) (end 1.523 0.916)
      (stroke (width 0.15) (type solid)) (layer "F.Fab"))
    (fp_line (start 1.523 -0.833) (end 1.523 0.916)
      (stroke (width 0.15) (type solid)) (layer "F.Fab"))
    (pad "1" smd rect (at -0.952 1.18 90) (size 0.7 0.8) (layers "F.Cu" "F.Paste" "F.Mask")
      (net 1 "GND") (pinfunction "GND") (pintype "power_in"))
    (pad "2" smd rect (at -0.001 1.18 90) (size 0.7 0.8) (layers "F.Cu" "F.Paste" "F.Mask")
      (net 315 "/Power Supply/DC/DC conventers/SW_PL_3V3") (pinfunction "SW") (pintype "power_out"))
    (pad "3" smd rect (at 0.947 1.18 90) (size 0.7 0.8) (layers "F.Cu" "F.Paste" "F.Mask")
      (net 14 "/Power Supply/DC/DC conventers/DC_MAIN_BUS") (pinfunction "VIN") (pintype "power_in"))
    (pad "4" smd rect (at 0.947 -1.18 90) (size 0.7 0.8) (layers "F.Cu" "F.Paste" "F.Mask")
      (net 693 "Net-(U54-FB)") (pinfunction "FB") (pintype "input"))
    (pad "5" smd rect (at -0.001 -1.18 90) (size 0.7 0.8) (layers "F.Cu" "F.Paste" "F.Mask")
      (net 24 "/Power Supply/VCCOEN_PL_M2C") (pinfunction "EN") (pintype "input"))
    (pad "6" smd rect (at -0.952 -1.18 90) (size 0.7 0.8) (layers "F.Cu" "F.Paste" "F.Mask")
      (net 325 "Net-(U54-BST)") (pinfunction "BST") (pintype "output"))
  )

  (footprint "kria-k26-devboard-footprints:C_0402_1005Metric" (layer "F.Cu")
    (at 148.3 93.83 -90)
    (descr "Capacitor SMD 0402")
    (tags "capacitor SMD 0402")
    (property "Author" "Antmicro")
    (property "Dielectric" "X5R")
    (property "License" "Apache-2.0")
    (property "MPN" "GRM155R61H104KE14D")
    (property "Manufacturer" "Murata")
    (property "Sheetfile" "eth.kicad_sch")
    (property "Sheetname" "Ethernet")
    (property "Val" "100n")
    (property "Voltage" "50V")
    (property "ki_description" " ")
    (attr smd)
    (fp_text reference "C100" (at 3.69 -0.41 -90) (layer "F.SilkS")
        (effects (font (size 0.7 0.7) (thickness 0.15)) (justify left bottom))
    )
    (fp_text value "C_100n_0402" (at 0 1.4 -90) (layer "F.Fab") hide
        (effects (font (size 0.7 0.7) (thickness 0.15)) (justify left bottom))
    )
    (fp_text user "License: Apache-2.0" (at -0.932 5.17 -90) (layer "F.Fab") hide
        (effects (font (size 0.7 0.7) (thickness 0.15)) (justify left bottom))
    )
    (fp_text user "${REFERENCE}" (at -0.932 3.168 -90) (layer "F.Fab") hide
        (effects (font (size 0.7 0.7) (thickness 0.15)) (justify left bottom))
    )
    (fp_text user "Author: Antmicro" (at -0.932 4.17 -90) (layer "F.Fab") hide
        (effects (font (size 0.7 0.7) (thickness 0.15)) (justify left bottom))
    )
    (fp_rect (start -0.94 -0.47) (end 0.94 0.47)
      (stroke (width 0.05) (type solid)) (fill none) (layer "F.CrtYd"))
    (fp_rect (start -0.499 -0.249) (end 0.499 0.249)
      (stroke (width 0.15) (type solid)) (fill none) (layer "F.Fab"))
    (pad "1" smd roundrect (at -0.484 0 270) (size 0.59 0.64) (layers "F.Cu" "F.Paste" "F.Mask") (roundrect_rratio 0.25)
      (net 17 "PS_1V8") (pintype "passive"))
    (pad "2" smd roundrect (at 0.484 0 270) (size 0.59 0.64) (layers "F.Cu" "F.Paste" "F.Mask") (roundrect_rratio 0.25)
      (net 1 "GND") (pintype "passive"))
  )

  (footprint "kria-k26-devboard-footprints:R_0402_1005Metric" (layer "F.Cu")
    (at 147.925 73.9 90)
    (descr "Resistor SMD 0402")
    (tags "resistor SMD 0402")
    (property "Author" "Antmicro")
    (property "License" "Apache-2.0")
    (property "MPN" "CR0402-FX-1003GLF")
    (property "Manufacturer" "Bourns")
    (property "Sheetfile" "dc-dc-conventers.kicad_sch")
    (property "Sheetname" "DC/DC conventers")
    (property "Tolerance" "1%")
    (property "Val" "100k")
    (property "ki_description" "100k resistor in 0402 package with 1% tolerance")
    (attr smd)
    (fp_text reference "R118" (at -1.27 -0.635 90) (layer "F.SilkS")
        (effects (font (size 0.7 0.7) (thickness 0.15)) (justify left bottom))
    )
    (fp_text value "R_100k_0402" (at 0 1.4 90) (layer "F.Fab") hide
        (effects (font (size 0.7 0.7) (thickness 0.15)) (justify left bottom))
    )
    (fp_text user "${REFERENCE}" (at -0.95 3.168 90) (layer "F.Fab") hide
        (effects (font (size 0.7 0.7) (thickness 0.15)) (justify left bottom))
    )
    (fp_text user "License: Apache-2.0" (at -0.95 5.169 90) (layer "F.Fab") hide
        (effects (font (size 0.7 0.7) (thickness 0.15)) (justify left bottom))
    )
    (fp_text user "Author: Antmicro" (at -0.95 4.169 90) (layer "F.Fab") hide
        (effects (font (size 0.7 0.7) (thickness 0.15)) (justify left bottom))
    )
    (fp_rect (start -0.93 -0.47) (end 0.93 0.47)
      (stroke (width 0.05) (type solid)) (fill none) (layer "F.CrtYd"))
    (fp_rect (start -0.5 -0.25) (end 0.5 0.25)
      (stroke (width 0.15) (type solid)) (fill none) (layer "F.Fab"))
    (pad "1" smd roundrect (at -0.485 0 90) (size 0.59 0.64) (layers "F.Cu" "F.Paste" "F.Mask") (roundrect_rratio 0.25)
      (net 685 "Net-(U47-EN)") (pintype "passive"))
    (pad "2" smd roundrect (at 0.485 0 90) (size 0.59 0.64) (layers "F.Cu" "F.Paste" "F.Mask") (roundrect_rratio 0.25)
      (net 14 "/Power Supply/DC/DC conventers/DC_MAIN_BUS") (pintype "passive"))
  )

  (footprint "kria-k26-devboard-footprints:LED_0603_1608Metric_G" (layer "F.Cu")
    (at 150.575 76.9)
    (descr "LED SMD 0603 Green")
    (tags "LED SMD 0603 Green")
    (property "Author" "Antmicro")
    (property "Color" "Green")
    (property "License" "Apache-2.0")
    (property "MPN" "LG L29K-G2J1-24-Z")
    (property "Manufacturer" "OSRAM")
    (property "Sheetfile" "dc-dc-conventers.kicad_sch")
    (property "Sheetname" "DC/DC conventers")
    (property "ki_description" "LED, Green, SMT, 0603, 20 mA, 2.1 V, 570 nm")
    (property "ki_keywords" "0603, SMT, DIODE, SEMICONDUCTOR, UNICOLOR")
    (attr smd)
    (fp_text reference "D13" (at -0.995 1.53) (layer "F.SilkS")
        (effects (font (size 0.7 0.7) (thickness 0.15)) (justify left bottom))
    )
    (fp_text value "LED_G_0603_LG_L29K-G2J1-24-Z" (at 0 1.6) (layer "F.Fab") hide
        (effects (font (size 0.7 0.7) (thickness 0.15)) (justify left bottom))
    )
    (fp_text user "Author: Antmicro" (at -1.31 4.769) (layer "F.Fab") hide
        (effects (font (size 0.7 0.7) (thickness 0.15)) (justify left bottom))
    )
    (fp_text user "${REFERENCE}" (at -1.31 3.769) (layer "F.Fab") hide
        (effects (font (size 0.7 0.7) (thickness 0.15)) (justify left bottom))
    )
    (fp_text user "License: Apache-2.0" (at -1.31 5.769) (layer "F.Fab") hide
        (effects (font (size 0.7 0.7) (thickness 0.15)) (justify left bottom))
    )
    (fp_line (start -0.27 -0.35) (end 0.27 -0.35)
      (stroke (width 0.15) (type solid)) (layer "F.SilkS"))
    (fp_line (start -0.27 0.351) (end 0.27 0.351)
      (stroke (width 0.15) (type solid)) (layer "F.SilkS"))
    (fp_line (start -0.106328 -0.200008) (end -0.106328 0.199992)
      (stroke (width 0.1) (type solid)) (layer "F.SilkS"))
    (fp_line (start -0.106328 -0.200008) (end 0.093672 -0.000008)
      (stroke (width 0.1) (type solid)) (layer "F.SilkS"))
    (fp_line (start -0.106328 -0.000008) (end -0.29 0)
      (stroke (width 0.1) (type solid)) (layer "F.SilkS"))
    (fp_line (start 0.093672 -0.200008) (end 0.093672 0.199992)
      (stroke (width 0.1) (type solid)) (layer "F.SilkS"))
    (fp_line (start 0.093672 -0.000008) (end -0.106328 0.199992)
      (stroke (width 0.1) (type solid)) (layer "F.SilkS"))
    (fp_line (start 0.093672 -0.000008) (end 0.293672 -0.000008)
      (stroke (width 0.1) (type solid)) (layer "F.SilkS"))
    (fp_line (start 1.25 0.32) (end 1.25 -0.32)
      (stroke (width 0.15) (type solid)) (layer "F.SilkS"))
    (fp_rect (start 1.26 0.65) (end -1.26 -0.65)
      (stroke (width 0.05) (type solid)) (fill none) (layer "F.CrtYd"))
    (fp_line (start -0.599 0) (end -0.201 0)
      (stroke (width 0.15) (type solid)) (layer "F.Fab"))
    (fp_line (start -0.201 -0.2) (end -0.201 0)
      (stroke (width 0.15) (type solid)) (layer "F.Fab"))
    (fp_line (start -0.201 0) (end -0.201 0.202)
      (stroke (width 0.15) (type solid)) (layer "F.Fab"))
    (fp_line (start -0.201 0.202) (end 0.101 0)
      (stroke (width 0.15) (type solid)) (layer "F.Fab"))
    (fp_line (start 0.101 0) (end -0.201 -0.2)
      (stroke (width 0.15) (type solid)) (layer "F.Fab"))
    (fp_line (start 0.199 -0.2) (end 0.199 -0.1)
      (stroke (width 0.15) (type solid)) (layer "F.Fab"))
    (fp_line (start 0.199 0) (end 0.597 0)
      (stroke (width 0.15) (type solid)) (layer "F.Fab"))
    (fp_line (start 0.199 0.202) (end 0.199 -0.1)
      (stroke (width 0.15) (type solid)) (layer "F.Fab"))
    (fp_rect (start -0.848 -0.4) (end 0.85 0.402)
      (stroke (width 0.15) (type solid)) (fill none) (layer "F.Fab"))
    (pad "1" smd rect (at -0.75 0 180) (size 0.8 0.8) (layers "F.Cu" "F.Paste" "F.Mask")
      (net 330 "Net-(D13-Pad1)") (pintype "passive"))
    (pad "2" smd rect (at 0.75 0 180) (size 0.8 0.8) (layers "F.Cu" "F.Paste" "F.Mask")
      (net 1 "GND") (pinfunction "2") (pintype "passive"))
  )

  (footprint "kria-k26-devboard-footprints:R_0402_1005Metric" (layer "F.Cu")
    (at 148.625 77.35 -90)
    (descr "Resistor SMD 0402")
    (tags "resistor SMD 0402")
    (property "Author" "Antmicro")
    (property "License" "Apache-2.0")
    (property "MPN" "CR0402-FX-2201GLF")
    (property "Manufacturer" "Bourns")
    (property "Sheetfile" "dc-dc-conventers.kicad_sch")
    (property "Sheetname" "DC/DC conventers")
    (property "Tolerance" "1%")
    (property "Val" "2k2")
    (property "ki_description" "2k2 resistor in 0402 package with 1% tolerance")
    (attr smd)
    (fp_text reference "R121" (at 1.31 0.615 -90) (layer "F.SilkS")
        (effects (font (size 0.7 0.7) (thickness 0.15)) (justify left bottom))
    )
    (fp_text value "R_2k2_0402" (at 0 1.4 -90) (layer "F.Fab") hide
        (effects (font (size 0.7 0.7) (thickness 0.15)) (justify left bottom))
    )
    (fp_text user "${REFERENCE}" (at -0.95 3.168 -90) (layer "F.Fab") hide
        (effects (font (size 0.7 0.7) (thickness 0.15)) (justify left bottom))
    )
    (fp_text user "Author: Antmicro" (at -0.95 4.169 -90) (layer "F.Fab") hide
        (effects (font (size 0.7 0.7) (thickness 0.15)) (justify left bottom))
    )
    (fp_text user "License: Apache-2.0" (at -0.95 5.169 -90) (layer "F.Fab") hide
        (effects (font (size 0.7 0.7) (thickness 0.15)) (justify left bottom))
    )
    (fp_rect (start -0.93 -0.47) (end 0.93 0.47)
      (stroke (width 0.05) (type solid)) (fill none) (layer "F.CrtYd"))
    (fp_rect (start -0.5 -0.25) (end 0.5 0.25)
      (stroke (width 0.15) (type solid)) (fill none) (layer "F.Fab"))
    (pad "1" smd roundrect (at -0.485 0 270) (size 0.59 0.64) (layers "F.Cu" "F.Paste" "F.Mask") (roundrect_rratio 0.25)
      (net 330 "Net-(D13-Pad1)") (pintype "passive"))
    (pad "2" smd roundrect (at 0.485 0 270) (size 0.59 0.64) (layers "F.Cu" "F.Paste" "F.Mask") (roundrect_rratio 0.25)
      (net 772 "/Power Supply/DC/DC conventers/USB_5V_OUT") (pintype "passive"))
  )

  (footprint "kria-k26-devboard-footprints:Spacer_Drill4.45mm_H5mm_9774050960R" (layer "F.Cu")
    (at 89.556999 144.4435 180)
    (property "Author" "Antmicro")
    (property "License" "Apache-2.0")
    (property "MPN" "9774050960R")
    (property "Manufacturer" "Würth Elektronik")
    (property "Sheetfile" "k26_som.kicad_sch")
    (property "Sheetname" "Xilinx K26 SOM")
    (property "ki_description" "Spacer, SMT, Non Stop, Steel, Swage Round, 6 mm x 5 mm, 3.3 mm Internal, WA-SMST Series")
    (property "ki_keywords" "SPACER")
    (clearance 0.6)
    (attr smd)
    (fp_text reference "SP1" (at 0 -3.4 180) (layer "F.SilkS")
        (effects (font (size 0.7 0.7) (thickness 0.15)) (justify left bottom))
    )
    (fp_text value "Spacer_Drill4.45mm_H5mm_9774050960R" (at 0 4.2 180) (layer "F.Fab")
        (effects (font (size 0.7 0.7) (thickness 0.15)) (justify left bottom))
    )
    (fp_text user "Author: Antmicro" (at -3.25 8.6 180) (layer "F.Fab") hide
        (effects (font (size 0.7 0.7) (thickness 0.15)) (justify left bottom))
    )
    (fp_text user "License: Apache-2.0" (at -3.25 6.2 180) (layer "F.Fab") hide
        (effects (font (size 0.7 0.7) (thickness 0.15)) (justify left bottom))
    )
    (fp_text user "${REFERENCE}" (at -3.25 7.4 180) (layer "F.Fab") hide
        (effects (font (size 0.7 0.7) (thickness 0.15)) (justify left bottom))
    )
    (fp_circle (center 0 0) (end 3.25 0)
      (stroke (width 0.05) (type solid)) (fill none) (layer "F.CrtYd"))
    (fp_circle (center 0 0) (end 2.564 0)
      (stroke (width 0.15) (type solid)) (fill none) (layer "F.Fab"))
    (pad "1" thru_hole circle (at 0 0 180) (size 6 6) (drill 4.45) (layers "*.Cu" "*.Mask" "F.Paste")
      (net 1 "GND") (pintype "passive") (solder_paste_margin_ratio -0.05))
  )

  (footprint "kria-k26-devboard-footprints:TP_SMD_0.75mm" (layer "F.Cu")
    (at 103.55 137.5)
    (property "Author" "Antmicro")
    (property "License" "Apache-2.0")
    (property "MPN" "")
    (property "Manufacturer" "")
    (property "Sheetfile" "debug.kicad_sch")
    (property "Sheetname" "Debug and JTAG")
    (property "ki_description" "Test Point 0.75mm")
    (attr exclude_from_pos_files)
    (fp_text reference "TP33" (at -3.02 0.39) (layer "F.SilkS")
        (effects (font (size 0.7 0.7) (thickness 0.15)) (justify left bottom))
    )
    (fp_text value "TP_0.75mm_SMD" (at 0 1.2) (layer "F.Fab") hide
        (effects (font (size 0.7 0.7) (thickness 0.15)) (justify left bottom))
    )
    (fp_text user "License: Apache-2.0" (at -0.4 5.101) (layer "F.Fab") hide
        (effects (font (size 0.7 0.7) (thickness 0.15)) (justify left bottom))
    )
    (fp_text user "Author: Antmicro" (at -0.4 3.901) (layer "F.Fab") hide
        (effects (font (size 0.7 0.7) (thickness 0.15)) (justify left bottom))
    )
    (fp_text user "${REFERENCE}" (at -0.4 2.7) (layer "F.Fab") hide
        (effects (font (size 0.7 0.7) (thickness 0.15)) (justify left bottom))
    )
    (pad "1" smd circle (at 0 0) (size 0.75 0.75) (layers "F.Cu" "F.Mask")
      (net 186 "/Debug and JTAG/~{EEPROM_WC}") (pinfunction "1") (pintype "passive"))
  )

  (footprint "kria-k26-devboard-footprints:UQFN-10_1.4x1.8x0.5mm_P0.4mm" (layer "F.Cu")
    (at 143.549916 126.012314)
    (property "Author" "Antmicro")
    (property "License" "Apache-2.0")
    (property "MPN" "SN74AVC2T245RSWR")
    (property "Manufacturer" "Texas Instruments")
    (property "Sheetfile" "debug.kicad_sch")
    (property "Sheetname" "Debug and JTAG")
    (property "ki_description" "Transceiver Non Inverting, AVC Family, 2 Input, 12 mA, 2.4 ns, 1.2 V to 3.6 V, LFCSP-10")
    (property "ki_keywords" "SMT, LOGIC, IC, LEVEL-SHIFTER, VOLTAGE")
    (attr smd)
    (fp_text reference "U45" (at -0.449916 -1.662314) (layer "F.SilkS")
        (effects (font (size 0.7 0.7) (thickness 0.15)) (justify left bottom))
    )
    (fp_text value "SN74AVC2T245_UQFN" (at 0 2.4) (layer "F.Fab") hide
        (effects (font (size 0.7 0.7) (thickness 0.15)) (justify left bottom))
    )
    (fp_text user "License: Apache-2.0" (at -0.657 6.9) (layer "F.Fab") hide
        (effects (font (size 0.7 0.7) (thickness 0.15)) (justify left bottom))
    )
    (fp_text user "Author: Antmicro" (at -0.657 5.7) (layer "F.Fab") hide
        (effects (font (size 0.7 0.7) (thickness 0.15)) (justify left bottom))
    )
    (fp_text user "${REFERENCE}" (at -0.657 4.498) (layer "F.Fab") hide
        (effects (font (size 0.7 0.7) (thickness 0.15)) (justify left bottom))
    )
    (fp_line (start -0.7305 -0.552) (end -1.2005 -0.552)
      (stroke (width 0.15) (type solid)) (layer "F.SilkS"))
    (fp_line (start -0.7305 -0.552) (end -0.7305 -0.93)
      (stroke (width 0.15) (type solid)) (layer "F.SilkS"))
    (fp_circle (center -1.0515 -1.151) (end -0.9805 -1.151)
      (stroke (width 0.15) (type solid)) (fill none) (layer "F.SilkS"))
    (fp_rect (start -1.3 -1.5) (end 1.3 1.5)
      (stroke (width 0.05) (type solid)) (fill none) (layer "F.CrtYd"))
    (fp_line (start -0.7 -0.4) (end -0.175 -0.925)
      (stroke (width 0.15) (type solid)) (layer "F.Fab"))
    (fp_line (start -0.7 0.93) (end -0.7 -0.4)
      (stroke (width 0.15) (type solid)) (layer "F.Fab"))
    (fp_line (start -0.175 -0.925) (end 0.7295 -0.925)
      (stroke (width 0.15) (type solid)) (layer "F.Fab"))
    (fp_line (start 0.725 0.93) (end -0.7 0.93)
      (stroke (width 0.15) (type solid)) (layer "F.Fab"))
    (fp_line (start 0.7295 -0.925) (end 0.725 0.93)
      (stroke (width 0.15) (type solid)) (layer "F.Fab"))
    (pad "1" smd roundrect (at -0.6445 -0.2) (size 0.81 0.22) (layers "F.Cu" "F.Paste" "F.Mask") (roundrect_rratio 0.25)
      (net 138 "/Debug and JTAG/USB_3V3") (pinfunction "DIR_{2}") (pintype "input"))
    (pad "2" smd roundrect (at -0.6445 0.2) (size 0.81 0.22) (layers "F.Cu" "F.Paste" "F.Mask") (roundrect_rratio 0.25)
      (net 1 "GND") (pinfunction "~{OE}") (pintype "input"))
    (pad "3" smd roundrect (at -0.4015 0.844 270) (size 0.81 0.22) (layers "F.Cu" "F.Paste" "F.Mask") (roundrect_rratio 0.25)
      (net 1 "GND") (pinfunction "GND") (pintype "power_in"))
    (pad "4" smd roundrect (at 0.0005 0.844 270) (size 0.81 0.22) (layers "F.Cu" "F.Paste" "F.Mask") (roundrect_rratio 0.25)
      (net 150 "/Debug and JTAG/MIO37") (pinfunction "B_{2}") (pintype "bidirectional"))
    (pad "5" smd roundrect (at 0.3995 0.844 270) (size 0.81 0.22) (layers "F.Cu" "F.Paste" "F.Mask") (roundrect_rratio 0.25)
      (net 149 "/Debug and JTAG/MIO36") (pinfunction "B_{1}") (pintype "bidirectional"))
    (pad "6" smd roundrect (at 0.6455 0.2) (size 0.81 0.22) (layers "F.Cu" "F.Paste" "F.Mask") (roundrect_rratio 0.25)
      (net 17 "PS_1V8") (pinfunction "V_{CCB}") (pintype "power_in"))
    (pad "7" smd roundrect (at 0.6455 -0.2) (size 0.81 0.22) (layers "F.Cu" "F.Paste" "F.Mask") (roundrect_rratio 0.25)
      (net 138 "/Debug and JTAG/USB_3V3") (pinfunction "V_{CCA}") (pintype "power_in"))
    (pad "8" smd roundrect (at 0.3995 -0.847 270) (size 0.81 0.22) (layers "F.Cu" "F.Paste" "F.Mask") (roundrect_rratio 0.25)
      (net 165 "/Debug and JTAG/FTDI_UARTB_RXD") (pinfunction "A_{1}") (pintype "bidirectional"))
    (pad "9" smd roundrect (at 0.0005 -0.847 270) (size 0.81 0.22) (layers "F.Cu" "F.Paste" "F.Mask") (roundrect_rratio 0.25)
      (net 166 "/Debug and JTAG/FTDI_UARTB_TXD") (pinfunction "A_{2}") (pintype "bidirectional"))
    (pad "10" smd roundrect (at -0.4015 -0.847 270) (size 0.81 0.22) (layers "F.Cu" "F.Paste" "F.Mask") (roundrect_rratio 0.25)
      (net 1 "GND") (pinfunction "DIR_{1}") (pintype "input"))
  )

  (footprint "kria-k26-devboard-footprints:FB_0402_1005Metric" (layer "F.Cu")
    (at 149.45 112.7 -90)
    (descr "Ferrite Bead SMD 0402")
    (tags "ferrite bead SMD 0402")
    (property "Author" "Antmicro")
    (property "License" "Apache-2.0")
    (property "MPN" "BLM15PD121SN1D")
    (property "Manufacturer" "Murata")
    (property "Sheetfile" "debug.kicad_sch")
    (property "Sheetname" "Debug and JTAG")
    (attr smd)
    (fp_text reference "FB5" (at 1.29 0.53 -90) (layer "F.SilkS")
        (effects (font (size 0.7 0.7) (thickness 0.15)) (justify left bottom))
    )
    (fp_text value "FB_120Z_1.3A_0402" (at 0 1.4 -90) (layer "F.Fab") hide
        (effects (font (size 0.7 0.7) (thickness 0.15)) (justify left bottom))
    )
    (fp_text user "Author: Antmicro" (at -0.95 4.169 -90) (layer "F.Fab") hide
        (effects (font (size 0.7 0.7) (thickness 0.15)) (justify left bottom))
    )
    (fp_text user "License: Apache-2.0" (at -0.95 5.169 -90) (layer "F.Fab") hide
        (effects (font (size 0.7 0.7) (thickness 0.15)) (justify left bottom))
    )
    (fp_text user "${REFERENCE}" (at -0.95 3.168 -90) (layer "F.Fab") hide
        (effects (font (size 0.7 0.7) (thickness 0.15)) (justify left bottom))
    )
    (fp_rect (start -0.95 -0.48) (end 0.95 0.48)
      (stroke (width 0.05) (type solid)) (fill none) (layer "F.CrtYd"))
    (fp_rect (start -0.5 -0.25) (end 0.5 0.25)
      (stroke (width 0.15) (type solid)) (fill none) (layer "F.Fab"))
    (pad "1" smd roundrect (at -0.485 0 270) (size 0.59 0.64) (layers "F.Cu" "F.Paste" "F.Mask") (roundrect_rratio 0.25)
      (net 138 "/Debug and JTAG/USB_3V3") (pintype "passive"))
    (pad "2" smd roundrect (at 0.485 0 270) (size 0.59 0.64) (layers "F.Cu" "F.Paste" "F.Mask") (roundrect_rratio 0.25)
      (net 135 "/Debug and JTAG/VCC_USB") (pintype "passive"))
  )

  (footprint "kria-k26-devboard-footprints:TP_SMD_0.75mm" (layer "F.Cu")
    (at 149.45 110.7)
    (property "Author" "Antmicro")
    (property "License" "Apache-2.0")
    (property "MPN" "")
    (property "Manufacturer" "")
    (property "Sheetfile" "debug.kicad_sch")
    (property "Sheetname" "Debug and JTAG")
    (property "ki_description" "Test Point 0.75mm")
    (attr exclude_from_pos_files)
    (fp_text reference "TP27" (at 0.37 -0.36 90) (layer "F.SilkS")
        (effects (font (size 0.7 0.7) (thickness 0.15)) (justify left bottom))
    )
    (fp_text value "TP_0.75mm_SMD" (at 0 1.2) (layer "F.Fab") hide
        (effects (font (size 0.7 0.7) (thickness 0.15)) (justify left bottom))
    )
    (fp_text user "${REFERENCE}" (at -0.4 2.7) (layer "F.Fab") hide
        (effects (font (size 0.7 0.7) (thickness 0.15)) (justify left bottom))
    )
    (fp_text user "License: Apache-2.0" (at -0.4 5.101) (layer "F.Fab") hide
        (effects (font (size 0.7 0.7) (thickness 0.15)) (justify left bottom))
    )
    (fp_text user "Author: Antmicro" (at -0.4 3.901) (layer "F.Fab") hide
        (effects (font (size 0.7 0.7) (thickness 0.15)) (justify left bottom))
    )
    (pad "1" smd circle (at 0 0) (size 0.75 0.75) (layers "F.Cu" "F.Mask")
      (net 138 "/Debug and JTAG/USB_3V3") (pinfunction "1") (pintype "passive"))
  )

  (footprint "kria-k26-devboard-footprints:SOT-416" (layer "F.Cu")
    (at 136.395 128.18 180)
    (descr "SOT-416")
    (tags "SOT-416")
    (property "Author" "Antmicro")
    (property "License" "Apache-2.0")
    (property "MPN" "DTC014TEBTL")
    (property "Manufacturer" "ROHM Semiconductor")
    (property "Sheetfile" "debug.kicad_sch")
    (property "Sheetname" "Debug and JTAG")
    (property "ki_description" "Digital NPN Transistor, 10k/NONE, EMT-3")
    (attr smd)
    (fp_text reference "Q10" (at 3.175 -0.01 180) (layer "F.SilkS")
        (effects (font (size 0.7 0.7) (thickness 0.15)) (justify left bottom))
    )
    (fp_text value "DTC014T_SOT-416" (at 0 2 180) (layer "F.Fab") hide
        (effects (font (size 0.7 0.7) (thickness 0.15)) (justify left bottom))
    )
    (fp_text user "License: Apache-2.0" (at -1 5.802 180) (layer "F.Fab") hide
        (effects (font (size 0.7 0.7) (thickness 0.15)) (justify left bottom))
    )
    (fp_text user "${REFERENCE}" (at -1 3.4 180) (layer "F.Fab") hide
        (effects (font (size 0.7 0.7) (thickness 0.15)) (justify left bottom))
    )
    (fp_text user "Author: Antmicro" (at -1 4.602 180) (layer "F.Fab") hide
        (effects (font (size 0.7 0.7) (thickness 0.15)) (justify left bottom))
    )
    (fp_line (start -0.5 -0.15) (end -0.5 0.15)
      (stroke (width 0.15) (type solid)) (layer "F.SilkS"))
    (fp_line (start 0.5 0.9) (end -0.5 0.9)
      (stroke (width 0.15) (type solid)) (layer "F.SilkS"))
    (fp_line (start 0.5 0.9) (end 0.5 0.7)
      (stroke (width 0.15) (type solid)) (layer "F.SilkS"))
    (fp_line (start 0.508 -0.9) (end -0.5 -0.9)
      (stroke (width 0.15) (type solid)) (layer "F.SilkS"))
    (fp_line (start 0.508 -0.9) (end 0.508 -0.592)
      (stroke (width 0.15) (type solid)) (layer "F.SilkS"))
    (fp_rect (start -1 -1.05) (end 1 1.05)
      (stroke (width 0.05) (type solid)) (fill none) (layer "F.CrtYd"))
    (fp_line (start -0.05 -0.9) (end -0.45 -0.5)
      (stroke (width 0.15) (type solid)) (layer "F.Fab"))
    (fp_rect (start 0.45 0.9) (end -0.45 -0.9)
      (stroke (width 0.15) (type solid)) (fill none) (layer "F.Fab"))
    (pad "1" smd rect (at -0.652 -0.5 180) (size 0.6 0.5) (layers "F.Cu" "F.Paste" "F.Mask")
      (net 159 "/Debug and JTAG/~{FTDI_LS_OE}") (pinfunction "B") (pintype "input"))
    (pad "2" smd rect (at -0.652 0.498 180) (size 0.6 0.5) (layers "F.Cu" "F.Paste" "F.Mask")
      (net 1 "GND") (pinfunction "E") (pintype "passive"))
    (pad "3" smd rect (at 0.65 0 180) (size 0.6 0.5) (layers "F.Cu" "F.Paste" "F.Mask")
      (net 220 "/Debug and JTAG/CONN_GND") (pinfunction "C") (pintype "passive"))
  )

  (footprint "kria-k26-devboard-footprints:R_0402_1005Metric" (layer "F.Cu")
    (at 91.28 71.4 180)
    (descr "Resistor SMD 0402")
    (tags "resistor SMD 0402")
    (property "Author" "Antmicro")
    (property "License" "Apache-2.0")
    (property "MPN" "CR0402-FX-1003GLF")
    (property "Manufacturer" "Bourns")
    (property "Sheetfile" "dp.kicad_sch")
    (property "Sheetname" "Display Port")
    (property "Tolerance" "1%")
    (property "Val" "100k")
    (property "ki_description" "100k resistor in 0402 package with 1% tolerance")
    (attr smd)
    (fp_text reference "R8" (at -6.255 -0.353 180) (layer "F.SilkS")
        (effects (font (size 0.7 0.7) (thickness 0.15)) (justify left bottom))
    )
    (fp_text value "R_100k_0402" (at 0 1.4 180) (layer "F.Fab") hide
        (effects (font (size 0.7 0.7) (thickness 0.15)) (justify left bottom))
    )
    (fp_text user "License: Apache-2.0" (at -0.95 5.169 180) (layer "F.Fab") hide
        (effects (font (size 0.7 0.7) (thickness 0.15)) (justify left bottom))
    )
    (fp_text user "${REFERENCE}" (at -0.95 3.168 180) (layer "F.Fab") hide
        (effects (font (size 0.7 0.7) (thickness 0.15)) (justify left bottom))
    )
    (fp_text user "Author: Antmicro" (at -0.95 4.169 180) (layer "F.Fab") hide
        (effects (font (size 0.7 0.7) (thickness 0.15)) (justify left bottom))
    )
    (fp_rect (start -0.93 -0.47) (end 0.93 0.47)
      (stroke (width 0.05) (type solid)) (fill none) (layer "F.CrtYd"))
    (fp_rect (start -0.5 -0.25) (end 0.5 0.25)
      (stroke (width 0.15) (type solid)) (fill none) (layer "F.Fab"))
    (pad "1" smd roundrect (at -0.485 0 180) (size 0.59 0.64) (layers "F.Cu" "F.Paste" "F.Mask") (roundrect_rratio 0.25)
      (net 97 "/Display Port/DP_AUX_C_P") (pintype "passive"))
    (pad "2" smd roundrect (at 0.485 0 180) (size 0.59 0.64) (layers "F.Cu" "F.Paste" "F.Mask") (roundrect_rratio 0.25)
      (net 1 "GND") (pintype "passive"))
  )

  (footprint "kria-k26-devboard-footprints:R_0402_1005Metric" (layer "F.Cu")
    (at 93.23 71.4 180)
    (descr "Resistor SMD 0402")
    (tags "resistor SMD 0402")
    (property "Author" "Antmicro")
    (property "License" "Apache-2.0")
    (property "MPN" "CR0402-FX-1003GLF")
    (property "Manufacturer" "Bourns")
    (property "Sheetfile" "dp.kicad_sch")
    (property "Sheetname" "Display Port")
    (property "Tolerance" "1%")
    (property "Val" "100k")
    (property "ki_description" "100k resistor in 0402 package with 1% tolerance")
    (attr smd)
    (fp_text reference "R7" (at -6.145 -0.353 180) (layer "F.SilkS")
        (effects (font (size 0.7 0.7) (thickness 0.15)) (justify left bottom))
    )
    (fp_text value "R_100k_0402" (at 0 1.4 180) (layer "F.Fab") hide
        (effects (font (size 0.7 0.7) (thickness 0.15)) (justify left bottom))
    )
    (fp_text user "Author: Antmicro" (at -0.95 4.169 180) (layer "F.Fab") hide
        (effects (font (size 0.7 0.7) (thickness 0.15)) (justify left bottom))
    )
    (fp_text user "${REFERENCE}" (at -0.95 3.168 180) (layer "F.Fab") hide
        (effects (font (size 0.7 0.7) (thickness 0.15)) (justify left bottom))
    )
    (fp_text user "License: Apache-2.0" (at -0.95 5.169 180) (layer "F.Fab") hide
        (effects (font (size 0.7 0.7) (thickness 0.15)) (justify left bottom))
    )
    (fp_rect (start -0.93 -0.47) (end 0.93 0.47)
      (stroke (width 0.05) (type solid)) (fill none) (layer "F.CrtYd"))
    (fp_rect (start -0.5 -0.25) (end 0.5 0.25)
      (stroke (width 0.15) (type solid)) (fill none) (layer "F.Fab"))
    (pad "1" smd roundrect (at -0.485 0 180) (size 0.59 0.64) (layers "F.Cu" "F.Paste" "F.Mask") (roundrect_rratio 0.25)
      (net 15 "PS_3V3") (pintype "passive"))
    (pad "2" smd roundrect (at 0.485 0 180) (size 0.59 0.64) (layers "F.Cu" "F.Paste" "F.Mask") (roundrect_rratio 0.25)
      (net 99 "/Display Port/DP_AUX_C_N") (pintype "passive"))
  )

  (footprint "kria-k26-devboard-footprints:R_0402_1005Metric" (layer "F.Cu")
    (at 89.88 73.73 90)
    (descr "Resistor SMD 0402")
    (tags "resistor SMD 0402")
    (property "Author" "Antmicro")
    (property "License" "Apache-2.0")
    (property "MPN" "CR0402-FX-1501GLF")
    (property "Manufacturer" "Bourns")
    (property "Sheetfile" "dp.kicad_sch")
    (property "Sheetname" "Display Port")
    (property "Tolerance" "1%")
    (property "Val" "1k5")
    (property "ki_description" "1k5 resistor in 0402 package with 1% tolerance")
    (attr smd)
    (fp_text reference "R6" (at -0.803 7.475 90) (layer "F.SilkS")
        (effects (font (size 0.7 0.7) (thickness 0.15)) (justify left bottom))
    )
    (fp_text value "R_1k5_0402" (at 0 1.4 90) (layer "F.Fab") hide
        (effects (font (size 0.7 0.7) (thickness 0.15)) (justify left bottom))
    )
    (fp_text user "License: Apache-2.0" (at -0.95 5.169 90) (layer "F.Fab") hide
        (effects (font (size 0.7 0.7) (thickness 0.15)) (justify left bottom))
    )
    (fp_text user "Author: Antmicro" (at -0.95 4.169 90) (layer "F.Fab") hide
        (effects (font (size 0.7 0.7) (thickness 0.15)) (justify left bottom))
    )
    (fp_text user "${REFERENCE}" (at -0.95 3.168 90) (layer "F.Fab") hide
        (effects (font (size 0.7 0.7) (thickness 0.15)) (justify left bottom))
    )
    (fp_rect (start -0.93 -0.47) (end 0.93 0.47)
      (stroke (width 0.05) (type solid)) (fill none) (layer "F.CrtYd"))
    (fp_rect (start -0.5 -0.25) (end 0.5 0.25)
      (stroke (width 0.15) (type solid)) (fill none) (layer "F.Fab"))
    (pad "1" smd roundrect (at -0.485 0 90) (size 0.59 0.64) (layers "F.Cu" "F.Paste" "F.Mask") (roundrect_rratio 0.25)
      (net 380 "Net-(R3-Pad2)") (pintype "passive"))
    (pad "2" smd roundrect (at 0.485 0 90) (size 0.59 0.64) (layers "F.Cu" "F.Paste" "F.Mask") (roundrect_rratio 0.25)
      (net 1 "GND") (pintype "passive"))
  )

  (footprint "kria-k26-devboard-footprints:R_0402_1005Metric" (layer "F.Cu")
    (at 94.605 73.717 -90)
    (descr "Resistor SMD 0402")
    (tags "resistor SMD 0402")
    (property "Author" "Antmicro")
    (property "License" "Apache-2.0")
    (property "MPN" "CR0402-FX-2491GLF")
    (property "Manufacturer" "Bourns")
    (property "Sheetfile" "dp.kicad_sch")
    (property "Sheetname" "Display Port")
    (property "Tolerance" "1%")
    (property "Val" "2k49")
    (property "ki_description" "2k49 resistor in 0402 package with 1% tolerance")
    (attr smd)
    (fp_text reference "R5" (at 0.903 -7.325 -90) (layer "F.SilkS")
        (effects (font (size 0.7 0.7) (thickness 0.15)) (justify left bottom))
    )
    (fp_text value "R_2k49_0402" (at 0 1.4 -90) (layer "F.Fab") hide
        (effects (font (size 0.7 0.7) (thickness 0.15)) (justify left bottom))
    )
    (fp_text user "License: Apache-2.0" (at -0.95 5.169 -90) (layer "F.Fab") hide
        (effects (font (size 0.7 0.7) (thickness 0.15)) (justify left bottom))
    )
    (fp_text user "Author: Antmicro" (at -0.95 4.169 -90) (layer "F.Fab") hide
        (effects (font (size 0.7 0.7) (thickness 0.15)) (justify left bottom))
    )
    (fp_text user "${REFERENCE}" (at -0.95 3.168 -90) (layer "F.Fab") hide
        (effects (font (size 0.7 0.7) (thickness 0.15)) (justify left bottom))
    )
    (fp_rect (start -0.93 -0.47) (end 0.93 0.47)
      (stroke (width 0.05) (type solid)) (fill none) (layer "F.CrtYd"))
    (fp_rect (start -0.5 -0.25) (end 0.5 0.25)
      (stroke (width 0.15) (type solid)) (fill none) (layer "F.Fab"))
    (pad "1" smd roundrect (at -0.485 0 270) (size 0.59 0.64) (layers "F.Cu" "F.Paste" "F.Mask") (roundrect_rratio 0.25)
      (net 15 "PS_3V3") (pintype "passive"))
    (pad "2" smd roundrect (at 0.485 0 270) (size 0.59 0.64) (layers "F.Cu" "F.Paste" "F.Mask") (roundrect_rratio 0.25)
      (net 380 "Net-(R3-Pad2)") (pintype "passive"))
  )

  (footprint "kria-k26-devboard-footprints:R_0402_1005Metric" (layer "F.Cu")
    (at 93.2 74.23)
    (descr "Resistor SMD 0402")
    (tags "resistor SMD 0402")
    (property "Author" "Antmicro")
    (property "License" "Apache-2.0")
    (property "MPN" "CR0402-FX-49R9GLF")
    (property "Manufacturer" "Bourns")
    (property "Sheetfile" "dp.kicad_sch")
    (property "Sheetname" "Display Port")
    (property "Tolerance" "1%")
    (property "Val" "49R9")
    (property "ki_description" "49R9 resistor in 0402 package with 1% tolerance")
    (attr smd)
    (fp_text reference "R4" (at 6.145 0.523) (layer "F.SilkS")
        (effects (font (size 0.7 0.7) (thickness 0.15)) (justify left bottom))
    )
    (fp_text value "R_49R9_0402" (at 0 1.4) (layer "F.Fab") hide
        (effects (font (size 0.7 0.7) (thickness 0.15)) (justify left bottom))
    )
    (fp_text user "License: Apache-2.0" (at -0.95 5.169) (layer "F.Fab") hide
        (effects (font (size 0.7 0.7) (thickness 0.15)) (justify left bottom))
    )
    (fp_text user "Author: Antmicro" (at -0.95 4.169) (layer "F.Fab") hide
        (effects (font (size 0.7 0.7) (thickness 0.15)) (justify left bottom))
    )
    (fp_text user "${REFERENCE}" (at -0.95 3.168) (layer "F.Fab") hide
        (effects (font (size 0.7 0.7) (thickness 0.15)) (justify left bottom))
    )
    (fp_rect (start -0.93 -0.47) (end 0.93 0.47)
      (stroke (width 0.05) (type solid)) (fill none) (layer "F.CrtYd"))
    (fp_rect (start -0.5 -0.25) (end 0.5 0.25)
      (stroke (width 0.15) (type solid)) (fill none) (layer "F.Fab"))
    (pad "1" smd roundrect (at -0.485 0) (size 0.59 0.64) (layers "F.Cu" "F.Paste" "F.Mask") (roundrect_rratio 0.25)
      (net 98 "/Display Port/DP_AUX_N") (pintype "passive"))
    (pad "2" smd roundrect (at 0.485 0) (size 0.59 0.64) (layers "F.Cu" "F.Paste" "F.Mask") (roundrect_rratio 0.25)
      (net 380 "Net-(R3-Pad2)") (pintype "passive"))
  )

  (footprint "kria-k26-devboard-footprints:R_0402_1005Metric" (layer "F.Cu")
    (at 91.29 74.23 180)
    (descr "Resistor SMD 0402")
    (tags "resistor SMD 0402")
    (property "Author" "Antmicro")
    (property "License" "Apache-2.0")
    (property "MPN" "CR0402-FX-49R9GLF")
    (property "Manufacturer" "Bourns")
    (property "Sheetfile" "dp.kicad_sch")
    (property "Sheetname" "Display Port")
    (property "Tolerance" "1%")
    (property "Val" "49R9")
    (property "ki_description" "49R9 resistor in 0402 package with 1% tolerance")
    (attr smd)
    (fp_text reference "R3" (at -6.255 -0.523 180) (layer "F.SilkS")
        (effects (font (size 0.7 0.7) (thickness 0.15)) (justify left bottom))
    )
    (fp_text value "R_49R9_0402" (at 0 1.4 180) (layer "F.Fab") hide
        (effects (font (size 0.7 0.7) (thickness 0.15)) (justify left bottom))
    )
    (fp_text user "Author: Antmicro" (at -0.95 4.169 180) (layer "F.Fab") hide
        (effects (font (size 0.7 0.7) (thickness 0.15)) (justify left bottom))
    )
    (fp_text user "License: Apache-2.0" (at -0.95 5.169 180) (layer "F.Fab") hide
        (effects (font (size 0.7 0.7) (thickness 0.15)) (justify left bottom))
    )
    (fp_text user "${REFERENCE}" (at -0.95 3.168 180) (layer "F.Fab") hide
        (effects (font (size 0.7 0.7) (thickness 0.15)) (justify left bottom))
    )
    (fp_rect (start -0.93 -0.47) (end 0.93 0.47)
      (stroke (width 0.05) (type solid)) (fill none) (layer "F.CrtYd"))
    (fp_rect (start -0.5 -0.25) (end 0.5 0.25)
      (stroke (width 0.15) (type solid)) (fill none) (layer "F.Fab"))
    (pad "1" smd roundrect (at -0.485 0 180) (size 0.59 0.64) (layers "F.Cu" "F.Paste" "F.Mask") (roundrect_rratio 0.25)
      (net 96 "/Display Port/DP_AUX_P") (pintype "passive"))
    (pad "2" smd roundrect (at 0.485 0 180) (size 0.59 0.64) (layers "F.Cu" "F.Paste" "F.Mask") (roundrect_rratio 0.25)
      (net 380 "Net-(R3-Pad2)") (pintype "passive"))
  )

  (footprint "kria-k26-devboard-footprints:C_0402_1005Metric" (layer "F.Cu")
    (at 92.73 72.817 90)
    (descr "Capacitor SMD 0402")
    (tags "capacitor SMD 0402")
    (property "Author" "Antmicro")
    (property "Dielectric" "X5R")
    (property "License" "Apache-2.0")
    (property "MPN" "GRM155R61H104KE14D")
    (property "Manufacturer" "Murata")
    (property "Sheetfile" "dp.kicad_sch")
    (property "Sheetname" "Display Port")
    (property "Val" "100n")
    (property "Voltage" "50V")
    (property "ki_description" " ")
    (attr smd)
    (fp_text reference "C11" (at -1.153 7.345 90) (layer "F.SilkS")
        (effects (font (size 0.7 0.7) (thickness 0.15)) (justify left bottom))
    )
    (fp_text value "C_100n_0402" (at 0 1.4 90) (layer "F.Fab") hide
        (effects (font (size 0.7 0.7) (thickness 0.15)) (justify left bottom))
    )
    (fp_text user "License: Apache-2.0" (at -0.932 5.17 90) (layer "F.Fab") hide
        (effects (font (size 0.7 0.7) (thickness 0.15)) (justify left bottom))
    )
    (fp_text user "${REFERENCE}" (at -0.932 3.168 90) (layer "F.Fab") hide
        (effects (font (size 0.7 0.7) (thickness 0.15)) (justify left bottom))
    )
    (fp_text user "Author: Antmicro" (at -0.932 4.17 90) (layer "F.Fab") hide
        (effects (font (size 0.7 0.7) (thickness 0.15)) (justify left bottom))
    )
    (fp_rect (start -0.94 -0.47) (end 0.94 0.47)
      (stroke (width 0.05) (type solid)) (fill none) (layer "F.CrtYd"))
    (fp_rect (start -0.499 -0.249) (end 0.499 0.249)
      (stroke (width 0.15) (type solid)) (fill none) (layer "F.Fab"))
    (pad "1" smd roundrect (at -0.484 0 90) (size 0.59 0.64) (layers "F.Cu" "F.Paste" "F.Mask") (roundrect_rratio 0.25)
      (net 98 "/Display Port/DP_AUX_N") (pintype "passive"))
    (pad "2" smd roundrect (at 0.484 0 90) (size 0.59 0.64) (layers "F.Cu" "F.Paste" "F.Mask") (roundrect_rratio 0.25)
      (net 99 "/Display Port/DP_AUX_C_N") (pintype "passive"))
  )

  (footprint "kria-k26-devboard-footprints:C_0402_1005Metric" (layer "F.Cu")
    (at 91.78 72.817 90)
    (descr "Capacitor SMD 0402")
    (tags "capacitor SMD 0402")
    (property "Author" "Antmicro")
    (property "Dielectric" "X5R")
    (property "License" "Apache-2.0")
    (property "MPN" "GRM155R61H104KE14D")
    (property "Manufacturer" "Murata")
    (property "Sheetfile" "dp.kicad_sch")
    (property "Sheetname" "Display Port")
    (property "Val" "100n")
    (property "Voltage" "50V")
    (property "ki_description" " ")
    (attr smd)
    (fp_text reference "C10" (at -1.153 7.345 90) (layer "F.SilkS")
        (effects (font (size 0.7 0.7) (thickness 0.15)) (justify left bottom))
    )
    (fp_text value "C_100n_0402" (at 0 1.4 90) (layer "F.Fab") hide
        (effects (font (size 0.7 0.7) (thickness 0.15)) (justify left bottom))
    )
    (fp_text user "Author: Antmicro" (at -0.932 4.17 90) (layer "F.Fab") hide
        (effects (font (size 0.7 0.7) (thickness 0.15)) (justify left bottom))
    )
    (fp_text user "License: Apache-2.0" (at -0.932 5.17 90) (layer "F.Fab") hide
        (effects (font (size 0.7 0.7) (thickness 0.15)) (justify left bottom))
    )
    (fp_text user "${REFERENCE}" (at -0.932 3.168 90) (layer "F.Fab") hide
        (effects (font (size 0.7 0.7) (thickness 0.15)) (justify left bottom))
    )
    (fp_rect (start -0.94 -0.47) (end 0.94 0.47)
      (stroke (width 0.05) (type solid)) (fill none) (layer "F.CrtYd"))
    (fp_rect (start -0.499 -0.249) (end 0.499 0.249)
      (stroke (width 0.15) (type solid)) (fill none) (layer "F.Fab"))
    (pad "1" smd roundrect (at -0.484 0 90) (size 0.59 0.64) (layers "F.Cu" "F.Paste" "F.Mask") (roundrect_rratio 0.25)
      (net 96 "/Display Port/DP_AUX_P") (pintype "passive"))
    (pad "2" smd roundrect (at 0.484 0 90) (size 0.59 0.64) (layers "F.Cu" "F.Paste" "F.Mask") (roundrect_rratio 0.25)
      (net 97 "/Display Port/DP_AUX_C_P") (pintype "passive"))
  )

  (footprint "kria-k26-devboard-footprints:C_0402_1005Metric" (layer "F.Cu")
    (at 147.5 142.95)
    (descr "Capacitor SMD 0402")
    (tags "capacitor SMD 0402")
    (property "Author" "Antmicro")
    (property "Dielectric" "")
    (property "License" "Apache-2.0")
    (property "MPN" "GRM155R71H104KE14D")
    (property "Manufacturer" "Murata")
    (property "Sheetfile" "debug.kicad_sch")
    (property "Sheetname" "Debug and JTAG")
    (property "Val" "100n/50V")
    (property "Voltage" "")
    (property "ki_description" " ")
    (attr smd)
    (fp_text reference "C153" (at -0.97 -0.65) (layer "F.SilkS")
        (effects (font (size 0.7 0.7) (thickness 0.15)) (justify left bottom))
    )
    (fp_text value "C_100n_50V_0402" (at 0 1.4) (layer "F.Fab") hide
        (effects (font (size 0.7 0.7) (thickness 0.15)) (justify left bottom))
    )
    (fp_text user "${REFERENCE}" (at -0.932 3.168) (layer "F.Fab") hide
        (effects (font (size 0.7 0.7) (thickness 0.15)) (justify left bottom))
    )
    (fp_text user "License: Apache-2.0" (at -0.932 5.17) (layer "F.Fab") hide
        (effects (font (size 0.7 0.7) (thickness 0.15)) (justify left bottom))
    )
    (fp_text user "Author: Antmicro" (at -0.932 4.17) (layer "F.Fab") hide
        (effects (font (size 0.7 0.7) (thickness 0.15)) (justify left bottom))
    )
    (fp_rect (start -0.94 -0.47) (end 0.94 0.47)
      (stroke (width 0.05) (type solid)) (fill none) (layer "F.CrtYd"))
    (fp_rect (start -0.499 -0.249) (end 0.499 0.249)
      (stroke (width 0.15) (type solid)) (fill none) (layer "F.Fab"))
    (pad "1" smd roundrect (at -0.484 0) (size 0.59 0.64) (layers "F.Cu" "F.Paste" "F.Mask") (roundrect_rratio 0.25)
      (net 266 "/Debug and JTAG/USBB_VBUS") (pintype "passive"))
    (pad "2" smd roundrect (at 0.484 0) (size 0.59 0.64) (layers "F.Cu" "F.Paste" "F.Mask") (roundrect_rratio 0.25)
      (net 1 "GND") (pintype "passive"))
  )

  (footprint "kria-k26-devboard-footprints:USB-C_Receptacle_GCT_USB4105-GF-A" (layer "F.Cu")
    (at 144.35 147.825)
    (property "Author" "Antmicro")
    (property "DNP" "DNP")
    (property "License" "Apache-2.0")
    (property "MPN" "USB4105-GF-A")
    (property "Manufacturer" "GCT")
    (property "Sheetfile" "debug.kicad_sch")
    (property "Sheetname" "Debug and JTAG")
    (property "VSD_Class" "USB-C")
    (property "dnp" "")
    (property "ki_description" "USB-C (USB TYPE-C) USB 2.0 Receptacle Connector 24 (16+8 Dummy) Position Surface Mount, Right Angle")
    (property "ki_keywords" "USB, CONNECTOR, SMT, HORIZONTAL")
    (attr exclude_from_pos_files)
    (fp_text reference "J8" (at 5.23 3.715) (layer "F.SilkS")
        (effects (font (size 0.7 0.7) (thickness 0.15)) (justify left bottom))
    )
    (fp_text value "USB-C_GCT_USB4105-GF-A" (at 0 5) (layer "F.Fab") hide
        (effects (font (size 0.7 0.7) (thickness 0.15)) (justify left bottom))
    )
    (fp_text user "License: Apache-2.0" (at -4.79 8.855) (layer "F.Fab") hide
        (effects (font (size 0.7 0.7) (thickness 0.15)) (justify left bottom))
    )
    (fp_text user "Author: Antmicro" (at -4.79 7.853) (layer "F.Fab") hide
        (effects (font (size 0.7 0.7) (thickness 0.15)) (justify left bottom))
    )
    (fp_text user "PCB-EDGE" (at -4.79 5.853) (layer "F.Fab") hide
        (effects (font (size 0.7 0.7) (thickness 0.15)) (justify left bottom))
    )
    (fp_text user "${REFERENCE}" (at -4.79 6.853) (layer "F.Fab") hide
        (effects (font (size 0.7 0.7) (thickness 0.15)) (justify left bottom))
    )
    (fp_line (start -4.79 -1.395) (end -4.79 -0.145)
      (stroke (width 0.15) (type solid)) (layer "F.SilkS"))
    (fp_line (start -4.79 2.575) (end -4.79 3.854)
      (stroke (width 0.15) (type solid)) (layer "F.SilkS"))
    (fp_line (start -4.79 3.854) (end 4.788 3.854)
      (stroke (width 0.15) (type solid)) (layer "F.SilkS"))
    (fp_line (start 4.788 -1.395) (end 4.788 -0.145)
      (stroke (width 0.15) (type solid)) (layer "F.SilkS"))
    (fp_line (start 4.788 3.854) (end 4.788 2.575)
      (stroke (width 0.15) (type solid)) (layer "F.SilkS"))
    (fp_circle (center -3.8 -4.27071) (end -3.75 -4.22071)
      (stroke (width 0.15) (type solid)) (fill solid) (layer "F.SilkS"))
    (fp_rect (start -5.1 -4.4) (end 5.1 3.9)
      (stroke (width 0.05) (type solid)) (fill none) (layer "F.CrtYd"))
    (fp_line (start -4.79 -3.676) (end 4.788 -3.676)
      (stroke (width 0.15) (type solid)) (layer "F.Fab"))
    (fp_line (start -4.79 3.854) (end -4.79 -3.676)
      (stroke (width 0.15) (type solid)) (layer "F.Fab"))
    (fp_line (start -4.702 3.854) (end 4.788 3.854)
      (stroke (width 0.15) (type solid)) (layer "F.Fab"))
    (fp_line (start 4.788 -3.676) (end 4.788 3.854)
      (stroke (width 0.15) (type solid)) (layer "F.Fab"))
    (fp_line (start 4.788 3.854) (end -4.79 3.854)
      (stroke (width 0.15) (type solid)) (layer "F.Fab"))
    (pad "" np_thru_hole circle (at -2.891 -2.426) (size 0.65 0.65) (drill 0.65) (layers "*.Cu" "*.Mask"))
    (pad "" np_thru_hole circle (at 2.89 -2.426) (size 0.65 0.65) (drill 0.65) (layers "*.Cu" "*.Mask"))
    (pad "A1" smd roundrect (at -3.202 -3.5) (size 0.6 1.15) (layers "F.Cu" "F.Paste" "F.Mask") (roundrect_rratio 0.25)
      (net 1 "GND") (pinfunction "GND") (pintype "power_in"))
    (pad "A4" smd roundrect (at -2.4 -3.5) (size 0.6 1.15) (layers "F.Cu" "F.Paste" "F.Mask") (roundrect_rratio 0.25)
      (net 266 "/Debug and JTAG/USBB_VBUS") (pinfunction "VBUS") (pintype "passive"))
    (pad "A5" smd roundrect (at -1.25 -3.5) (size 0.3 1.15) (layers "F.Cu" "F.Paste" "F.Mask") (roundrect_rratio 0.25)
      (net 354 "Net-(J8-CC_{1})") (pinfunction "CC_{1}") (pintype "bidirectional"))
    (pad "A6" smd roundrect (at -0.25 -3.5) (size 0.3 1.15) (layers "F.Cu" "F.Paste" "F.Mask") (roundrect_rratio 0.25)
      (net 355 "Net-(J8-D_{A}+)") (pinfunction "D_{A}+") (pintype "bidirectional"))
    (pad "A7" smd roundrect (at 0.248 -3.5) (size 0.3 1.15) (layers "F.Cu" "F.Paste" "F.Mask") (roundrect_rratio 0.25)
      (net 356 "Net-(J8-D_{A}-)") (pinfunction "D_{A}-") (pintype "bidirectional"))
    (pad "A8" smd roundrect (at 1.249 -3.5) (size 0.3 1.15) (layers "F.Cu" "F.Paste" "F.Mask") (roundrect_rratio 0.25)
      (net 357 "unconnected-(J8-SBU_{1}-PadA8)") (pinfunction "SBU_{1}") (pintype "bidirectional+no_connect"))
    (pad "A9" smd roundrect (at 2.398 -3.5) (size 0.6 1.15) (layers "F.Cu" "F.Paste" "F.Mask") (roundrect_rratio 0.25)
      (net 266 "/Debug and JTAG/USBB_VBUS") (pinfunction "VBUS") (pintype "passive"))
    (pad "A12" smd roundrect (at 3.2 -3.5) (size 0.6 1.15) (layers "F.Cu" "F.Paste" "F.Mask") (roundrect_rratio 0.25)
      (net 1 "GND") (pinfunction "GND") (pintype "passive"))
    (pad "B1" smd roundrect (at 3.2 -3.5) (size 0.6 1.15) (layers "F.Cu" "F.Paste" "F.Mask") (roundrect_rratio 0.25)
      (net 1 "GND") (pinfunction "GND") (pintype "passive"))
    (pad "B4" smd roundrect (at 2.398 -3.5) (size 0.6 1.15) (layers "F.Cu" "F.Paste" "F.Mask") (roundrect_rratio 0.25)
      (net 266 "/Debug and JTAG/USBB_VBUS") (pinfunction "VBUS") (pintype "passive"))
    (pad "B5" smd roundrect (at 1.749 -3.5) (size 0.3 1.15) (layers "F.Cu" "F.Paste" "F.Mask") (roundrect_rratio 0.25)
      (net 358 "Net-(J8-CC_{2})") (pinfunction "CC_{2}") (pintype "bidirectional"))
    (pad "B6" smd roundrect (at 0.748 -3.5) (size 0.3 1.15) (layers "F.Cu" "F.Paste" "F.Mask") (roundrect_rratio 0.25)
      (net 355 "Net-(J8-D_{A}+)") (pinfunction "D_{B}+") (pintype "bidirectional"))
    (pad "B7" smd roundrect (at -0.75 -3.5) (size 0.3 1.15) (layers "F.Cu" "F.Paste" "F.Mask") (roundrect_rratio 0.25)
      (net 356 "Net-(J8-D_{A}-)") (pinfunction "D_{B}-") (pintype "bidirectional"))
    (pad "B8" smd roundrect (at -1.75 -3.5) (size 0.3 1.15) (layers "F.Cu" "F.Paste" "F.Mask") (roundrect_rratio 0.25)
      (net 359 "unconnected-(J8-SBU_{2}-PadB8)") (pinfunction "SBU_{2}") (pintype "bidirectional+no_connect"))
    (pad "B9" smd roundrect (at -2.4 -3.5) (size 0.6 1.15) (layers "F.Cu" "F.Paste" "F.Mask") (roundrect_rratio 0.25)
      (net 266 "/Debug and JTAG/USBB_VBUS") (pinfunction "VBUS") (pintype "passive"))
    (pad "B12" smd roundrect (at -3.202 -3.5) (size 0.6 1.15) (layers "F.Cu" "F.Paste" "F.Mask") (roundrect_rratio 0.25)
      (net 1 "GND") (pinfunction "GND") (pintype "passive"))
    (pad "SH" thru_hole oval (at -4.321 -2.926) (size 1.05 2.1) (drill oval 0.6 1.7) (layers "*.Cu" "*.Mask")
      (net 318 "SH_DOWN") (pinfunction "SH") (pintype "passive"))
    (pad "SH" thru_hole oval (at -4.321 1.255) (size 1 2) (drill oval 0.6 1.4) (layers "*.Cu" "*.Mask")
      (net 318 "SH_DOWN") (pinfunction "SH") (pintype "passive"))
    (pad "SH" thru_hole oval (at 4.32 -2.926) (size 1.05 2.1) (drill oval 0.6 1.7) (layers "*.Cu" "*.Mask")
      (net 318 "SH_DOWN") (pinfunction "SH") (pintype "passive"))
    (pad "SH" thru_hole oval (at 4.32 1.255) (size 1 2) (drill oval 0.6 1.4) (layers "*.Cu" "*.Mask")
      (net 318 "SH_DOWN") (pinfunction "SH") (pintype "passive"))
  )

  (footprint "kria-k26-devboard-footprints:R_0402_1005Metric" (layer "F.Cu")
    (at 87.285 116.81 180)
    (descr "Resistor SMD 0402")
    (tags "resistor SMD 0402")
    (property "Author" "Antmicro")
    (property "License" "Apache-2.0")
    (property "MPN" "CR0402-FX-4700GLF")
    (property "Manufacturer" "Bourns")
    (property "Sheetfile" "k26_som.kicad_sch")
    (property "Sheetname" "Xilinx K26 SOM")
    (property "Tolerance" "1%")
    (property "Val" "470R")
    (property "ki_description" "470R resistor in 0402 package with 1% tolerance")
    (attr smd)
    (fp_text reference "R79" (at 0.81 5.32 180) (layer "F.SilkS")
        (effects (font (size 0.7 0.7) (thickness 0.15)) (justify left bottom))
    )
    (fp_text value "R_470R_0402" (at 0 1.4 180) (layer "F.Fab") hide
        (effects (font (size 0.7 0.7) (thickness 0.15)) (justify left bottom))
    )
    (fp_text user "Author: Antmicro" (at -0.95 4.169 180) (layer "F.Fab") hide
        (effects (font (size 0.7 0.7) (thickness 0.15)) (justify left bottom))
    )
    (fp_text user "License: Apache-2.0" (at -0.95 5.169 180) (layer "F.Fab") hide
        (effects (font (size 0.7 0.7) (thickness 0.15)) (justify left bottom))
    )
    (fp_text user "${REFERENCE}" (at -0.95 3.168 180) (layer "F.Fab") hide
        (effects (font (size 0.7 0.7) (thickness 0.15)) (justify left bottom))
    )
    (fp_rect (start -0.93 -0.47) (end 0.93 0.47)
      (stroke (width 0.05) (type solid)) (fill none) (layer "F.CrtYd"))
    (fp_rect (start -0.5 -0.25) (end 0.5 0.25)
      (stroke (width 0.15) (type solid)) (fill none) (layer "F.Fab"))
    (pad "1" smd roundrect (at -0.485 0 180) (size 0.59 0.64) (layers "F.Cu" "F.Paste" "F.Mask") (roundrect_rratio 0.25)
      (net 5 "/Xilinx K26 SOM/MODE3_C2M") (pintype "passive"))
    (pad "2" smd roundrect (at 0.485 0 180) (size 0.59 0.64) (layers "F.Cu" "F.Paste" "F.Mask") (roundrect_rratio 0.25)
      (net 1 "GND") (pintype "passive"))
  )

  (footprint "kria-k26-devboard-footprints:C_0402_1005Metric" (layer "F.Cu")
    (at 111.6 143.59 180)
    (descr "Capacitor SMD 0402")
    (tags "capacitor SMD 0402")
    (property "Author" "Antmicro")
    (property "Dielectric" "X5R")
    (property "License" "Apache-2.0")
    (property "MPN" "GRM155R61H104KE14D")
    (property "Manufacturer" "Murata")
    (property "Sheetfile" "reset.kicad_sch")
    (property "Sheetname" "Reset logic")
    (property "Val" "100n")
    (property "Voltage" "50V")
    (property "ki_description" " ")
    (attr smd)
    (fp_text reference "C139" (at -0.86 -0.45 180) (layer "F.SilkS")
        (effects (font (size 0.7 0.7) (thickness 0.15)) (justify left bottom))
    )
    (fp_text value "C_100n_0402" (at 0 1.4 180) (layer "F.Fab") hide
        (effects (font (size 0.7 0.7) (thickness 0.15)) (justify left bottom))
    )
    (fp_text user "Author: Antmicro" (at -0.932 4.17 180) (layer "F.Fab") hide
        (effects (font (size 0.7 0.7) (thickness 0.15)) (justify left bottom))
    )
    (fp_text user "${REFERENCE}" (at -0.932 3.168 180) (layer "F.Fab") hide
        (effects (font (size 0.7 0.7) (thickness 0.15)) (justify left bottom))
    )
    (fp_text user "License: Apache-2.0" (at -0.932 5.17 180) (layer "F.Fab") hide
        (effects (font (size 0.7 0.7) (thickness 0.15)) (justify left bottom))
    )
    (fp_rect (start -0.9659 -0.481258) (end 0.9649 0.458742)
      (stroke (width 0.05) (type solid)) (fill none) (layer "F.CrtYd"))
    (fp_line (start -0.499 -0.25) (end 0.499 -0.25)
      (stroke (width 0.15) (type solid)) (layer "F.Fab"))
    (fp_line (start -0.499 0.248) (end -0.499 -0.25)
      (stroke (width 0.15) (type solid)) (layer "F.Fab"))
    (fp_line (start 0.499 -0.25) (end 0.499 0.248)
      (stroke (width 0.15) (type solid)) (layer "F.Fab"))
    (fp_line (start 0.499 0.248) (end -0.499 0.248)
      (stroke (width 0.15) (type solid)) (layer "F.Fab"))
    (pad "1" smd roundrect (at -0.484 0 180) (size 0.59 0.64) (layers "F.Cu" "F.Paste" "F.Mask") (roundrect_rratio 0.25)
      (net 15 "PS_3V3") (pintype "passive"))
    (pad "2" smd roundrect (at 0.484 0 180) (size 0.59 0.64) (layers "F.Cu" "F.Paste" "F.Mask") (roundrect_rratio 0.25)
      (net 1 "GND") (pintype "passive"))
  )

  (footprint "kria-k26-devboard-footprints:R_0402_1005Metric" (layer "F.Cu")
    (at 127.2 118.5 180)
    (descr "Resistor SMD 0402")
    (tags "resistor SMD 0402")
    (property "Author" "Antmicro")
    (property "License" "Apache-2.0")
    (property "MPN" "CR0402-FX-1002GLF")
    (property "Manufacturer" "Bourns")
    (property "Sheetfile" "pcie-m2-key-e.kicad_sch")
    (property "Sheetname" "PCIE M2 key E ")
    (property "Tolerance" "1%")
    (property "Val" "10k")
    (property "ki_description" "10k resistor in 0402 package with 1% tolerance")
    (attr smd)
    (fp_text reference "R153" (at 1.45 -1.35 180) (layer "F.SilkS")
        (effects (font (size 0.7 0.7) (thickness 0.15)) (justify left bottom))
    )
    (fp_text value "R_10k_0402" (at 0 1.4 180) (layer "F.Fab") hide
        (effects (font (size 0.7 0.7) (thickness 0.15)) (justify left bottom))
    )
    (fp_text user "Author: Antmicro" (at -0.95 4.169 180) (layer "F.Fab") hide
        (effects (font (size 0.7 0.7) (thickness 0.15)) (justify left bottom))
    )
    (fp_text user "${REFERENCE}" (at -0.95 3.168 180) (layer "F.Fab") hide
        (effects (font (size 0.7 0.7) (thickness 0.15)) (justify left bottom))
    )
    (fp_text user "License: Apache-2.0" (at -0.95 5.169 180) (layer "F.Fab") hide
        (effects (font (size 0.7 0.7) (thickness 0.15)) (justify left bottom))
    )
    (fp_rect (start -0.93 -0.47) (end 0.93 0.47)
      (stroke (width 0.05) (type solid)) (fill none) (layer "F.CrtYd"))
    (fp_rect (start -0.5 -0.25) (end 0.5 0.25)
      (stroke (width 0.15) (type solid)) (fill none) (layer "F.Fab"))
    (pad "1" smd roundrect (at -0.485 0 180) (size 0.59 0.64) (layers "F.Cu" "F.Paste" "F.Mask") (roundrect_rratio 0.25)
      (net 15 "PS_3V3") (pintype "passive"))
    (pad "2" smd roundrect (at 0.485 0 180) (size 0.59 0.64) (layers "F.Cu" "F.Paste" "F.Mask") (roundrect_rratio 0.25)
      (net 221 "/PCIE M2 key E /~{M2_PERST}") (pintype "passive"))
  )

  (footprint "kria-k26-devboard-footprints:SOT-563" (layer "F.Cu")
    (at 132.58 74.22 90)
    (property "Author" "Antmicro")
    (property "License" "Apache-2.0")
    (property "MPN" "82400152")
    (property "Manufacturer" "Würth Elektronik")
    (property "Sheetfile" "usb.kicad_sch")
    (property "Sheetname" "USB")
    (property "ki_description" "TVS diode")
    (property "ki_keywords" "SMT, DIODE, IC, ESD, TVS")
    (attr smd)
    (fp_text reference "U21" (at -2.07 -1.09 180) (layer "F.SilkS")
        (effects (font (size 0.7 0.7) (thickness 0.15)) (justify left bottom))
    )
    (fp_text value "82400152" (at 0 2 90) (layer "F.Fab") hide
        (effects (font (size 0.7 0.7) (thickness 0.15)) (justify left bottom))
    )
    (fp_text user "Author: Antmicro" (at -1.299 6.124 90) (layer "F.Fab") hide
        (effects (font (size 0.7 0.7) (thickness 0.15)) (justify left bottom))
    )
    (fp_text user "${REFERENCE}" (at -1.299 7.323 90) (layer "F.Fab") hide
        (effects (font (size 0.7 0.7) (thickness 0.15)) (justify left bottom))
    )
    (fp_text user "License: Apache-2.0" (at -1.299 4.924 90) (layer "F.Fab") hide
        (effects (font (size 0.7 0.7) (thickness 0.15)) (justify left bottom))
    )
    (fp_line (start -0.778 0.776) (end -0.778 0.949)
      (stroke (width 0.15) (type solid)) (layer "F.SilkS"))
    (fp_line (start -0.778 0.949) (end -0.424 0.949)
      (stroke (width 0.15) (type solid)) (layer "F.SilkS"))
    (fp_line (start -0.499 -0.974) (end -0.724 -0.778)
      (stroke (width 0.15) (type solid)) (layer "F.SilkS"))
    (fp_line (start 0.776 -0.974) (end 0.526 -0.974)
      (stroke (width 0.15) (type solid)) (layer "F.SilkS"))
    (fp_line (start 0.776 -0.974) (end 0.776 -0.778)
      (stroke (width 0.15) (type solid)) (layer "F.SilkS"))
    (fp_line (start 0.776 0.776) (end 0.776 0.972)
      (stroke (width 0.15) (type solid)) (layer "F.SilkS"))
    (fp_line (start 0.776 0.972) (end 0.526 0.972)
      (stroke (width 0.15) (type solid)) (layer "F.SilkS"))
    (fp_circle (center -0.903 -0.999) (end -0.952 -0.95)
      (stroke (width 0.15) (type solid)) (fill solid) (layer "F.SilkS"))
    (fp_rect (start 1.19 -1.12) (end -1.2 1.1)
      (stroke (width 0.05) (type solid)) (fill none) (layer "F.CrtYd"))
    (fp_line (start -0.653 -0.678) (end -0.653 0.847)
      (stroke (width 0.15) (type solid)) (layer "F.Fab"))
    (fp_line (start -0.453 -0.849) (end -0.653 -0.678)
      (stroke (width 0.15) (type solid)) (layer "F.Fab"))
    (fp_line (start -0.453 -0.849) (end 0.651 -0.849)
      (stroke (width 0.15) (type solid)) (layer "F.Fab"))
    (fp_line (start 0.651 -0.849) (end 0.651 0.847)
      (stroke (width 0.15) (type solid)) (layer "F.Fab"))
    (fp_line (start 0.651 0.847) (end -0.653 0.847)
      (stroke (width 0.15) (type solid)) (layer "F.Fab"))
    (pad "1" smd roundrect (at -0.749 -0.499) (size 0.3 0.6) (layers "F.Cu" "F.Paste" "F.Mask") (roundrect_rratio 0.25)
      (net 70 "/USB/USB2_P") (pintype "passive"))
    (pad "2" smd roundrect (at -0.749 0.001) (size 0.3 0.6) (layers "F.Cu" "F.Paste" "F.Mask") (roundrect_rratio 0.25)
      (net 1 "GND") (pintype "passive"))
    (pad "3" smd roundrect (at -0.749 0.497) (size 0.3 0.6) (layers "F.Cu" "F.Paste" "F.Mask") (roundrect_rratio 0.25)
      (net 69 "/USB/USB2_N") (pintype "passive"))
    (pad "4" smd roundrect (at 0.747 0.497) (size 0.3 0.6) (layers "F.Cu" "F.Paste" "F.Mask") (roundrect_rratio 0.25)
      (net 288 "/USB/USB2_TVS_N") (pintype "passive"))
    (pad "5" smd roundrect (at 0.747 0.001) (size 0.3 0.6) (layers "F.Cu" "F.Paste" "F.Mask") (roundrect_rratio 0.25)
      (net 85 "/USB/USB2_VBUS") (pintype "passive"))
    (pad "6" smd roundrect (at 0.747 -0.499) (size 0.3 0.6) (layers "F.Cu" "F.Paste" "F.Mask") (roundrect_rratio 0.25)
      (net 289 "/USB/USB2_TVS_P") (pintype "passive"))
  )

  (footprint "kria-k26-devboard-footprints:R_0402_1005Metric" (layer "F.Cu")
    (at 124.725 97.404)
    (descr "Resistor SMD 0402")
    (tags "resistor SMD 0402")
    (property "Author" "Antmicro")
    (property "License" "Apache-2.0")
    (property "MPN" "CR0402-FX-8061GLF")
    (property "Manufacturer" "Bourns")
    (property "Sheetfile" "usb.kicad_sch")
    (property "Sheetname" "USB")
    (property "Tolerance" "1%")
    (property "Val" "8k06")
    (property "ki_description" "8k06 resistor in 0402 package with 1% tolerance")
    (attr smd)
    (fp_text reference "R65" (at -1.095 -0.604) (layer "F.SilkS")
        (effects (font (size 0.7 0.7) (thickness 0.15)) (justify left bottom))
    )
    (fp_text value "R_8k06_0402" (at 0 1.4) (layer "F.Fab") hide
        (effects (font (size 0.7 0.7) (thickness 0.15)) (justify left bottom))
    )
    (fp_text user "${REFERENCE}" (at -0.95 3.168) (layer "F.Fab") hide
        (effects (font (size 0.7 0.7) (thickness 0.15)) (justify left bottom))
    )
    (fp_text user "Author: Antmicro" (at -0.95 4.169) (layer "F.Fab") hide
        (effects (font (size 0.7 0.7) (thickness 0.15)) (justify left bottom))
    )
    (fp_text user "License: Apache-2.0" (at -0.95 5.169) (layer "F.Fab") hide
        (effects (font (size 0.7 0.7) (thickness 0.15)) (justify left bottom))
    )
    (fp_rect (start -0.93 -0.47) (end 0.93 0.47)
      (stroke (width 0.05) (type solid)) (fill none) (layer "F.CrtYd"))
    (fp_rect (start -0.5 -0.25) (end 0.5 0.25)
      (stroke (width 0.15) (type solid)) (fill none) (layer "F.Fab"))
    (pad "1" smd roundrect (at -0.485 0) (size 0.59 0.64) (layers "F.Cu" "F.Paste" "F.Mask") (roundrect_rratio 0.25)
      (net 668 "Net-(U23-RBIAS)") (pintype "passive"))
    (pad "2" smd roundrect (at 0.485 0) (size 0.59 0.64) (layers "F.Cu" "F.Paste" "F.Mask") (roundrect_rratio 0.25)
      (net 1 "GND") (pintype "passive"))
  )

  (footprint "kria-k26-devboard-footprints:TP_SMD_0.75mm" (layer "F.Cu")
    (at 189.975 137.5)
    (property "Author" "Antmicro")
    (property "License" "Apache-2.0")
    (property "MPN" "")
    (property "Manufacturer" "")
    (property "Sheetfile" "dc-dc-conventers.kicad_sch")
    (property "Sheetname" "DC/DC conventers")
    (property "ki_description" "Test Point 0.75mm")
    (attr exclude_from_pos_files)
    (fp_text reference "TP42" (at 0.325 7.53 90) (layer "F.SilkS")
        (effects (font (size 0.7 0.7) (thickness 0.15)) (justify left bottom))
    )
    (fp_text value "TP_0.75mm_SMD" (at 0 1.2) (layer "F.Fab") hide
        (effects (font (size 0.7 0.7) (thickness 0.15)) (justify left bottom))
    )
    (fp_text user "Author: Antmicro" (at -0.4 3.901) (layer "F.Fab") hide
        (effects (font (size 0.7 0.7) (thickness 0.15)) (justify left bottom))
    )
    (fp_text user "${REFERENCE}" (at -0.4 2.7) (layer "F.Fab") hide
        (effects (font (size 0.7 0.7) (thickness 0.15)) (justify left bottom))
    )
    (fp_text user "License: Apache-2.0" (at -0.4 5.101) (layer "F.Fab") hide
        (effects (font (size 0.7 0.7) (thickness 0.15)) (justify left bottom))
    )
    (pad "1" smd circle (at 0 0) (size 0.75 0.75) (layers "F.Cu" "F.Mask")
      (net 771 "/Power Supply/DC/DC conventers/PL_1V2_OUT") (pinfunction "1") (pintype "passive"))
  )

  (footprint "kria-k26-devboard-footprints:C_2220_5650Metric" (layer "F.Cu")
    (at 176.95 82.95 90)
    (descr "Capacitor SMD 2220")
    (tags "capacitor SMD 2220")
    (property "Author" "Antmicro")
    (property "Dielectric" "")
    (property "License" "Apache-2.0")
    (property "MPN" "C5750X7S2A226M280KB")
    (property "Manufacturer" "TDK")
    (property "Sheetfile" "PoE.kicad_sch")
    (property "Sheetname" "PoE")
    (property "Val" "22u/100V")
    (property "Voltage" "")
    (property "ki_description" " ")
    (attr smd)
    (fp_text reference "C173" (at -1.4 -15.89 90) (layer "F.SilkS")
        (effects (font (size 0.7 0.7) (thickness 0.15)) (justify left bottom))
    )
    (fp_text value "C_22u_100V_2220" (at 0 3.9 90) (layer "F.Fab") hide
        (effects (font (size 0.7 0.7) (thickness 0.15)) (justify left bottom))
    )
    (fp_text user "${REFERENCE}" (at -3.7 5.9 90) (layer "F.Fab") hide
        (effects (font (size 0.7 0.7) (thickness 0.15)) (justify left bottom))
    )
    (fp_text user "License: Apache-2.0" (at -3.7 6.9 90) (layer "F.Fab") hide
        (effects (font (size 0.7 0.7) (thickness 0.15)) (justify left bottom))
    )
    (fp_text user "Author: Antmicro" (at -3.7 7.9 90) (layer "F.Fab") hide
        (effects (font (size 0.7 0.7) (thickness 0.15)) (justify left bottom))
    )
    (fp_line (start -1.415 -2.61) (end 1.415 -2.61)
      (stroke (width 0.15) (type solid)) (layer "F.SilkS"))
    (fp_line (start -1.415 2.61) (end 1.415 2.61)
      (stroke (width 0.15) (type solid)) (layer "F.SilkS"))
    (fp_rect (start -3.7 -2.95) (end 3.7 2.95)
      (stroke (width 0.05) (type solid)) (fill none) (layer "F.CrtYd"))
    (fp_rect (start -2.85 -2.5) (end 2.85 2.5)
      (stroke (width 0.15) (type solid)) (fill none) (layer "F.Fab"))
    (pad "1" smd roundrect (at -2.55 0 90) (size 1.8 5.4) (layers "F.Cu" "F.Paste" "F.Mask") (roundrect_rratio 0.138889)
      (net 9 "/Power Supply/PoE/VDD_POE_IN") (pintype "passive"))
    (pad "2" smd roundrect (at 2.55 0 90) (size 1.8 5.4) (layers "F.Cu" "F.Paste" "F.Mask") (roundrect_rratio 0.138889)
      (net 11 "GNDD") (pintype "passive"))
  )

  (footprint "kria-k26-devboard-footprints:TP_SMD_0.75mm" (layer "F.Cu")
    (at 141.325 64.35)
    (property "Author" "Antmicro")
    (property "License" "Apache-2.0")
    (property "MPN" "")
    (property "Manufacturer" "")
    (property "Sheetfile" "usbc-socket.kicad_sch")
    (property "Sheetname" "USB-C socket")
    (property "ki_description" "Test Point 0.75mm")
    (attr exclude_from_pos_files)
    (fp_text reference "TP44" (at -1.345 -0.45) (layer "F.SilkS")
        (effects (font (size 0.7 0.7) (thickness 0.15)) (justify left bottom))
    )
    (fp_text value "TP_0.75mm_SMD" (at 0 1.2) (layer "F.Fab") hide
        (effects (font (size 0.7 0.7) (thickness 0.15)) (justify left bottom))
    )
    (fp_text user "${REFERENCE}" (at -0.4 2.7) (layer "F.Fab") hide
        (effects (font (size 0.7 0.7) (thickness 0.15)) (justify left bottom))
    )
    (fp_text user "Author: Antmicro" (at -0.4 3.901) (layer "F.Fab") hide
        (effects (font (size 0.7 0.7) (thickness 0.15)) (justify left bottom))
    )
    (fp_text user "License: Apache-2.0" (at -0.4 5.101) (layer "F.Fab") hide
        (effects (font (size 0.7 0.7) (thickness 0.15)) (justify left bottom))
    )
    (pad "1" smd circle (at 0 0) (size 0.75 0.75) (layers "F.Cu" "F.Mask")
      (net 228 "/Power Supply/Supply ORing/PD_VBUS") (pinfunction "1") (pintype "passive"))
  )

  (footprint "kria-k26-devboard-footprints:R_Array_4x0201_Panasonic_EXB18V" (layer "F.Cu")
    (at 97.7457 118.0032 -90)
    (property "Author" "Antmicro")
    (property "License" "Apache-2.0")
    (property "MPN" "EXB-18V330JX")
    (property "Manufacturer" "Panasonic")
    (property "Sheetfile" "sd-3-card.kicad_sch")
    (property "Sheetname" "SD 3.0 card")
    (property "Val" "R_4x33R_0201")
    (attr smd)
    (fp_text reference "R15" (at 3.0068 -0.4143 90) (layer "F.SilkS")
        (effects (font (size 0.7 0.7) (thickness 0.15)) (justify left bottom))
    )
    (fp_text value "R_4x33R_0201_array" (at -1.1 1.8 -90) (layer "F.Fab") hide
        (effects (font (size 0.7 0.7) (thickness 0.15)) (justify left bottom))
    )
    (fp_text user "Author: Antmicro" (at -1.051 4.599 -90) (layer "F.Fab") hide
        (effects (font (size 0.7 0.7) (thickness 0.15)) (justify left bottom))
    )
    (fp_text user "License: Apache-2.0" (at -1.051 6 -90) (layer "F.Fab") hide
        (effects (font (size 0.7 0.7) (thickness 0.15)) (justify left bottom))
    )
    (fp_text user "${REFERENCE}" (at -1.051 3.2 -90) (layer "F.Fab") hide
        (effects (font (size 0.7 0.7) (thickness 0.15)) (justify left bottom))
    )
    (fp_line (start -0.8 -0.45) (end -0.8 0.45)
      (stroke (width 0.12) (type solid)) (layer "F.SilkS"))
    (fp_line (start 0.8 -0.45) (end 0.8 0.45)
      (stroke (width 0.12) (type solid)) (layer "F.SilkS"))
    (fp_rect (start -0.898 -0.66) (end 0.898 0.65)
      (stroke (width 0.05) (type solid)) (fill none) (layer "F.CrtYd"))
    (pad "1" smd roundrect (at -0.6 0.298 270) (size 0.2 0.4) (layers "F.Cu" "F.Paste" "F.Mask") (roundrect_rratio 0.25)
      (net 115 "/SD 3.0 card/MIO49") (pinfunction "R1.1") (pintype "passive"))
    (pad "2" smd roundrect (at -0.202 0.298 270) (size 0.2 0.4) (layers "F.Cu" "F.Paste" "F.Mask") (roundrect_rratio 0.25)
      (net 114 "/SD 3.0 card/MIO48") (pinfunction "R2.1") (pintype "passive"))
    (pad "3" smd roundrect (at 0.2 0.298 270) (size 0.2 0.4) (layers "F.Cu" "F.Paste" "F.Mask") (roundrect_rratio 0.25)
      (net 113 "/SD 3.0 card/MIO47") (pinfunction "R3.1") (pintype "passive"))
    (pad "4" smd roundrect (at 0.598 0.298 270) (size 0.2 0.4) (layers "F.Cu" "F.Paste" "F.Mask") (roundrect_rratio 0.25)
      (net 118 "/SD 3.0 card/MIO46") (pinfunction "R4.1") (pintype "passive"))
    (pad "5" smd roundrect (at 0.598 -0.3 270) (size 0.2 0.4) (layers "F.Cu" "F.Paste" "F.Mask") (roundrect_rratio 0.25)
      (net 638 "Net-(R15-R4.2)") (pinfunction "R4.2") (pintype "passive"))
    (pad "6" smd roundrect (at 0.2 -0.3 270) (size 0.2 0.4) (layers "F.Cu" "F.Paste" "F.Mask") (roundrect_rratio 0.25)
      (net 639 "Net-(R15-R3.2)") (pinfunction "R3.2") (pintype "passive"))
    (pad "7" smd roundrect (at -0.202 -0.3 270) (size 0.2 0.4) (layers "F.Cu" "F.Paste" "F.Mask") (roundrect_rratio 0.25)
      (net 640 "Net-(R15-R2.2)") (pinfunction "R2.2") (pintype "passive"))
    (pad "8" smd roundrect (at -0.6 -0.3 270) (size 0.2 0.4) (layers "F.Cu" "F.Paste" "F.Mask") (roundrect_rratio 0.25)
      (net 641 "Net-(R15-R1.2)") (pinfunction "R1.2") (pintype "passive"))
  )

  (footprint "kria-k26-devboard-footprints:LED_0603_1608Metric_G" (layer "F.Cu")
    (at 183.36 78.17 180)
    (descr "LED SMD 0603 Green")
    (tags "LED SMD 0603 Green")
    (property "Author" "Antmicro")
    (property "Color" "Green")
    (property "License" "Apache-2.0")
    (property "MPN" "LG L29K-G2J1-24-Z")
    (property "Manufacturer" "OSRAM")
    (property "Sheetfile" "PoE.kicad_sch")
    (property "Sheetname" "PoE")
    (property "ki_description" "LED, Green, SMT, 0603, 20 mA, 2.1 V, 570 nm")
    (property "ki_keywords" "0603, SMT, DIODE, SEMICONDUCTOR, UNICOLOR")
    (attr smd)
    (fp_text reference "D11" (at -2.04 1.12 90) (layer "F.SilkS")
        (effects (font (size 0.7 0.7) (thickness 0.15)) (justify right bottom))
    )
    (fp_text value "LED_G_0603_LG_L29K-G2J1-24-Z" (at 0 1.6) (layer "F.Fab") hide
        (effects (font (size 0.7 0.7) (thickness 0.15)) (justify right bottom))
    )
    (fp_text user "License: Apache-2.0" (at -1.31 5.769) (layer "F.Fab") hide
        (effects (font (size 0.7 0.7) (thickness 0.15)) (justify right bottom))
    )
    (fp_text user "${REFERENCE}" (at -1.31 3.769) (layer "F.Fab") hide
        (effects (font (size 0.7 0.7) (thickness 0.15)) (justify right bottom))
    )
    (fp_text user "Author: Antmicro" (at -1.31 4.769) (layer "F.Fab") hide
        (effects (font (size 0.7 0.7) (thickness 0.15)) (justify right bottom))
    )
    (fp_line (start -0.27 -0.35) (end 0.27 -0.35)
      (stroke (width 0.15) (type solid)) (layer "F.SilkS"))
    (fp_line (start -0.27 0.351) (end 0.27 0.351)
      (stroke (width 0.15) (type solid)) (layer "F.SilkS"))
    (fp_line (start -0.106328 -0.200008) (end -0.106328 0.199992)
      (stroke (width 0.1) (type solid)) (layer "F.SilkS"))
    (fp_line (start -0.106328 -0.200008) (end 0.093672 -0.000008)
      (stroke (width 0.1) (type solid)) (layer "F.SilkS"))
    (fp_line (start -0.106328 -0.000008) (end -0.29 0)
      (stroke (width 0.1) (type solid)) (layer "F.SilkS"))
    (fp_line (start 0.093672 -0.200008) (end 0.093672 0.199992)
      (stroke (width 0.1) (type solid)) (layer "F.SilkS"))
    (fp_line (start 0.093672 -0.000008) (end -0.106328 0.199992)
      (stroke (width 0.1) (type solid)) (layer "F.SilkS"))
    (fp_line (start 0.093672 -0.000008) (end 0.293672 -0.000008)
      (stroke (width 0.1) (type solid)) (layer "F.SilkS"))
    (fp_line (start 1.25 0.32) (end 1.25 -0.32)
      (stroke (width 0.15) (type solid)) (layer "F.SilkS"))
    (fp_rect (start 1.26 0.65) (end -1.26 -0.65)
      (stroke (width 0.05) (type solid)) (fill none) (layer "F.CrtYd"))
    (fp_line (start -0.599 0) (end -0.201 0)
      (stroke (width 0.15) (type solid)) (layer "F.Fab"))
    (fp_line (start -0.201 -0.2) (end -0.201 0)
      (stroke (width 0.15) (type solid)) (layer "F.Fab"))
    (fp_line (start -0.201 0) (end -0.201 0.202)
      (stroke (width 0.15) (type solid)) (layer "F.Fab"))
    (fp_line (start -0.201 0.202) (end 0.101 0)
      (stroke (width 0.15) (type solid)) (layer "F.Fab"))
    (fp_line (start 0.101 0) (end -0.201 -0.2)
      (stroke (width 0.15) (type solid)) (layer "F.Fab"))
    (fp_line (start 0.199 -0.2) (end 0.199 -0.1)
      (stroke (width 0.15) (type solid)) (layer "F.Fab"))
    (fp_line (start 0.199 0) (end 0.597 0)
      (stroke (width 0.15) (type solid)) (layer "F.Fab"))
    (fp_line (start 0.199 0.202) (end 0.199 -0.1)
      (stroke (width 0.15) (type solid)) (layer "F.Fab"))
    (fp_rect (start -0.848 -0.4) (end 0.85 0.402)
      (stroke (width 0.15) (type solid)) (fill none) (layer "F.Fab"))
    (pad "1" smd rect (at -0.75 0) (size 0.8 0.8) (layers "F.Cu" "F.Paste" "F.Mask")
      (net 7 "Net-(D11-Pad1)") (pintype "passive"))
    (pad "2" smd rect (at 0.75 0) (size 0.8 0.8) (layers "F.Cu" "F.Paste" "F.Mask")
      (net 11 "GNDD") (pinfunction "2") (pintype "passive"))
  )

  (footprint "kria-k26-devboard-footprints:C_0402_1005Metric" (layer "F.Cu")
    (at 87.23 102.2 180)
    (descr "Capacitor SMD 0402")
    (tags "capacitor SMD 0402")
    (property "Author" "Antmicro")
    (property "Dielectric" "X5R")
    (property "License" "Apache-2.0")
    (property "MPN" "GRM155R61H104KE14D")
    (property "Manufacturer" "Murata")
    (property "Sheetfile" "k26_som.kicad_sch")
    (property "Sheetname" "Xilinx K26 SOM")
    (property "Val" "100n")
    (property "Voltage" "50V")
    (property "ki_description" " ")
    (attr smd)
    (fp_text reference "C118" (at 3.7 -0.34 180) (layer "F.SilkS")
        (effects (font (size 0.7 0.7) (thickness 0.15)) (justify left bottom))
    )
    (fp_text value "C_100n_0402" (at 0 1.4 180) (layer "F.Fab") hide
        (effects (font (size 0.7 0.7) (thickness 0.15)) (justify left bottom))
    )
    (fp_text user "License: Apache-2.0" (at -0.932 5.17 180) (layer "F.Fab") hide
        (effects (font (size 0.7 0.7) (thickness 0.15)) (justify left bottom))
    )
    (fp_text user "Author: Antmicro" (at -0.932 4.17 180) (layer "F.Fab") hide
        (effects (font (size 0.7 0.7) (thickness 0.15)) (justify left bottom))
    )
    (fp_text user "${REFERENCE}" (at -0.932 3.168 180) (layer "F.Fab") hide
        (effects (font (size 0.7 0.7) (thickness 0.15)) (justify left bottom))
    )
    (fp_rect (start -0.94 -0.47) (end 0.94 0.47)
      (stroke (width 0.05) (type solid)) (fill none) (layer "F.CrtYd"))
    (fp_rect (start -0.499 -0.249) (end 0.499 0.249)
      (stroke (width 0.15) (type solid)) (fill none) (layer "F.Fab"))
    (pad "1" smd roundrect (at -0.484 0 180) (size 0.59 0.64) (layers "F.Cu" "F.Paste" "F.Mask") (roundrect_rratio 0.25)
      (net 8 "SOM_5V0") (pintype "passive"))
    (pad "2" smd roundrect (at 0.484 0 180) (size 0.59 0.64) (layers "F.Cu" "F.Paste" "F.Mask") (roundrect_rratio 0.25)
      (net 1 "GND") (pintype "passive"))
  )

  (footprint "kria-k26-devboard-footprints:C_0402_1005Metric" (layer "F.Cu")
    (at 87.23 101.2 180)
    (descr "Capacitor SMD 0402")
    (tags "capacitor SMD 0402")
    (property "Author" "Antmicro")
    (property "Dielectric" "")
    (property "License" "Apache-2.0")
    (property "MPN" "C1005X6S1A105K050BC")
    (property "Manufacturer" "TDK")
    (property "Sheetfile" "k26_som.kicad_sch")
    (property "Sheetname" "Xilinx K26 SOM")
    (property "Val" "1u")
    (property "Voltage" "")
    (property "ki_description" " ")
    (attr smd)
    (fp_text reference "C117" (at 3.7 -0.34 180) (layer "F.SilkS")
        (effects (font (size 0.7 0.7) (thickness 0.15)) (justify left bottom))
    )
    (fp_text value "C_1u_0402" (at 0 1.4 180) (layer "F.Fab") hide
        (effects (font (size 0.7 0.7) (thickness 0.15)) (justify left bottom))
    )
    (fp_text user "Author: Antmicro" (at -0.932 4.17 180) (layer "F.Fab") hide
        (effects (font (size 0.7 0.7) (thickness 0.15)) (justify left bottom))
    )
    (fp_text user "${REFERENCE}" (at -0.932 3.168 180) (layer "F.Fab") hide
        (effects (font (size 0.7 0.7) (thickness 0.15)) (justify left bottom))
    )
    (fp_text user "License: Apache-2.0" (at -0.932 5.17 180) (layer "F.Fab") hide
        (effects (font (size 0.7 0.7) (thickness 0.15)) (justify left bottom))
    )
    (fp_rect (start -0.94 -0.47) (end 0.94 0.47)
      (stroke (width 0.05) (type solid)) (fill none) (layer "F.CrtYd"))
    (fp_rect (start -0.499 -0.249) (end 0.499 0.249)
      (stroke (width 0.15) (type solid)) (fill none) (layer "F.Fab"))
    (pad "1" smd roundrect (at -0.484 0 180) (size 0.59 0.64) (layers "F.Cu" "F.Paste" "F.Mask") (roundrect_rratio 0.25)
      (net 8 "SOM_5V0") (pintype "passive"))
    (pad "2" smd roundrect (at 0.484 0 180) (size 0.59 0.64) (layers "F.Cu" "F.Paste" "F.Mask") (roundrect_rratio 0.25)
      (net 1 "GND") (pintype "passive"))
  )

  (footprint "kria-k26-devboard-footprints:C_0805_2012Metric" (layer "F.Cu")
    (at 86.2 99.65 180)
    (descr "Capacitor SMD 0805")
    (tags "capacitor SMD 0805")
    (property "Author" "Antmicro")
    (property "Dielectric" "")
    (property "License" "Apache-2.0")
    (property "MPN" "C0805C476M9PACTU")
    (property "Manufacturer" "KEMET")
    (property "Sheetfile" "k26_som.kicad_sch")
    (property "Sheetname" "Xilinx K26 SOM")
    (property "Val" "47u")
    (property "Voltage" "")
    (property "ki_description" " ")
    (attr smd)
    (fp_text reference "C115" (at 4.55 -0.36 180) (layer "F.SilkS")
        (effects (font (size 0.7 0.7) (thickness 0.15)) (justify left bottom))
    )
    (fp_text value "C_47u_0805" (at 0 1.947 180) (layer "F.Fab") hide
        (effects (font (size 0.7 0.7) (thickness 0.15)) (justify left bottom))
    )
    (fp_text user "License: Apache-2.0" (at -1.9 4.947 180) (layer "F.Fab") hide
        (effects (font (size 0.7 0.7) (thickness 0.15)) (justify left bottom))
    )
    (fp_text user "${REFERENCE}" (at -1.9 3.947 180) (layer "F.Fab") hide
        (effects (font (size 0.7 0.7) (thickness 0.15)) (justify left bottom))
    )
    (fp_text user "Author: Antmicro" (at -1.9 5.947 180) (layer "F.Fab") hide
        (effects (font (size 0.7 0.7) (thickness 0.15)) (justify left bottom))
    )
    (fp_line (start -0.3 -0.8) (end 0.3 -0.8)
      (stroke (width 0.15) (type solid)) (layer "F.SilkS"))
    (fp_line (start -0.3 0.8) (end 0.3 0.8)
      (stroke (width 0.15) (type solid)) (layer "F.SilkS"))
    (fp_rect (start -1.9 -0.93) (end 1.9 0.93)
      (stroke (width 0.05) (type solid)) (fill none) (layer "F.CrtYd"))
    (fp_rect (start -0.95 -0.675) (end 0.95 0.675)
      (stroke (width 0.15) (type solid)) (fill none) (layer "F.Fab"))
    (pad "1" smd rect (at -1.05 0 180) (size 1.2 1.2) (layers "F.Cu" "F.Paste" "F.Mask")
      (net 8 "SOM_5V0") (pintype "passive"))
    (pad "2" smd rect (at 1.05 0 180) (size 1.2 1.2) (layers "F.Cu" "F.Paste" "F.Mask")
      (net 1 "GND") (pintype "passive"))
  )

  (footprint "kria-k26-devboard-footprints:TP_SMD_0.75mm" (layer "F.Cu")
    (at 113.393934 91.550736)
    (property "Author" "Antmicro")
    (property "License" "Apache-2.0")
    (property "MPN" "")
    (property "Manufacturer" "")
    (property "Sheetfile" "usb.kicad_sch")
    (property "Sheetname" "USB")
    (property "ki_description" "Test Point 0.75mm")
    (attr exclude_from_pos_files)
    (fp_text reference "TP11" (at 0.246066 2.999264 90) (layer "F.SilkS")
        (effects (font (size 0.7 0.7) (thickness 0.15)) (justify left bottom))
    )
    (fp_text value "TP_0.75mm_SMD" (at 0 1.2) (layer "F.Fab") hide
        (effects (font (size 0.7 0.7) (thickness 0.15)) (justify left bottom))
    )
    (fp_text user "License: Apache-2.0" (at -0.4 5.101) (layer "F.Fab") hide
        (effects (font (size 0.7 0.7) (thickness 0.15)) (justify left bottom))
    )
    (fp_text user "${REFERENCE}" (at -0.4 2.7) (layer "F.Fab") hide
        (effects (font (size 0.7 0.7) (thickness 0.15)) (justify left bottom))
    )
    (fp_text user "Author: Antmicro" (at -0.4 3.901) (layer "F.Fab") hide
        (effects (font (size 0.7 0.7) (thickness 0.15)) (justify left bottom))
    )
    (pad "1" smd circle (at 0 0) (size 0.75 0.75) (layers "F.Cu" "F.Mask")
      (net 666 "Net-(U17-PF26)") (pinfunction "1") (pintype "passive"))
  )

  (footprint "kria-k26-devboard-footprints:TP_SMD_0.75mm" (layer "F.Cu")
    (at 114.118153 92.276086)
    (property "Author" "Antmicro")
    (property "License" "Apache-2.0")
    (property "MPN" "")
    (property "Manufacturer" "")
    (property "Sheetfile" "usb.kicad_sch")
    (property "Sheetname" "USB")
    (property "ki_description" "Test Point 0.75mm")
    (attr exclude_from_pos_files)
    (fp_text reference "TP12" (at 0.441847 2.993914 90) (layer "F.SilkS")
        (effects (font (size 0.7 0.7) (thickness 0.15)) (justify left bottom))
    )
    (fp_text value "TP_0.75mm_SMD" (at 0 1.2) (layer "F.Fab") hide
        (effects (font (size 0.7 0.7) (thickness 0.15)) (justify left bottom))
    )
    (fp_text user "${REFERENCE}" (at -0.4 2.7) (layer "F.Fab") hide
        (effects (font (size 0.7 0.7) (thickness 0.15)) (justify left bottom))
    )
    (fp_text user "License: Apache-2.0" (at -0.4 5.101) (layer "F.Fab") hide
        (effects (font (size 0.7 0.7) (thickness 0.15)) (justify left bottom))
    )
    (fp_text user "Author: Antmicro" (at -0.4 3.901) (layer "F.Fab") hide
        (effects (font (size 0.7 0.7) (thickness 0.15)) (justify left bottom))
    )
    (pad "1" smd circle (at 0 0) (size 0.75 0.75) (layers "F.Cu" "F.Mask")
      (net 667 "Net-(U17-PF27)") (pinfunction "1") (pintype "passive"))
  )

  (footprint "kria-k26-devboard-footprints:PinHeader_1x2_P2.54mm_Drill1.02mm" (layer "F.Cu")
    (at 109.35 83.9 180)
    (property "Author" "Antmicro")
    (property "License" "Apache-2.0")
    (property "MPN" "M20-9990246")
    (property "Manufacturer" "Harwin")
    (property "Sheetfile" "k26_som.kicad_sch")
    (property "Sheetname" "Xilinx K26 SOM")
    (attr through_hole)
    (fp_text reference "J6" (at 5.46 -1.37 180) (layer "F.SilkS")
        (effects (font (size 0.7 0.7) (thickness 0.15)) (justify left bottom))
    )
    (fp_text value "PinHeader_1x2_P2.54mm_Drill1.02mm" (at 0 2.6 180) (layer "F.Fab") hide
        (effects (font (size 0.7 0.7) (thickness 0.15)) (justify left bottom))
    )
    (fp_text user "${REFERENCE}" (at -1.6 7 180) (layer "F.Fab") hide
        (effects (font (size 0.7 0.7) (thickness 0.15)) (justify left bottom))
    )
    (fp_text user "Author: Antmicro" (at -1.6 4.6 180) (layer "F.Fab") hide
        (effects (font (size 0.7 0.7) (thickness 0.15)) (justify left bottom))
    )
    (fp_text user "License: Apache-2.0" (at -1.6 5.8 180) (layer "F.Fab") hide
        (effects (font (size 0.7 0.7) (thickness 0.15)) (justify left bottom))
    )
    (fp_line (start -1.401 -1.401) (end -1.401 -0.902)
      (stroke (width 0.15) (type solid)) (layer "F.SilkS"))
    (fp_line (start -1.401 -1.401) (end -0.902 -1.401)
      (stroke (width 0.15) (type solid)) (layer "F.SilkS"))
    (fp_line (start -1.401 1.398) (end -1.401 0.9)
      (stroke (width 0.15) (type solid)) (layer "F.SilkS"))
    (fp_line (start -1.401 1.398) (end -0.902 1.398)
      (stroke (width 0.15) (type solid)) (layer "F.SilkS"))
    (fp_line (start 3.898 -1.401) (end 3.398 -1.401)
      (stroke (width 0.15) (type solid)) (layer "F.SilkS"))
    (fp_line (start 3.898 -1.401) (end 3.898 -0.902)
      (stroke (width 0.15) (type solid)) (layer "F.SilkS"))
    (fp_line (start 3.898 1.398) (end 3.398 1.398)
      (stroke (width 0.15) (type solid)) (layer "F.SilkS"))
    (fp_line (start 3.898 1.398) (end 3.898 0.9)
      (stroke (width 0.15) (type solid)) (layer "F.SilkS"))
    (fp_rect (start -1.51 -1.51) (end 4.01 1.51)
      (stroke (width 0.05) (type solid)) (fill none) (layer "F.CrtYd"))
    (fp_line (start -1.27 -1.27) (end 3.809 -1.27)
      (stroke (width 0.15) (type solid)) (layer "F.Fab"))
    (fp_line (start -1.27 1.269) (end -1.27 -1.27)
      (stroke (width 0.15) (type solid)) (layer "F.Fab"))
    (fp_line (start -1.27 1.269) (end 3.809 1.269)
      (stroke (width 0.15) (type solid)) (layer "F.Fab"))
    (fp_line (start 3.809 1.269) (end 3.809 -1.27)
      (stroke (width 0.15) (type solid)) (layer "F.Fab"))
    (pad "1" thru_hole rect (at 0 0 180) (size 1.7 1.7) (drill 1.02) (layers "*.Cu" "*.Mask")
      (net 245 "Net-(FB2-Pad2)") (pintype "passive"))
    (pad "2" thru_hole circle (at 2.539 0.02 180) (size 1.7 1.7) (drill 1.02) (layers "*.Cu" "*.Mask")
      (net 244 "Net-(FB1-Pad2)") (pintype "passive"))
  )

  (footprint "kria-k26-devboard-footprints:R_0402_1005Metric" (layer "F.Cu")
    (at 97.725 116.6)
    (descr "Resistor SMD 0402")
    (tags "resistor SMD 0402")
    (property "Author" "Antmicro")
    (property "License" "Apache-2.0")
    (property "MPN" "CR0402-FX-33R0GLF")
    (property "Manufacturer" "Bourns")
    (property "Sheetfile" "sd-3-card.kicad_sch")
    (property "Sheetname" "SD 3.0 card")
    (property "Tolerance" "1%")
    (property "Val" "33R")
    (property "ki_description" "33R resistor in 0402 package with 1% tolerance")
    (attr smd)
    (fp_text reference "R13" (at -1.115 -1.5) (layer "F.SilkS")
        (effects (font (size 0.7 0.7) (thickness 0.15)) (justify left bottom))
    )
    (fp_text value "R_33R_0402" (at 0 1.4) (layer "F.Fab") hide
        (effects (font (size 0.7 0.7) (thickness 0.15)) (justify left bottom))
    )
    (fp_text user "License: Apache-2.0" (at -0.95 5.169) (layer "F.Fab") hide
        (effects (font (size 0.7 0.7) (thickness 0.15)) (justify left bottom))
    )
    (fp_text user "Author: Antmicro" (at -0.95 4.169) (layer "F.Fab") hide
        (effects (font (size 0.7 0.7) (thickness 0.15)) (justify left bottom))
    )
    (fp_text user "${REFERENCE}" (at -0.95 3.168) (layer "F.Fab") hide
        (effects (font (size 0.7 0.7) (thickness 0.15)) (justify left bottom))
    )
    (fp_rect (start -0.93 -0.47) (end 0.93 0.47)
      (stroke (width 0.05) (type solid)) (fill none) (layer "F.CrtYd"))
    (fp_rect (start -0.5 -0.25) (end 0.5 0.25)
      (stroke (width 0.15) (type solid)) (fill none) (layer "F.Fab"))
    (pad "1" smd roundrect (at -0.485 0) (size 0.59 0.64) (layers "F.Cu" "F.Paste" "F.Mask") (roundrect_rratio 0.25)
      (net 110 "/SD 3.0 card/MIO50") (pintype "passive"))
    (pad "2" smd roundrect (at 0.485 0) (size 0.59 0.64) (layers "F.Cu" "F.Paste" "F.Mask") (roundrect_rratio 0.25)
      (net 435 "Net-(U5-CMD_{A})") (pintype "passive"))
  )

  (footprint "kria-k26-devboard-footprints:R_0402_1005Metric" (layer "F.Cu")
    (at 97.725 115.65)
    (descr "Resistor SMD 0402")
    (tags "resistor SMD 0402")
    (property "Author" "Antmicro")
    (property "License" "Apache-2.0")
    (property "MPN" "CR0402-FX-33R0GLF")
    (property "Manufacturer" "Bourns")
    (property "Sheetfile" "sd-3-card.kicad_sch")
    (property "Sheetname" "SD 3.0 card")
    (property "Tolerance" "1%")
    (property "Val" "33R")
    (property "ki_description" "33R resistor in 0402 package with 1% tolerance")
    (attr smd)
    (fp_text reference "R14" (at -1.115 -1.5) (layer "F.SilkS")
        (effects (font (size 0.7 0.7) (thickness 0.15)) (justify left bottom))
    )
    (fp_text value "R_33R_0402" (at 0 1.4) (layer "F.Fab") hide
        (effects (font (size 0.7 0.7) (thickness 0.15)) (justify left bottom))
    )
    (fp_text user "Author: Antmicro" (at -0.95 4.169) (layer "F.Fab") hide
        (effects (font (size 0.7 0.7) (thickness 0.15)) (justify left bottom))
    )
    (fp_text user "${REFERENCE}" (at -0.95 3.168) (layer "F.Fab") hide
        (effects (font (size 0.7 0.7) (thickness 0.15)) (justify left bottom))
    )
    (fp_text user "License: Apache-2.0" (at -0.95 5.169) (layer "F.Fab") hide
        (effects (font (size 0.7 0.7) (thickness 0.15)) (justify left bottom))
    )
    (fp_rect (start -0.93 -0.47) (end 0.93 0.47)
      (stroke (width 0.05) (type solid)) (fill none) (layer "F.CrtYd"))
    (fp_rect (start -0.5 -0.25) (end 0.5 0.25)
      (stroke (width 0.15) (type solid)) (fill none) (layer "F.Fab"))
    (pad "1" smd roundrect (at -0.485 0) (size 0.59 0.64) (layers "F.Cu" "F.Paste" "F.Mask") (roundrect_rratio 0.25)
      (net 123 "/SD 3.0 card/MIO51") (pintype "passive"))
    (pad "2" smd roundrect (at 0.485 0) (size 0.59 0.64) (layers "F.Cu" "F.Paste" "F.Mask") (roundrect_rratio 0.25)
      (net 436 "Net-(U5-CLK_{A})") (pintype "passive"))
  )

  (footprint "kria-k26-devboard-footprints:USB-A_Receptacle_Amphenol_GSB3112311HR" (layer "F.Cu")
    (at 133.25 65.73 180)
    (descr "Ethernet Amphenol")
    (tags "Ethernet Amphenol")
    (property "Author" "Antmicro")
    (property "License" "Apache-2.0")
    (property "MPN" "GSB3112311HR")
    (property "Manufacturer" "Amphenol")
    (property "Sheetfile" "usb.kicad_sch")
    (property "Sheetname" "USB")
    (property "ki_description" "USB-A (USB TYPE-A) USB 3.2 Gen 1 (USB 3.1 Gen 1, Superspeed (USB 3.0)) Receptacle Connector 5 Position Through Hole, Right Angle")
    (property "ki_keywords" "USB, CONNECTOR, THT, HORIZONTAL")
    (attr through_hole)
    (fp_text reference "U24" (at -3.04 -6.99) (layer "F.SilkS")
        (effects (font (size 0.7 0.7) (thickness 0.15)) (justify right bottom))
    )
    (fp_text value "USB-A_Amphenol_GSB3112311HR" (at 0 14.8) (layer "F.Fab") hide
        (effects (font (size 0.7 0.7) (thickness 0.15)) (justify right bottom))
    )
    (fp_text user "Author: Antmicro" (at -4.6 17.501) (layer "F.Fab") hide
        (effects (font (size 0.7 0.7) (thickness 0.15)) (justify right bottom))
    )
    (fp_text user "${REFERENCE}" (at -4.6 16.3) (layer "F.Fab") hide
        (effects (font (size 0.7 0.7) (thickness 0.15)) (justify right bottom))
    )
    (fp_text user "License: Apache-2.0" (at -4.6 18.7) (layer "F.Fab") hide
        (effects (font (size 0.7 0.7) (thickness 0.15)) (justify right bottom))
    )
    (fp_rect (start -4.6 13.711) (end 11.7 -6.6)
      (stroke (width 0.05) (type solid)) (fill none) (layer "F.CrtYd"))
    (pad "1" thru_hole circle (at 0 0 270) (size 1.1 1.1) (drill 0.7) (layers "*.Cu" "*.Mask")
      (net 64 "/USB/USB1_VBUS") (pinfunction "VBUS") (pintype "passive"))
    (pad "2" thru_hole circle (at 2.499 0 270) (size 1.1 1.1) (drill 0.7) (layers "*.Cu" "*.Mask")
      (net 286 "/USB/USB1_TVS_N") (pinfunction "D-") (pintype "bidirectional"))
    (pad "3" thru_hole circle (at 4.498 0 270) (size 1.1 1.1) (drill 0.7) (layers "*.Cu" "*.Mask")
      (net 287 "/USB/USB1_TVS_P") (pinfunction "D+") (pintype "bidirectional"))
    (pad "4" thru_hole circle (at 6.999 0 270) (size 1.1 1.1) (drill 0.7) (layers "*.Cu" "*.Mask")
      (net 1 "GND") (pinfunction "GND") (pintype "power_in"))
    (pad "5" thru_hole circle (at 7.499 -1.499 270) (size 1.1 1.1) (drill 0.7) (layers "*.Cu" "*.Mask")
      (net 83 "/USB/USB1_RX_N") (pinfunction "SSRX-") (pintype "bidirectional"))
    (pad "6" thru_hole circle (at 5.499 -1.499 270) (size 1.1 1.1) (drill 0.7) (layers "*.Cu" "*.Mask")
      (net 84 "/USB/USB1_RX_P") (pinfunction "SSRX+") (pintype "bidirectional"))
    (pad "7" thru_hole circle (at 3.499 -1.499 270) (size 1.1 1.1) (drill 0.7) (layers "*.Cu" "*.Mask")
      (net 1 "GND") (pinfunction "GND_DRAIN") (pintype "power_in"))
    (pad "8" thru_hole circle (at 1.499 -1.499 270) (size 1.1 1.1) (drill 0.7) (layers "*.Cu" "*.Mask")
      (net 278 "/USB/USB1_TX_C_N") (pinfunction "SSTX-") (pintype "bidirectional"))
    (pad "9" thru_hole circle (at -0.5 -1.499 270) (size 1.1 1.1) (drill 0.7) (layers "*.Cu" "*.Mask")
      (net 279 "/USB/USB1_TX_C_P") (pinfunction "SSTX+") (pintype "bidirectional"))
    (pad "10" thru_hole circle (at 0 -3.2 270) (size 1.1 1.1) (drill 0.7) (layers "*.Cu" "*.Mask")
      (net 85 "/USB/USB2_VBUS") (pinfunction "VBUS") (pintype "power_in"))
    (pad "11" thru_hole circle (at 2.499 -3.2 270) (size 1.1 1.1) (drill 0.7) (layers "*.Cu" "*.Mask")
      (net 288 "/USB/USB2_TVS_N") (pinfunction "D-") (pintype "bidirectional"))
    (pad "12" thru_hole circle (at 4.498 -3.2 270) (size 1.1 1.1) (drill 0.7) (layers "*.Cu" "*.Mask")
      (net 289 "/USB/USB2_TVS_P") (pinfunction "D+") (pintype "bidirectional"))
    (pad "13" thru_hole circle (at 6.999 -3.2 270) (size 1.1 1.1) (drill 0.7) (layers "*.Cu" "*.Mask")
      (net 1 "GND") (pinfunction "GND") (pintype "power_in"))
    (pad "14" thru_hole circle (at 7.499 -4.7 270) (size 1.1 1.1) (drill 0.7) (layers "*.Cu" "*.Mask")
      (net 81 "/USB/USB2_RX_N") (pinfunction "SSRX-") (pintype "bidirectional"))
    (pad "15" thru_hole circle (at 5.499 -4.7 270) (size 1.1 1.1) (drill 0.7) (layers "*.Cu" "*.Mask")
      (net 82 "/USB/USB2_RX_P") (pinfunction "SSRX+") (pintype "bidirectional"))
    (pad "16" thru_hole circle (at 3.499 -4.7 270) (size 1.1 1.1) (drill 0.7) (layers "*.Cu" "*.Mask")
      (net 1 "GND") (pinfunction "GND_DRAIN") (pintype "power_in"))
    (pad "17" thru_hole circle (at 1.499 -4.7 270) (size 1.1 1.1) (drill 0.7) (layers "*.Cu" "*.Mask")
      (net 280 "/USB/USB2_TX_C_N") (pinfunction "SSTX-") (pintype "bidirectional"))
    (pad "18" thru_hole circle (at -0.5 -4.7 270) (size 1.1 1.1) (drill 0.7) (layers "*.Cu" "*.Mask")
      (net 281 "/USB/USB2_TX_C_P") (pinfunction "SSTX+") (pintype "bidirectional"))
    (pad "SH" thru_hole circle (at -3.072 -3.68 270) (size 2.9 2.9) (drill 2.3) (layers "*.Cu" "*.Mask")
      (net 319 "SH_UP") (pinfunction "SHIELD") (pintype "passive"))
    (pad "SH" thru_hole circle (at -3.072 2 270) (size 2.9 2.9) (drill 2.3) (layers "*.Cu" "*.Mask")
      (net 319 "SH_UP") (pinfunction "SHIELD") (pintype "passive"))
    (pad "SH" thru_hole circle (at 10.07 -3.68 270) (size 2.9 2.9) (drill 2.3) (layers "*.Cu" "*.Mask")
      (net 319 "SH_UP") (pinfunction "SHIELD") (pintype "passive"))
    (pad "SH" thru_hole circle (at 10.169 2 270) (size 2.9 2.9) (drill 2.3) (layers "*.Cu" "*.Mask")
      (net 319 "SH_UP") (pinfunction "SHIELD") (pintype "passive"))
  )

  (footprint "kria-k26-devboard-footprints:SW_KMR211NGLFS_SMD" (layer "F.Cu")
    (at 95.2 150.1)
    (property "Author" "Antmicro")
    (property "License" "Apache-2.0")
    (property "MPN" "KMR211NGLFS")
    (property "Manufacturer" "C&K")
    (property "Sheetfile" "reset.kicad_sch")
    (property "Sheetname" "Reset logic")
    (property "ki_description" "Tactile Switch, KMR 2 Series, Top Actuated, Surface Mount, Oval Button, 120 gf, 50mA at 32VDC")
    (property "ki_keywords" "VERTICAL, SMT, SWITCH, MECHANICAL, TACTILE")
    (attr smd)
    (fp_text reference "S1" (at -3.88 -1.22) (layer "F.SilkS")
        (effects (font (size 0.7 0.7) (thickness 0.15)) (justify left bottom))
    )
    (fp_text value "SW_KMR211NGLFS_SMD" (at -3 3) (layer "F.Fab") hide
        (effects (font (size 0.7 0.7) (thickness 0.15)) (justify left bottom))
    )
    (fp_text user "License: Apache-2.0" (at -3 6.75) (layer "F.Fab") hide
        (effects (font (size 0.7 0.7) (thickness 0.15)) (justify left bottom))
    )
    (fp_text user "Author: Antmicro" (at -3 5.5) (layer "F.Fab") hide
        (effects (font (size 0.7 0.7) (thickness 0.15)) (justify left bottom))
    )
    (fp_text user "${REFERENCE}" (at -3 4.25) (layer "F.Fab") hide
        (effects (font (size 0.7 0.7) (thickness 0.15)) (justify left bottom))
    )
    (fp_line (start -2.1 -1.6) (end -2.1 -1.499)
      (stroke (width 0.15) (type solid)) (layer "F.SilkS"))
    (fp_line (start -2.1 1.601) (end -2.1 1.48)
      (stroke (width 0.15) (type solid)) (layer "F.SilkS"))
    (fp_line (start 2.101 -1.6) (end -2.1 -1.6)
      (stroke (width 0.15) (type solid)) (layer "F.SilkS"))
    (fp_line (start 2.101 -1.58) (end 2.101 -1.459)
      (stroke (width 0.15) (type solid)) (layer "F.SilkS"))
    (fp_line (start 2.101 1.601) (end -2.1 1.601)
      (stroke (width 0.15) (type solid)) (layer "F.SilkS"))
    (fp_line (start 2.101 1.601) (end 2.101 1.48)
      (stroke (width 0.15) (type solid)) (layer "F.SilkS"))
    (fp_rect (start 2.751 1.75) (end -2.748 -1.749)
      (stroke (width 0.05) (type solid)) (fill none) (layer "F.CrtYd"))
    (fp_line (start -2.1 -1.6) (end -2.1 1.601)
      (stroke (width 0.15) (type solid)) (layer "F.Fab"))
    (fp_line (start -2.1 1.601) (end 2.101 1.601)
      (stroke (width 0.15) (type solid)) (layer "F.Fab"))
    (fp_line (start -0.248 -0.8) (end 0.25 -0.8)
      (stroke (width 0.15) (type solid)) (layer "F.Fab"))
    (fp_line (start 0.25 0.802) (end -0.248 0.802)
      (stroke (width 0.15) (type solid)) (layer "F.Fab"))
    (fp_line (start 2.101 -1.6) (end -2.1 -1.6)
      (stroke (width 0.15) (type solid)) (layer "F.Fab"))
    (fp_line (start 2.101 1.601) (end 2.101 -1.6)
      (stroke (width 0.15) (type solid)) (layer "F.Fab"))
    (fp_arc (start -0.248 0.802) (mid -1.050001 0.001) (end -0.248 -0.8)
      (stroke (width 0.15) (type solid)) (layer "F.Fab"))
    (fp_arc (start 0.25 -0.8) (mid 1.051001 0.001) (end 0.25 0.802)
      (stroke (width 0.15) (type solid)) (layer "F.Fab"))
    (pad "1" smd rect (at -2.048 -0.8 180) (size 0.9 1) (layers "F.Cu" "F.Paste" "F.Mask")
      (net 1 "GND") (pinfunction "1") (pintype "passive"))
    (pad "2" smd rect (at 2.05 -0.8 180) (size 0.9 1) (layers "F.Cu" "F.Paste" "F.Mask")
      (net 1 "GND") (pinfunction "2") (pintype "passive"))
    (pad "3" smd rect (at -2.048 0.802 180) (size 0.9 1) (layers "F.Cu" "F.Paste" "F.Mask")
      (net 327 "Net-(D4-PadK)") (pinfunction "3") (pintype "passive"))
    (pad "4" smd rect (at 2.05 0.802 180) (size 0.9 1) (layers "F.Cu" "F.Paste" "F.Mask")
      (net 327 "Net-(D4-PadK)") (pinfunction "4") (pintype "passive"))
  )

  (footprint "kria-k26-devboard-footprints:TP_SMD_0.75mm" (layer "F.Cu")
    (at 111.3 146.5)
    (property "Author" "Antmicro")
    (property "License" "Apache-2.0")
    (property "MPN" "")
    (property "Manufacturer" "")
    (property "Sheetfile" "reset.kicad_sch")
    (property "Sheetname" "Reset logic")
    (property "ki_description" "Test Point 0.75mm")
    (attr exclude_from_pos_files)
    (fp_text reference "TP19" (at 7.33 0.86 90) (layer "F.SilkS")
        (effects (font (size 0.7 0.7) (thickness 0.15)) (justify left bottom))
    )
    (fp_text value "TP_0.75mm_SMD" (at 0 1.2) (layer "F.Fab") hide
        (effects (font (size 0.7 0.7) (thickness 0.15)) (justify left bottom))
    )
    (fp_text user "${REFERENCE}" (at -0.4 2.7) (layer "F.Fab") hide
        (effects (font (size 0.7 0.7) (thickness 0.15)) (justify left bottom))
    )
    (fp_text user "License: Apache-2.0" (at -0.4 5.101) (layer "F.Fab") hide
        (effects (font (size 0.7 0.7) (thickness 0.15)) (justify left bottom))
    )
    (fp_text user "Author: Antmicro" (at -0.4 3.901) (layer "F.Fab") hide
        (effects (font (size 0.7 0.7) (thickness 0.15)) (justify left bottom))
    )
    (pad "1" smd circle (at 0 0) (size 0.75 0.75) (layers "F.Cu" "F.Mask")
      (net 175 "/Reset logic/~{USB_HUB_RESET}") (pinfunction "1") (pintype "passive"))
  )

  (footprint "kria-k26-devboard-footprints:DFN-8-1EP_3x2mm_P0.5mm_EP1.36x1.46mm" (layer "F.Cu")
    (at 104.65 134.65 -90)
    (property "Author" "Antmicro")
    (property "License" "Apache-2.0")
    (property "MPN" "M24C64-FMC6TG")
    (property "Manufacturer" "STMicroelectronics")
    (property "Sheetfile" "i2c.kicad_sch")
    (property "Sheetname" "I2C ")
    (property "ki_description" "EEPROM, 8K x 8bit, Serial I2C (2-Wire), 1 MHz, UFDFPN, 8 Pins")
    (property "ki_keywords" "SMT, MEMORY, IC, STORAGE, I2C")
    (attr smd)
    (fp_text reference "U13" (at 1.1 -2.11 -90) (layer "F.SilkS")
        (effects (font (size 0.7 0.7) (thickness 0.15)) (justify left bottom))
    )
    (fp_text value "M24C64-F_DFN8" (at 0 2.2 -90) (layer "F.Fab")
        (effects (font (size 0.7 0.7) (thickness 0.15)) (justify left bottom))
    )
    (fp_text user "License: Apache-2.0" (at -2.27 6.453 -90) (layer "F.Fab") hide
        (effects (font (size 0.7 0.7) (thickness 0.15)) (justify left bottom))
    )
    (fp_text user "${REFERENCE}" (at -2.27 4.052 -90) (layer "F.Fab") hide
        (effects (font (size 0.7 0.7) (thickness 0.15)) (justify left bottom))
    )
    (fp_text user "Author: Antmicro" (at -2.27 5.253 -90) (layer "F.Fab") hide
        (effects (font (size 0.7 0.7) (thickness 0.15)) (justify left bottom))
    )
    (fp_line (start -1.501 1.111) (end 1.518 1.111)
      (stroke (width 0.15) (type solid)) (layer "F.SilkS"))
    (fp_line (start 1.498 -1.12) (end -1.511 -1.12)
      (stroke (width 0.15) (type solid)) (layer "F.SilkS"))
    (fp_circle (center -1.751 -1.05) (end -1.7 -1.05)
      (stroke (width 0.15) (type solid)) (fill solid) (layer "F.SilkS"))
    (fp_line (start -1.901 -1.262) (end 1.889 -1.262)
      (stroke (width 0.05) (type solid)) (layer "F.CrtYd"))
    (fp_line (start -1.901 1.228) (end -1.901 -1.262)
      (stroke (width 0.05) (type solid)) (layer "F.CrtYd"))
    (fp_line (start 1.889 -1.262) (end 1.889 1.228)
      (stroke (width 0.05) (type solid)) (layer "F.CrtYd"))
    (fp_line (start 1.889 1.228) (end -1.901 1.228)
      (stroke (width 0.05) (type solid)) (layer "F.CrtYd"))
    (fp_line (start -1.501 0.99) (end -1.501 -0.989)
      (stroke (width 0.15) (type solid)) (layer "F.Fab"))
    (fp_line (start 1.498 -0.999) (end -1.491 -0.999)
      (stroke (width 0.15) (type solid)) (layer "F.Fab"))
    (fp_line (start 1.498 -0.999) (end 1.498 0.99)
      (stroke (width 0.15) (type solid)) (layer "F.Fab"))
    (fp_line (start 1.498 0.999) (end -1.501 0.999)
      (stroke (width 0.15) (type solid)) (layer "F.Fab"))
    (pad "1" smd rect (at -1.451 -0.749 180) (size 0.3 0.7) (layers "F.Cu" "F.Paste" "F.Mask")
      (net 15 "PS_3V3") (pinfunction "E0") (pintype "input"))
    (pad "2" smd rect (at -1.451 -0.25 180) (size 0.3 0.7) (layers "F.Cu" "F.Paste" "F.Mask")
      (net 1 "GND") (pinfunction "E1") (pintype "input"))
    (pad "3" smd rect (at -1.451 0.249 180) (size 0.3 0.7) (layers "F.Cu" "F.Paste" "F.Mask")
      (net 1 "GND") (pinfunction "E2") (pintype "input"))
    (pad "4" smd rect (at -1.451 0.75 180) (size 0.3 0.7) (layers "F.Cu" "F.Paste" "F.Mask")
      (net 1 "GND") (pinfunction "VSS") (pintype "power_in"))
    (pad "5" smd rect (at 1.448 0.75 180) (size 0.3 0.7) (layers "F.Cu" "F.Paste" "F.Mask")
      (net 163 "/I2C /I2C_SDA_3V3") (pinfunction "SDA") (pintype "bidirectional"))
    (pad "6" smd rect (at 1.448 0.249 180) (size 0.3 0.7) (layers "F.Cu" "F.Paste" "F.Mask")
      (net 162 "/I2C /I2C_SCK_3V3") (pinfunction "SCL") (pintype "input"))
    (pad "7" smd rect (at 1.448 -0.25 180) (size 0.3 0.7) (layers "F.Cu" "F.Paste" "F.Mask")
      (net 186 "/Debug and JTAG/~{EEPROM_WC}") (pinfunction "~{WC}") (pintype "input"))
    (pad "8" smd rect (at 1.448 -0.749 180) (size 0.3 0.7) (layers "F.Cu" "F.Paste" "F.Mask")
      (net 15 "PS_3V3") (pinfunction "VCC") (pintype "power_in"))
    (pad "9" smd rect (at 0 0 180) (size 1.5 1.7) (layers "F.Cu" "F.Paste" "F.Mask")
      (net 1 "GND") (pinfunction "VSS") (pintype "passive") (solder_paste_margin_ratio -0.1))
  )

  (footprint "kria-k26-devboard-footprints:TP_SMD_0.75mm" (layer "F.Cu")
    (at 185.4 114.8)
    (property "Author" "Antmicro")
    (property "License" "Apache-2.0")
    (property "MPN" "")
    (property "Manufacturer" "")
    (property "Sheetfile" "PoE.kicad_sch")
    (property "Sheetname" "PoE")
    (property "ki_description" "Test Point 0.75mm")
    (attr exclude_from_pos_files)
    (fp_text reference "TP35" (at -2.63 -0.39 180) (layer "F.SilkS")
        (effects (font (size 0.7 0.7) (thickness 0.15)) (justify left bottom))
    )
    (fp_text value "TP_0.75mm_SMD" (at 0 1.2) (layer "F.Fab") hide
        (effects (font (size 0.7 0.7) (thickness 0.15)) (justify left bottom))
    )
    (fp_text user "License: Apache-2.0" (at -0.4 5.101) (layer "F.Fab") hide
        (effects (font (size 0.7 0.7) (thickness 0.15)) (justify left bottom))
    )
    (fp_text user "Author: Antmicro" (at -0.4 3.901) (layer "F.Fab") hide
        (effects (font (size 0.7 0.7) (thickness 0.15)) (justify left bottom))
    )
    (fp_text user "${REFERENCE}" (at -0.4 2.7) (layer "F.Fab") hide
        (effects (font (size 0.7 0.7) (thickness 0.15)) (justify left bottom))
    )
    (pad "1" smd circle (at 0 0) (size 0.75 0.75) (layers "F.Cu" "F.Mask")
      (net 13 "/Power Supply/PoE/POE_12V") (pinfunction "1") (pintype "passive"))
  )

  (footprint "kria-k26-devboard-footprints:TP_SMD_0.75mm" (layer "F.Cu")
    (at 184.6 87.2)
    (property "Author" "Antmicro")
    (property "License" "Apache-2.0")
    (property "MPN" "")
    (property "Manufacturer" "")
    (property "Sheetfile" "PoE.kicad_sch")
    (property "Sheetname" "PoE")
    (property "ki_description" "Test Point 0.75mm")
    (attr exclude_from_pos_files)
    (fp_text reference "TP34" (at 0.3 0.42) (layer "F.SilkS")
        (effects (font (size 0.7 0.7) (thickness 0.15)) (justify left bottom))
    )
    (fp_text value "TP_0.75mm_SMD" (at 0 1.2) (layer "F.Fab") hide
        (effects (font (size 0.7 0.7) (thickness 0.15)) (justify left bottom))
    )
    (fp_text user "License: Apache-2.0" (at -0.4 5.101) (layer "F.Fab") hide
        (effects (font (size 0.7 0.7) (thickness 0.15)) (justify left bottom))
    )
    (fp_text user "Author: Antmicro" (at -0.4 3.901) (layer "F.Fab") hide
        (effects (font (size 0.7 0.7) (thickness 0.15)) (justify left bottom))
    )
    (fp_text user "${REFERENCE}" (at -0.4 2.7) (layer "F.Fab") hide
        (effects (font (size 0.7 0.7) (thickness 0.15)) (justify left bottom))
    )
    (pad "1" smd circle (at 0 0) (size 0.75 0.75) (layers "F.Cu" "F.Mask")
      (net 9 "/Power Supply/PoE/VDD_POE_IN") (pinfunction "1") (pintype "passive"))
  )

  (footprint "kria-k26-devboard-footprints:TP_SMD_0.75mm" (layer "F.Cu")
    (at 151 70.65)
    (property "Author" "Antmicro")
    (property "License" "Apache-2.0")
    (property "MPN" "")
    (property "Manufacturer" "")
    (property "Sheetfile" "usbc-socket.kicad_sch")
    (property "Sheetname" "USB-C socket")
    (property "ki_description" "Test Point 0.75mm")
    (attr exclude_from_pos_files)
    (fp_text reference "TP45" (at -1.98 1.3) (layer "F.SilkS")
        (effects (font (size 0.7 0.7) (thickness 0.15)) (justify left bottom))
    )
    (fp_text value "TP_0.75mm_SMD" (at 0 1.2) (layer "F.Fab") hide
        (effects (font (size 0.7 0.7) (thickness 0.15)) (justify left bottom))
    )
    (fp_text user "Author: Antmicro" (at -0.4 3.901) (layer "F.Fab") hide
        (effects (font (size 0.7 0.7) (thickness 0.15)) (justify left bottom))
    )
    (fp_text user "License: Apache-2.0" (at -0.4 5.101) (layer "F.Fab") hide
        (effects (font (size 0.7 0.7) (thickness 0.15)) (justify left bottom))
    )
    (fp_text user "${REFERENCE}" (at -0.4 2.7) (layer "F.Fab") hide
        (effects (font (size 0.7 0.7) (thickness 0.15)) (justify left bottom))
    )
    (pad "1" smd circle (at 0 0) (size 0.75 0.75) (layers "F.Cu" "F.Mask")
      (net 229 "/Debug and JTAG/PD_EN") (pinfunction "1") (pintype "passive"))
  )

  (footprint "kria-k26-devboard-footprints:SOT-23-3" (layer "F.Cu")
    (at 149.5 65.125 180)
    (property "Author" "Antmicro")
    (property "License" "Apache-2.0")
    (property "MPN" "PJA3441_R1_00001")
    (property "Manufacturer" "Panjit")
    (property "Sheetfile" "usbc-socket.kicad_sch")
    (property "Sheetname" "USB-C socket")
    (property "ki_description" "MOSFET 40V P-Channel Enhancement Mode MOSFET")
    (attr smd)
    (fp_text reference "Q16" (at -0.19 -3.705 90) (layer "F.SilkS")
        (effects (font (size 0.7 0.7) (thickness 0.15)) (justify left bottom))
    )
    (fp_text value "PJA3441" (at -1.9 2.7 180) (layer "F.Fab") hide
        (effects (font (size 0.7 0.7) (thickness 0.15)) (justify left bottom))
    )
    (fp_text user "License: Apache-2.0" (at -1.8 6.8 180) (layer "F.Fab") hide
        (effects (font (size 0.7 0.7) (thickness 0.15)) (justify left bottom))
    )
    (fp_text user "${REFERENCE}" (at -1.837 4 180) (layer "F.Fab") hide
        (effects (font (size 0.7 0.7) (thickness 0.15)) (justify left bottom))
    )
    (fp_text user "Author: Antmicro" (at -1.837 5.3 180) (layer "F.Fab") hide
        (effects (font (size 0.7 0.7) (thickness 0.15)) (justify left bottom))
    )
    (fp_line (start -1.45 -1.35) (end -0.85 -1.35)
      (stroke (width 0.15) (type solid)) (layer "F.SilkS"))
    (fp_line (start -0.85 -1.35) (end -0.7 -1.5)
      (stroke (width 0.15) (type solid)) (layer "F.SilkS"))
    (fp_line (start -0.7 1.5) (end -0.7 1.35)
      (stroke (width 0.15) (type solid)) (layer "F.SilkS"))
    (fp_line (start 0.7 -1.5) (end -0.7 -1.5)
      (stroke (width 0.15) (type solid)) (layer "F.SilkS"))
    (fp_line (start 0.7 -0.4) (end 0.7 -1.5)
      (stroke (width 0.15) (type solid)) (layer "F.SilkS"))
    (fp_line (start 0.7 0.4) (end 0.7 1.5)
      (stroke (width 0.15) (type solid)) (layer "F.SilkS"))
    (fp_line (start 0.7 1.5) (end -0.7 1.5)
      (stroke (width 0.15) (type solid)) (layer "F.SilkS"))
    (fp_line (start -1.75 -0.5) (end -1.75 -1.4)
      (stroke (width 0.05) (type solid)) (layer "F.CrtYd"))
    (fp_line (start -1.75 0.5) (end -0.85 0.5)
      (stroke (width 0.05) (type solid)) (layer "F.CrtYd"))
    (fp_line (start -1.75 1.4) (end -1.75 0.5)
      (stroke (width 0.05) (type solid)) (layer "F.CrtYd"))
    (fp_line (start -0.9 -1.6) (end -0.9 -1.4)
      (stroke (width 0.05) (type solid)) (layer "F.CrtYd"))
    (fp_line (start -0.9 -1.6) (end 0.825 -1.6)
      (stroke (width 0.05) (type solid)) (layer "F.CrtYd"))
    (fp_line (start -0.9 -1.4) (end -1.75 -1.4)
      (stroke (width 0.05) (type solid)) (layer "F.CrtYd"))
    (fp_line (start -0.85 -0.5) (end -1.75 -0.5)
      (stroke (width 0.05) (type solid)) (layer "F.CrtYd"))
    (fp_line (start -0.85 0.5) (end -0.85 -0.5)
      (stroke (width 0.05) (type solid)) (layer "F.CrtYd"))
    (fp_line (start -0.85 1.4) (end -1.75 1.4)
      (stroke (width 0.05) (type solid)) (layer "F.CrtYd"))
    (fp_line (start -0.85 1.65) (end -0.85 1.4)
      (stroke (width 0.05) (type solid)) (layer "F.CrtYd"))
    (fp_line (start 0.825 -1.6) (end 0.825 -0.45)
      (stroke (width 0.05) (type solid)) (layer "F.CrtYd"))
    (fp_line (start 0.825 -0.45) (end 1.75 -0.45)
      (stroke (width 0.05) (type solid)) (layer "F.CrtYd"))
    (fp_line (start 0.85 0.45) (end 0.85 1.65)
      (stroke (width 0.05) (type solid)) (layer "F.CrtYd"))
    (fp_line (start 0.85 1.65) (end -0.85 1.65)
      (stroke (width 0.05) (type solid)) (layer "F.CrtYd"))
    (fp_line (start 1.75 -0.45) (end 1.75 0.45)
      (stroke (width 0.05) (type solid)) (layer "F.CrtYd"))
    (fp_line (start 1.75 0.45) (end 0.85 0.45)
      (stroke (width 0.05) (type solid)) (layer "F.CrtYd"))
    (fp_line (start -0.712 -1.325) (end -0.712 1.523)
      (stroke (width 0.15) (type solid)) (layer "F.Fab"))
    (fp_line (start -0.712 1.519) (end 0.688 1.519)
      (stroke (width 0.15) (type solid)) (layer "F.Fab"))
    (fp_line (start -0.437 -1.526) (end -0.712 -1.325)
      (stroke (width 0.15) (type solid)) (layer "F.Fab"))
    (fp_line (start -0.437 -1.526) (end 0.688 -1.526)
      (stroke (width 0.15) (type solid)) (layer "F.Fab"))
    (fp_line (start 0.688 1.519) (end 0.688 -1.52)
      (stroke (width 0.15) (type solid)) (layer "F.Fab"))
    (pad "1" smd roundrect (at -1.1 -0.951 180) (size 1 0.6) (layers "F.Cu" "F.Paste" "F.Mask") (roundrect_rratio 0.15)
      (net 433 "Net-(Q16-G)") (pinfunction "G") (pintype "bidirectional"))
    (pad "2" smd roundrect (at -1.1 0.949 180) (size 1 0.6) (layers "F.Cu" "F.Paste" "F.Mask") (roundrect_rratio 0.15)
      (net 265 "/Debug and JTAG/USBC_VBUS") (pinfunction "S") (pintype "bidirectional"))
    (pad "3" smd roundrect (at 1.1 -0.0005 180) (size 1 0.6) (layers "F.Cu" "F.Paste" "F.Mask") (roundrect_rratio 0.15)
      (net 228 "/Power Supply/Supply ORing/PD_VBUS") (pinfunction "D") (pintype "bidirectional"))
  )

  (footprint "kria-k26-devboard-footprints:Spacer_Drill4.45mm_H5mm_9774050960R" (layer "F.Cu")
    (at 160.206999 144.4435)
    (property "Author" "Antmicro")
    (property "License" "Apache-2.0")
    (property "MPN" "9774050960R")
    (property "Manufacturer" "Würth Elektronik")
    (property "Sheetfile" "k26_som.kicad_sch")
    (property "Sheetname" "Xilinx K26 SOM")
    (property "ki_description" "Spacer, SMT, Non Stop, Steel, Swage Round, 6 mm x 5 mm, 3.3 mm Internal, WA-SMST Series")
    (property "ki_keywords" "SPACER")
    (clearance 0.6)
    (attr smd)
    (fp_text reference "SP2" (at 0 -3.4) (layer "F.SilkS")
        (effects (font (size 0.7 0.7) (thickness 0.15)) (justify left bottom))
    )
    (fp_text value "Spacer_Drill4.45mm_H5mm_9774050960R" (at 0 4.2) (layer "F.Fab")
        (effects (font (size 0.7 0.7) (thickness 0.15)) (justify left bottom))
    )
    (fp_text user "License: Apache-2.0" (at -3.25 6.2) (layer "F.Fab") hide
        (effects (font (size 0.7 0.7) (thickness 0.15)) (justify left bottom))
    )
    (fp_text user "${REFERENCE}" (at -3.25 7.4) (layer "F.Fab") hide
        (effects (font (size 0.7 0.7) (thickness 0.15)) (justify left bottom))
    )
    (fp_text user "Author: Antmicro" (at -3.25 8.6) (layer "F.Fab") hide
        (effects (font (size 0.7 0.7) (thickness 0.15)) (justify left bottom))
    )
    (fp_circle (center 0 0) (end 3.25 0)
      (stroke (width 0.05) (type solid)) (fill none) (layer "F.CrtYd"))
    (fp_circle (center 0 0) (end 2.564 0)
      (stroke (width 0.15) (type solid)) (fill none) (layer "F.Fab"))
    (pad "1" thru_hole circle (at 0 0) (size 6 6) (drill 4.45) (layers "*.Cu" "*.Mask" "F.Paste")
      (net 1 "GND") (pintype "passive") (solder_paste_margin_ratio -0.05))
  )

  (footprint "kria-k26-devboard-footprints:USON-10_2.5x1mm_P0.5mm" (layer "F.Cu")
    (at 129.752 73.2805 90)
    (descr "USON-10 2.5x1mm_ Pitch 0.5mm")
    (tags "USON-10 2.5x1mm Pitch 0.5mm")
    (property "Author" "Antmicro")
    (property "License" "Apache-2.0")
    (property "MPN" "TPD4E05U06QDQARQ1")
    (property "Manufacturer" "Texas Instruments")
    (property "Sheetfile" "usb.kicad_sch")
    (property "Sheetname" "USB")
    (property "ki_description" "ESD protection")
    (property "ki_keywords" "SMT, DIODE, IC, TVS, ESD")
    (attr smd)
    (fp_text reference "U19" (at 0.018 -1.7 90) (layer "F.SilkS")
        (effects (font (size 0.7 0.7) (thickness 0.15)) (justify left bottom))
    )
    (fp_text value "TPD4E05U06QDQARQ1" (at 0.018 2.499 90) (layer "F.Fab")
        (effects (font (size 0.7 0.7) (thickness 0.15)) (justify left bottom))
    )
    (fp_text user "License: Apache-2.0" (at -0.802 6.9 90) (layer "F.Fab") hide
        (effects (font (size 0.7 0.7) (thickness 0.15)) (justify left bottom))
    )
    (fp_text user "Author: Antmicro" (at -0.802 5.7 90) (layer "F.Fab") hide
        (effects (font (size 0.7 0.7) (thickness 0.15)) (justify left bottom))
    )
    (fp_text user "${REFERENCE}" (at -0.802 4.498 90) (layer "F.Fab") hide
        (effects (font (size 0.7 0.7) (thickness 0.15)) (justify left bottom))
    )
    (fp_line (start 0.498 -1.401) (end -0.5 -1.401)
      (stroke (width 0.15) (type solid)) (layer "F.SilkS"))
    (fp_line (start 0.498 1.398) (end -0.5 1.398)
      (stroke (width 0.15) (type solid)) (layer "F.SilkS"))
    (fp_circle (center -0.68 -1.27) (end -0.63 -1.27)
      (stroke (width 0.15) (type solid)) (fill solid) (layer "F.SilkS"))
    (fp_rect (start -0.8 -1.5) (end 0.8 1.499)
      (stroke (width 0.05) (type solid)) (fill none) (layer "F.CrtYd"))
    (fp_line (start -0.5 -1) (end -0.5 1.249)
      (stroke (width 0.15) (type solid)) (layer "F.Fab"))
    (fp_line (start -0.5 1.249) (end 0.498 1.249)
      (stroke (width 0.15) (type solid)) (layer "F.Fab"))
    (fp_line (start -0.25 -1.25) (end -0.5 -1)
      (stroke (width 0.15) (type solid)) (layer "F.Fab"))
    (fp_line (start 0.498 -1.25) (end -0.25 -1.25)
      (stroke (width 0.15) (type solid)) (layer "F.Fab"))
    (fp_line (start 0.498 -1.25) (end 0.498 1.249)
      (stroke (width 0.15) (type solid)) (layer "F.Fab"))
    (pad "1" smd roundrect (at -0.387 -1) (size 0.25 0.55) (layers "F.Cu" "F.Paste" "F.Mask") (roundrect_rratio 0.25)
      (net 81 "/USB/USB2_RX_N") (pintype "passive"))
    (pad "2" smd roundrect (at -0.387 -0.5) (size 0.25 0.55) (layers "F.Cu" "F.Paste" "F.Mask") (roundrect_rratio 0.25)
      (net 82 "/USB/USB2_RX_P") (pintype "passive"))
    (pad "3" smd roundrect (at -0.387 0) (size 0.4 0.55) (layers "F.Cu" "F.Paste" "F.Mask") (roundrect_rratio 0.25)
      (net 1 "GND") (pintype "power_in"))
    (pad "4" smd roundrect (at -0.387 0.498) (size 0.25 0.55) (layers "F.Cu" "F.Paste" "F.Mask") (roundrect_rratio 0.25)
      (net 280 "/USB/USB2_TX_C_N") (pintype "passive"))
    (pad "5" smd roundrect (at -0.387 0.998) (size 0.25 0.55) (layers "F.Cu" "F.Paste" "F.Mask") (roundrect_rratio 0.25)
      (net 281 "/USB/USB2_TX_C_P") (pintype "passive"))
    (pad "6" smd roundrect (at 0.385 0.998) (size 0.25 0.55) (layers "F.Cu" "F.Paste" "F.Mask") (roundrect_rratio 0.25)
      (net 281 "/USB/USB2_TX_C_P") (pintype "passive"))
    (pad "7" smd roundrect (at 0.385 0.498) (size 0.25 0.55) (layers "F.Cu" "F.Paste" "F.Mask") (roundrect_rratio 0.25)
      (net 280 "/USB/USB2_TX_C_N") (pintype "passive"))
    (pad "8" smd roundrect (at 0.385 0) (size 0.4 0.55) (layers "F.Cu" "F.Paste" "F.Mask") (roundrect_rratio 0.25)
      (net 1 "GND") (pintype "passive"))
    (pad "9" smd roundrect (at 0.385 -0.5) (size 0.25 0.55) (layers "F.Cu" "F.Paste" "F.Mask") (roundrect_rratio 0.25)
      (net 82 "/USB/USB2_RX_P") (pintype "passive"))
    (pad "10" smd roundrect (at 0.385 -1) (size 0.25 0.55) (layers "F.Cu" "F.Paste" "F.Mask") (roundrect_rratio 0.25)
      (net 81 "/USB/USB2_RX_N") (pintype "passive"))
  )

  (footprint "kria-k26-devboard-footprints:TP_SMD_0.75mm" (layer "F.Cu")
    (at 145.55 110.95)
    (property "Author" "Antmicro")
    (property "License" "Apache-2.0")
    (property "MPN" "")
    (property "Manufacturer" "")
    (property "Sheetfile" "debug.kicad_sch")
    (property "Sheetname" "Debug and JTAG")
    (property "ki_description" "Test Point 0.75mm")
    (attr exclude_from_pos_files)
    (fp_text reference "TP29" (at 0.26 1.03) (layer "F.SilkS")
        (effects (font (size 0.7 0.7) (thickness 0.15)) (justify left bottom))
    )
    (fp_text value "TP_0.75mm_SMD" (at 0 1.2) (layer "F.Fab") hide
        (effects (font (size 0.7 0.7) (thickness 0.15)) (justify left bottom))
    )
    (fp_text user "${REFERENCE}" (at -0.4 2.7) (layer "F.Fab") hide
        (effects (font (size 0.7 0.7) (thickness 0.15)) (justify left bottom))
    )
    (fp_text user "License: Apache-2.0" (at -0.4 5.101) (layer "F.Fab") hide
        (effects (font (size 0.7 0.7) (thickness 0.15)) (justify left bottom))
    )
    (fp_text user "Author: Antmicro" (at -0.4 3.901) (layer "F.Fab") hide
        (effects (font (size 0.7 0.7) (thickness 0.15)) (justify left bottom))
    )
    (pad "1" smd circle (at 0 0) (size 0.75 0.75) (layers "F.Cu" "F.Mask")
      (net 136 "/Debug and JTAG/PD1_SVBUS") (pinfunction "1") (pintype "passive"))
  )

  (footprint "kria-k26-devboard-footprints:TP_SMD_0.75mm" (layer "F.Cu")
    (at 135.75 130.1)
    (property "Author" "Antmicro")
    (property "License" "Apache-2.0")
    (property "MPN" "")
    (property "Manufacturer" "")
    (property "Sheetfile" "debug.kicad_sch")
    (property "Sheetname" "Debug and JTAG")
    (property "ki_description" "Test Point 0.75mm")
    (attr exclude_from_pos_files)
    (fp_text reference "TP30" (at -3.02 0.37) (layer "F.SilkS")
        (effects (font (size 0.7 0.7) (thickness 0.15)) (justify left bottom))
    )
    (fp_text value "TP_0.75mm_SMD" (at 0 1.2) (layer "F.Fab") hide
        (effects (font (size 0.7 0.7) (thickness 0.15)) (justify left bottom))
    )
    (fp_text user "${REFERENCE}" (at -0.4 2.7) (layer "F.Fab") hide
        (effects (font (size 0.7 0.7) (thickness 0.15)) (justify left bottom))
    )
    (fp_text user "License: Apache-2.0" (at -0.4 5.101) (layer "F.Fab") hide
        (effects (font (size 0.7 0.7) (thickness 0.15)) (justify left bottom))
    )
    (fp_text user "Author: Antmicro" (at -0.4 3.901) (layer "F.Fab") hide
        (effects (font (size 0.7 0.7) (thickness 0.15)) (justify left bottom))
    )
    (pad "1" smd circle (at 0 0) (size 0.75 0.75) (layers "F.Cu" "F.Mask")
      (net 159 "/Debug and JTAG/~{FTDI_LS_OE}") (pinfunction "1") (pintype "passive"))
  )

  (footprint "kria-k26-devboard-footprints:TP_SMD_0.75mm" (layer "F.Cu")
    (at 135.3 129.08)
    (property "Author" "Antmicro")
    (property "License" "Apache-2.0")
    (property "MPN" "")
    (property "Manufacturer" "")
    (property "Sheetfile" "debug.kicad_sch")
    (property "Sheetname" "Debug and JTAG")
    (property "ki_description" "Test Point 0.75mm")
    (attr exclude_from_pos_files)
    (fp_text reference "TP31" (at -2.93 0.37) (layer "F.SilkS")
        (effects (font (size 0.7 0.7) (thickness 0.15)) (justify left bottom))
    )
    (fp_text value "TP_0.75mm_SMD" (at 0 1.2) (layer "F.Fab") hide
        (effects (font (size 0.7 0.7) (thickness 0.15)) (justify left bottom))
    )
    (fp_text user "Author: Antmicro" (at -0.4 3.901) (layer "F.Fab") hide
        (effects (font (size 0.7 0.7) (thickness 0.15)) (justify left bottom))
    )
    (fp_text user "${REFERENCE}" (at -0.4 2.7) (layer "F.Fab") hide
        (effects (font (size 0.7 0.7) (thickness 0.15)) (justify left bottom))
    )
    (fp_text user "License: Apache-2.0" (at -0.4 5.101) (layer "F.Fab") hide
        (effects (font (size 0.7 0.7) (thickness 0.15)) (justify left bottom))
    )
    (pad "1" smd circle (at 0 0) (size 0.75 0.75) (layers "F.Cu" "F.Mask")
      (net 220 "/Debug and JTAG/CONN_GND") (pinfunction "1") (pintype "passive"))
  )

  (footprint "kria-k26-devboard-footprints:TP_SMD_0.75mm" (layer "F.Cu")
    (at 134.75 124.9508)
    (property "Author" "Antmicro")
    (property "License" "Apache-2.0")
    (property "MPN" "")
    (property "Manufacturer" "")
    (property "Sheetfile" "debug.kicad_sch")
    (property "Sheetname" "Debug and JTAG")
    (property "ki_description" "Test Point 0.75mm")
    (attr exclude_from_pos_files)
    (fp_text reference "TP32" (at -3.02 0.3492) (layer "F.SilkS")
        (effects (font (size 0.7 0.7) (thickness 0.15)) (justify left bottom))
    )
    (fp_text value "TP_0.75mm_SMD" (at 0 1.2) (layer "F.Fab") hide
        (effects (font (size 0.7 0.7) (thickness 0.15)) (justify left bottom))
    )
    (fp_text user "License: Apache-2.0" (at -0.4 5.101) (layer "F.Fab") hide
        (effects (font (size 0.7 0.7) (thickness 0.15)) (justify left bottom))
    )
    (fp_text user "${REFERENCE}" (at -0.4 2.7) (layer "F.Fab") hide
        (effects (font (size 0.7 0.7) (thickness 0.15)) (justify left bottom))
    )
    (fp_text user "Author: Antmicro" (at -0.4 3.901) (layer "F.Fab") hide
        (effects (font (size 0.7 0.7) (thickness 0.15)) (justify left bottom))
    )
    (pad "1" smd circle (at 0 0) (size 0.75 0.75) (layers "F.Cu" "F.Mask")
      (net 160 "/Debug and JTAG/~{LS_OE}") (pinfunction "1") (pintype "passive"))
  )

  (footprint "kria-k26-devboard-footprints:TP_SMD_0.75mm" (layer "F.Cu")
    (at 167.525 137.25)
    (property "Author" "Antmicro")
    (property "License" "Apache-2.0")
    (property "MPN" "")
    (property "Manufacturer" "")
    (property "Sheetfile" "dc-dc-conventers.kicad_sch")
    (property "Sheetname" "DC/DC conventers")
    (property "ki_description" "Test Point 0.75mm")
    (attr exclude_from_pos_files)
    (fp_text reference "TP36" (at -2.965 0.97) (layer "F.SilkS")
        (effects (font (size 0.7 0.7) (thickness 0.15)) (justify left bottom))
    )
    (fp_text value "TP_0.75mm_SMD" (at 0 1.2) (layer "F.Fab") hide
        (effects (font (size 0.7 0.7) (thickness 0.15)) (justify left bottom))
    )
    (fp_text user "${REFERENCE}" (at -0.4 2.7) (layer "F.Fab") hide
        (effects (font (size 0.7 0.7) (thickness 0.15)) (justify left bottom))
    )
    (fp_text user "Author: Antmicro" (at -0.4 3.901) (layer "F.Fab") hide
        (effects (font (size 0.7 0.7) (thickness 0.15)) (justify left bottom))
    )
    (fp_text user "License: Apache-2.0" (at -0.4 5.101) (layer "F.Fab") hide
        (effects (font (size 0.7 0.7) (thickness 0.15)) (justify left bottom))
    )
    (pad "1" smd circle (at 0 0) (size 0.75 0.75) (layers "F.Cu" "F.Mask")
      (net 765 "/Power Supply/DC/DC conventers/PS_3V3_OUT") (pinfunction "1") (pintype "passive"))
  )

  (footprint "kria-k26-devboard-footprints:TP_SMD_0.75mm" (layer "F.Cu")
    (at 138.55 84.85)
    (property "Author" "Antmicro")
    (property "License" "Apache-2.0")
    (property "MPN" "")
    (property "Manufacturer" "")
    (property "Sheetfile" "dc-dc-conventers.kicad_sch")
    (property "Sheetname" "DC/DC conventers")
    (property "ki_description" "Test Point 0.75mm")
    (attr exclude_from_pos_files)
    (fp_text reference "TP37" (at -1.23 -0.43) (layer "F.SilkS")
        (effects (font (size 0.7 0.7) (thickness 0.15)) (justify left bottom))
    )
    (fp_text value "TP_0.75mm_SMD" (at 0 1.2) (layer "F.Fab") hide
        (effects (font (size 0.7 0.7) (thickness 0.15)) (justify left bottom))
    )
    (fp_text user "Author: Antmicro" (at -0.4 3.901) (layer "F.Fab") hide
        (effects (font (size 0.7 0.7) (thickness 0.15)) (justify left bottom))
    )
    (fp_text user "License: Apache-2.0" (at -0.4 5.101) (layer "F.Fab") hide
        (effects (font (size 0.7 0.7) (thickness 0.15)) (justify left bottom))
    )
    (fp_text user "${REFERENCE}" (at -0.4 2.7) (layer "F.Fab") hide
        (effects (font (size 0.7 0.7) (thickness 0.15)) (justify left bottom))
    )
    (pad "1" smd circle (at 0 0) (size 0.75 0.75) (layers "F.Cu" "F.Mask")
      (net 766 "/Power Supply/DC/DC conventers/PS_2V5_OUT") (pinfunction "1") (pintype "passive"))
  )

  (footprint "kria-k26-devboard-footprints:TP_SMD_0.75mm" (layer "F.Cu")
    (at 181.35 139.05)
    (property "Author" "Antmicro")
    (property "License" "Apache-2.0")
    (property "MPN" "")
    (property "Manufacturer" "")
    (property "Sheetfile" "dc-dc-conventers.kicad_sch")
    (property "Sheetname" "DC/DC conventers")
    (property "ki_description" "Test Point 0.75mm")
    (attr exclude_from_pos_files)
    (fp_text reference "TP41" (at -0.83 1.28) (layer "F.SilkS")
        (effects (font (size 0.7 0.7) (thickness 0.15)) (justify left bottom))
    )
    (fp_text value "TP_0.75mm_SMD" (at 0 1.2) (layer "F.Fab") hide
        (effects (font (size 0.7 0.7) (thickness 0.15)) (justify left bottom))
    )
    (fp_text user "${REFERENCE}" (at -0.4 2.7) (layer "F.Fab") hide
        (effects (font (size 0.7 0.7) (thickness 0.15)) (justify left bottom))
    )
    (fp_text user "Author: Antmicro" (at -0.4 3.901) (layer "F.Fab") hide
        (effects (font (size 0.7 0.7) (thickness 0.15)) (justify left bottom))
    )
    (fp_text user "License: Apache-2.0" (at -0.4 5.101) (layer "F.Fab") hide
        (effects (font (size 0.7 0.7) (thickness 0.15)) (justify left bottom))
    )
    (pad "1" smd circle (at 0 0) (size 0.75 0.75) (layers "F.Cu" "F.Mask")
      (net 770 "/Power Supply/DC/DC conventers/PL_3V3_OUT") (pinfunction "1") (pintype "passive"))
  )

  (footprint "kria-k26-devboard-footprints:TP_SMD_0.75mm" (layer "F.Cu")
    (at 185.45 62.7)
    (property "Author" "Antmicro")
    (property "License" "Apache-2.0")
    (property "MPN" "")
    (property "Manufacturer" "")
    (property "Sheetfile" "dc-input.kicad_sch")
    (property "Sheetname" "DC Input")
    (property "ki_description" "Test Point 0.75mm")
    (attr exclude_from_pos_files)
    (fp_text reference "TP46" (at 0.33 -0.25 90) (layer "F.SilkS")
        (effects (font (size 0.7 0.7) (thickness 0.15)) (justify left bottom))
    )
    (fp_text value "TP_0.75mm_SMD" (at 0 1.2) (layer "F.Fab") hide
        (effects (font (size 0.7 0.7) (thickness 0.15)) (justify left bottom))
    )
    (fp_text user "Author: Antmicro" (at -0.4 3.901) (layer "F.Fab") hide
        (effects (font (size 0.7 0.7) (thickness 0.15)) (justify left bottom))
    )
    (fp_text user "License: Apache-2.0" (at -0.4 5.101) (layer "F.Fab") hide
        (effects (font (size 0.7 0.7) (thickness 0.15)) (justify left bottom))
    )
    (fp_text user "${REFERENCE}" (at -0.4 2.7) (layer "F.Fab") hide
        (effects (font (size 0.7 0.7) (thickness 0.15)) (justify left bottom))
    )
    (pad "1" smd circle (at 0 0) (size 0.75 0.75) (layers "F.Cu" "F.Mask")
      (net 22 "/Power Supply/DC Input/DC_IN") (pinfunction "1") (pintype "passive"))
  )

  (footprint "kria-k26-devboard-footprints:C_0603_1608Metric" (layer "F.Cu")
    (at 172 137.65 180)
    (descr "Capacitor SMD 0603")
    (tags "capacitor 0603")
    (property "Author" "Antmicro")
    (property "Dielectric" "")
    (property "License" "Apache-2.0")
    (property "MPN" "C1608X5R1E106M080AC")
    (property "Manufacturer" "TDK")
    (property "Sheetfile" "dc-dc-conventers.kicad_sch")
    (property "Sheetname" "DC/DC conventers")
    (property "Val" "10u/25V")
    (property "Voltage" "")
    (property "ki_description" " ")
    (attr smd)
    (fp_text reference "C201" (at 1.39 -1.57 180) (layer "F.SilkS")
        (effects (font (size 0.7 0.7) (thickness 0.15)) (justify left bottom))
    )
    (fp_text value "C_10u_25V_0603" (at 0 1.6 180) (layer "F.Fab") hide
        (effects (font (size 0.7 0.7) (thickness 0.15)) (justify left bottom))
    )
    (fp_text user "Author: Antmicro" (at -1.682 4.894 180) (layer "F.Fab") hide
        (effects (font (size 0.7 0.7) (thickness 0.15)) (justify left bottom))
    )
    (fp_text user "License: Apache-2.0" (at -1.682 5.895 180) (layer "F.Fab") hide
        (effects (font (size 0.7 0.7) (thickness 0.15)) (justify left bottom))
    )
    (fp_text user "${REFERENCE}" (at -1.682 3.895 180) (layer "F.Fab") hide
        (effects (font (size 0.7 0.7) (thickness 0.15)) (justify left bottom))
    )
    (fp_line (start -0.3 -0.3) (end 0.3 -0.3)
      (stroke (width 0.15) (type solid)) (layer "F.SilkS"))
    (fp_line (start -0.3 0.3) (end 0.3 0.3)
      (stroke (width 0.15) (type solid)) (layer "F.SilkS"))
    (fp_rect (start -1.24 -0.7) (end 1.24 0.7)
      (stroke (width 0.05) (type solid)) (fill none) (layer "F.CrtYd"))
    (fp_rect (start -0.8 -0.4) (end 0.8 0.4)
      (stroke (width 0.15) (type solid)) (fill none) (layer "F.Fab"))
    (pad "1" smd roundrect (at -0.7 0 180) (size 0.6 0.8) (layers "F.Cu" "F.Paste" "F.Mask") (roundrect_rratio 0.2)
      (net 14 "/Power Supply/DC/DC conventers/DC_MAIN_BUS") (pintype "passive"))
    (pad "2" smd roundrect (at 0.7 0 180) (size 0.6 0.8) (layers "F.Cu" "F.Paste" "F.Mask") (roundrect_rratio 0.2)
      (net 1 "GND") (pintype "passive"))
  )

  (footprint "kria-k26-devboard-footprints:FB_0402_1005Metric" (layer "F.Cu")
    (at 151.14 123.52 180)
    (descr "Ferrite Bead SMD 0402")
    (tags "ferrite bead SMD 0402")
    (property "Author" "Antmicro")
    (property "License" "Apache-2.0")
    (property "MPN" "BLM15PD121SN1D")
    (property "Manufacturer" "Murata")
    (property "Sheetfile" "debug.kicad_sch")
    (property "Sheetname" "Debug and JTAG")
    (attr smd)
    (fp_text reference "FB4" (at 3.14 -0.37 180) (layer "F.SilkS")
        (effects (font (size 0.7 0.7) (thickness 0.15)) (justify left bottom))
    )
    (fp_text value "FB_120Z_1.3A_0402" (at 0 1.4 180) (layer "F.Fab") hide
        (effects (font (size 0.7 0.7) (thickness 0.15)) (justify left bottom))
    )
    (fp_text user "License: Apache-2.0" (at -0.95 5.169 180) (layer "F.Fab") hide
        (effects (font (size 0.7 0.7) (thickness 0.15)) (justify left bottom))
    )
    (fp_text user "Author: Antmicro" (at -0.95 4.169 180) (layer "F.Fab") hide
        (effects (font (size 0.7 0.7) (thickness 0.15)) (justify left bottom))
    )
    (fp_text user "${REFERENCE}" (at -0.95 3.168 180) (layer "F.Fab") hide
        (effects (font (size 0.7 0.7) (thickness 0.15)) (justify left bottom))
    )
    (fp_rect (start -0.95 -0.48) (end 0.95 0.48)
      (stroke (width 0.05) (type solid)) (fill none) (layer "F.CrtYd"))
    (fp_rect (start -0.5 -0.25) (end 0.5 0.25)
      (stroke (width 0.15) (type solid)) (fill none) (layer "F.Fab"))
    (pad "1" smd roundrect (at -0.485 0 180) (size 0.59 0.64) (layers "F.Cu" "F.Paste" "F.Mask") (roundrect_rratio 0.25)
      (net 138 "/Debug and JTAG/USB_3V3") (pintype "passive"))
    (pad "2" smd roundrect (at 0.485 0 180) (size 0.59 0.64) (layers "F.Cu" "F.Paste" "F.Mask") (roundrect_rratio 0.25)
      (net 134 "/Debug and JTAG/VREGIN") (pintype "passive"))
  )

  (footprint "kria-k26-devboard-footprints:TP_SMD_0.75mm" (layer "F.Cu")
    (at 190.8 123.65)
    (property "Author" "Antmicro")
    (property "License" "Apache-2.0")
    (property "MPN" "")
    (property "Manufacturer" "")
    (property "Sheetfile" "supply-oring.kicad_sch")
    (property "Sheetname" "Supply ORing")
    (property "ki_description" "Test Point 0.75mm")
    (attr exclude_from_pos_files)
    (fp_text reference "TP43" (at 0.4 3 90) (layer "F.SilkS")
        (effects (font (size 0.7 0.7) (thickness 0.15)) (justify left bottom))
    )
    (fp_text value "TP_0.75mm_SMD" (at 0 1.2) (layer "F.Fab") hide
        (effects (font (size 0.7 0.7) (thickness 0.15)) (justify left bottom))
    )
    (fp_text user "Author: Antmicro" (at -0.4 3.901) (layer "F.Fab") hide
        (effects (font (size 0.7 0.7) (thickness 0.15)) (justify left bottom))
    )
    (fp_text user "License: Apache-2.0" (at -0.4 5.101) (layer "F.Fab") hide
        (effects (font (size 0.7 0.7) (thickness 0.15)) (justify left bottom))
    )
    (fp_text user "${REFERENCE}" (at -0.4 2.7) (layer "F.Fab") hide
        (effects (font (size 0.7 0.7) (thickness 0.15)) (justify left bottom))
    )
    (pad "1" smd circle (at 0 0) (size 0.75 0.75) (layers "F.Cu" "F.Mask")
      (net 14 "/Power Supply/DC/DC conventers/DC_MAIN_BUS") (pinfunction "1") (pintype "passive"))
  )

  (footprint "kria-k26-devboard-footprints:TP_SMD_0.75mm" (layer "F.Cu")
    (at 138.6 96.4)
    (property "Author" "Antmicro")
    (property "License" "Apache-2.0")
    (property "MPN" "")
    (property "Manufacturer" "")
    (property "Sheetfile" "dc-dc-conventers.kicad_sch")
    (property "Sheetname" "DC/DC conventers")
    (property "ki_description" "Test Point 0.75mm")
    (attr exclude_from_pos_files)
    (fp_text reference "TP40" (at -1.32 1.23) (layer "F.SilkS")
        (effects (font (size 0.7 0.7) (thickness 0.15)) (justify left bottom))
    )
    (fp_text value "TP_0.75mm_SMD" (at 0 1.2) (layer "F.Fab") hide
        (effects (font (size 0.7 0.7) (thickness 0.15)) (justify left bottom))
    )
    (fp_text user "License: Apache-2.0" (at -0.4 5.101) (layer "F.Fab") hide
        (effects (font (size 0.7 0.7) (thickness 0.15)) (justify left bottom))
    )
    (fp_text user "Author: Antmicro" (at -0.4 3.901) (layer "F.Fab") hide
        (effects (font (size 0.7 0.7) (thickness 0.15)) (justify left bottom))
    )
    (fp_text user "${REFERENCE}" (at -0.4 2.7) (layer "F.Fab") hide
        (effects (font (size 0.7 0.7) (thickness 0.15)) (justify left bottom))
    )
    (pad "1" smd circle (at 0 0) (size 0.75 0.75) (layers "F.Cu" "F.Mask")
      (net 769 "/Power Supply/DC/DC conventers/PS_1V0_OUT") (pinfunction "1") (pintype "passive"))
  )

  (footprint "kria-k26-devboard-footprints:UQFN-13_2x3mm_P0.5mm" (layer "F.Cu")
    (at 173.15 125.1 90)
    (property "Author" "Antmicro")
    (property "License" "Apache-2.0")
    (property "MPN" "RT6236AHGQUF")
    (property "Manufacturer" "Richtek")
    (property "Sheetfile" "dc-dc-conventers.kicad_sch")
    (property "Sheetname" "DC/DC conventers")
    (property "ki_description" "DC-DC Switching Buck Step Down Regulator, Adjustable, 4.5V-18Vin, 700mV-8V/6A out, 650kHz, UQFN-13")
    (property "ki_keywords" "SMT, PMIC, IC, SWITCHING, VOLTAGE, REGULATOR, DC-DC")
    (attr smd)
    (fp_text reference "U48" (at 1.51 -0.2 180) (layer "F.SilkS")
        (effects (font (size 0.7 0.7) (thickness 0.15)) (justify left bottom))
    )
    (fp_text value "RT6236AHGQUF" (at 0.812 3.293 90) (layer "F.Fab") hide
        (effects (font (size 0.7 0.7) (thickness 0.15)) (justify left bottom))
    )
    (fp_text user "License: Apache-2.0" (at -1.537 7.693 90) (layer "F.Fab") hide
        (effects (font (size 0.7 0.7) (thickness 0.15)) (justify left bottom))
    )
    (fp_text user "${REFERENCE}" (at -1.537 5.294 90) (layer "F.Fab") hide
        (effects (font (size 0.7 0.7) (thickness 0.15)) (justify left bottom))
    )
    (fp_text user "Author: Antmicro" (at -1.537 6.493 90) (layer "F.Fab") hide
        (effects (font (size 0.7 0.7) (thickness 0.15)) (justify left bottom))
    )
    (fp_circle (center -1.25 -1.65) (end -1.2 -1.65)
      (stroke (width 0.15) (type solid)) (fill solid) (layer "F.SilkS"))
    (fp_rect (start -1.65 -2.15) (end 1.65 2.15)
      (stroke (width 0.05) (type solid)) (fill none) (layer "F.CrtYd"))
    (fp_line (start -0.9 -0.85) (end -0.45 -1.3)
      (stroke (width 0.15) (type solid)) (layer "F.Fab"))
    (fp_line (start -0.9 1.3) (end -0.9 -0.85)
      (stroke (width 0.15) (type solid)) (layer "F.Fab"))
    (fp_line (start -0.45 -1.3) (end 0.9 -1.3)
      (stroke (width 0.15) (type solid)) (layer "F.Fab"))
    (fp_line (start 0.9 -1.3) (end 0.9 1.3)
      (stroke (width 0.15) (type solid)) (layer "F.Fab"))
    (fp_line (start 0.9 1.3) (end -0.9 1.3)
      (stroke (width 0.15) (type solid)) (layer "F.Fab"))
    (pad "1" smd roundrect (at -1 -0.75 270) (size 0.8 0.3) (layers "F.Cu" "F.Paste" "F.Mask") (roundrect_rratio 0.25)
      (net 1 "GND") (pinfunction "GND") (pintype "power_in") (zone_connect 2))
    (pad "2" smd roundrect (at -1 -0.25 270) (size 0.8 0.3) (layers "F.Cu" "F.Paste" "F.Mask") (roundrect_rratio 0.25)
      (net 686 "Net-(U48-EN)") (pinfunction "EN") (pintype "input") (zone_connect 2))
    (pad "3" smd roundrect (at -1 0.248 270) (size 0.8 0.3) (layers "F.Cu" "F.Paste" "F.Mask") (roundrect_rratio 0.25)
      (net 255 "Net-(U48-FB)") (pinfunction "FB") (pintype "input") (zone_connect 2))
    (pad "4" smd roundrect (at -1 0.748 270) (size 0.8 0.3) (layers "F.Cu" "F.Paste" "F.Mask") (roundrect_rratio 0.25)
      (net 782 "unconnected-(U48-NC-Pad4)") (pinfunction "NC") (pintype "no_connect") (zone_connect 2))
    (pad "5" smd roundrect (at -0.25 0.998 180) (size 1.8 0.3) (layers "F.Cu" "F.Paste" "F.Mask") (roundrect_rratio 0.25)
      (net 251 "Net-(U48-SS)") (pinfunction "SS") (pintype "input") (zone_connect 2))
    (pad "6" smd roundrect (at 0.248 0.998 180) (size 1.8 0.3) (layers "F.Cu" "F.Paste" "F.Mask") (roundrect_rratio 0.25)
      (net 249 "Net-(U48-PVCC)") (pinfunction "PVCC") (pintype "output") (zone_connect 2))
    (pad "7" smd roundrect (at 0.998 0.748 270) (size 0.8 0.3) (layers "F.Cu" "F.Paste" "F.Mask") (roundrect_rratio 0.25)
      (net 783 "unconnected-(U48-NC-Pad7)") (pinfunction "NC") (pintype "no_connect") (zone_connect 2))
    (pad "8" smd roundrect (at 0.998 0.248 270) (size 0.8 0.3) (layers "F.Cu" "F.Paste" "F.Mask") (roundrect_rratio 0.25)
      (net 784 "unconnected-(U48-PG-Pad8)") (pinfunction "PG") (pintype "output+no_connect") (zone_connect 2))
    (pad "9" smd roundrect (at 0.998 -0.25 270) (size 0.8 0.3) (layers "F.Cu" "F.Paste" "F.Mask") (roundrect_rratio 0.25)
      (net 14 "/Power Supply/DC/DC conventers/DC_MAIN_BUS") (pinfunction "VIN") (pintype "passive") (zone_connect 2))
    (pad "10" smd roundrect (at 0.998 -0.75 270) (size 0.8 0.3) (layers "F.Cu" "F.Paste" "F.Mask") (roundrect_rratio 0.25)
      (net 14 "/Power Supply/DC/DC conventers/DC_MAIN_BUS") (pinfunction "VIN") (pintype "power_in") (zone_connect 2))
    (pad "11" smd roundrect (at 0.583 -1.476 180) (size 0.85 0.3) (layers "F.Cu" "F.Paste" "F.Mask") (roundrect_rratio 0.25)
      (net 253 "Net-(U48-BOOT)") (pinfunction "BOOT") (pintype "output") (zone_connect 2))
    (pad "12" smd roundrect (at -0.003 -1.2) (size 1.4 0.47) (layers "F.Cu" "F.Paste" "F.Mask") (roundrect_rratio 0.25)
      (net 366 "/Power Supply/DC/DC conventers/SW_SOM_5V") (pinfunction "SW") (pintype "power_out") (zone_connect 2))
    (pad "13" smd roundrect (at -0.585 -1.476 180) (size 0.85 0.3) (layers "F.Cu" "F.Paste" "F.Mask") (roundrect_rratio 0.25)
      (net 1 "GND") (pinfunction "GND") (pintype "passive") (zone_connect 2))
  )

  (footprint "kria-k26-devboard-footprints:C_0402_1005Metric" (layer "F.Cu")
    (at 176.275 125.975)
    (descr "Capacitor SMD 0402")
    (tags "capacitor SMD 0402")
    (property "Author" "Antmicro")
    (property "Dielectric" "")
    (property "License" "Apache-2.0")
    (property "MPN" "GRM155R71H392KA01D")
    (property "Manufacturer" "Murata")
    (property "Sheetfile" "dc-dc-conventers.kicad_sch")
    (property "Sheetname" "DC/DC conventers")
    (property "Val" "3n9")
    (property "Voltage" "")
    (property "ki_description" " ")
    (attr smd)
    (fp_text reference "C190" (at -1.255 3.135) (layer "F.SilkS")
        (effects (font (size 0.7 0.7) (thickness 0.15)) (justify left bottom))
    )
    (fp_text value "C_3n9_0402" (at 0 1.4) (layer "F.Fab") hide
        (effects (font (size 0.7 0.7) (thickness 0.15)) (justify left bottom))
    )
    (fp_text user "${REFERENCE}" (at -0.932 3.168) (layer "F.Fab") hide
        (effects (font (size 0.7 0.7) (thickness 0.15)) (justify left bottom))
    )
    (fp_text user "License: Apache-2.0" (at -0.932 5.17) (layer "F.Fab") hide
        (effects (font (size 0.7 0.7) (thickness 0.15)) (justify left bottom))
    )
    (fp_text user "Author: Antmicro" (at -0.932 4.17) (layer "F.Fab") hide
        (effects (font (size 0.7 0.7) (thickness 0.15)) (justify left bottom))
    )
    (fp_rect (start -0.94 -0.47) (end 0.94 0.47)
      (stroke (width 0.05) (type solid)) (fill none) (layer "F.CrtYd"))
    (fp_rect (start -0.499 -0.249) (end 0.499 0.249)
      (stroke (width 0.15) (type solid)) (fill none) (layer "F.Fab"))
    (pad "1" smd roundrect (at -0.484 0) (size 0.59 0.64) (layers "F.Cu" "F.Paste" "F.Mask") (roundrect_rratio 0.25)
      (net 251 "Net-(U48-SS)") (pintype "passive"))
    (pad "2" smd roundrect (at 0.484 0) (size 0.59 0.64) (layers "F.Cu" "F.Paste" "F.Mask") (roundrect_rratio 0.25)
      (net 1 "GND") (pintype "passive"))
  )

  (footprint "kria-k26-devboard-footprints:LED_0603_1608Metric_G" (layer "F.Cu")
    (at 179.25 127.95)
    (descr "LED SMD 0603 Green")
    (tags "LED SMD 0603 Green")
    (property "Author" "Antmicro")
    (property "Color" "Green")
    (property "License" "Apache-2.0")
    (property "MPN" "LG L29K-G2J1-24-Z")
    (property "Manufacturer" "OSRAM")
    (property "Sheetfile" "dc-dc-conventers.kicad_sch")
    (property "Sheetname" "DC/DC conventers")
    (property "ki_description" "LED, Green, SMT, 0603, 20 mA, 2.1 V, 570 nm")
    (property "ki_keywords" "0603, SMT, DIODE, SEMICONDUCTOR, UNICOLOR")
    (attr smd)
    (fp_text reference "D12" (at -1.53 1.27) (layer "F.SilkS")
        (effects (font (size 0.7 0.7) (thickness 0.15)) (justify left bottom))
    )
    (fp_text value "LED_G_0603_LG_L29K-G2J1-24-Z" (at 0 1.6) (layer "F.Fab") hide
        (effects (font (size 0.7 0.7) (thickness 0.15)) (justify left bottom))
    )
    (fp_text user "Author: Antmicro" (at -1.31 4.769) (layer "F.Fab") hide
        (effects (font (size 0.7 0.7) (thickness 0.15)) (justify left bottom))
    )
    (fp_text user "License: Apache-2.0" (at -1.31 5.769) (layer "F.Fab") hide
        (effects (font (size 0.7 0.7) (thickness 0.15)) (justify left bottom))
    )
    (fp_text user "${REFERENCE}" (at -1.31 3.769) (layer "F.Fab") hide
        (effects (font (size 0.7 0.7) (thickness 0.15)) (justify left bottom))
    )
    (fp_line (start -0.27 -0.35) (end 0.27 -0.35)
      (stroke (width 0.15) (type solid)) (layer "F.SilkS"))
    (fp_line (start -0.27 0.351) (end 0.27 0.351)
      (stroke (width 0.15) (type solid)) (layer "F.SilkS"))
    (fp_line (start -0.106328 -0.200008) (end -0.106328 0.199992)
      (stroke (width 0.1) (type solid)) (layer "F.SilkS"))
    (fp_line (start -0.106328 -0.200008) (end 0.093672 -0.000008)
      (stroke (width 0.1) (type solid)) (layer "F.SilkS"))
    (fp_line (start -0.106328 -0.000008) (end -0.29 0)
      (stroke (width 0.1) (type solid)) (layer "F.SilkS"))
    (fp_line (start 0.093672 -0.200008) (end 0.093672 0.199992)
      (stroke (width 0.1) (type solid)) (layer "F.SilkS"))
    (fp_line (start 0.093672 -0.000008) (end -0.106328 0.199992)
      (stroke (width 0.1) (type solid)) (layer "F.SilkS"))
    (fp_line (start 0.093672 -0.000008) (end 0.293672 -0.000008)
      (stroke (width 0.1) (type solid)) (layer "F.SilkS"))
    (fp_line (start 1.25 0.32) (end 1.25 -0.32)
      (stroke (width 0.15) (type solid)) (layer "F.SilkS"))
    (fp_rect (start 1.26 0.65) (end -1.26 -0.65)
      (stroke (width 0.05) (type solid)) (fill none) (layer "F.CrtYd"))
    (fp_line (start -0.599 0) (end -0.201 0)
      (stroke (width 0.15) (type solid)) (layer "F.Fab"))
    (fp_line (start -0.201 -0.2) (end -0.201 0)
      (stroke (width 0.15) (type solid)) (layer "F.Fab"))
    (fp_line (start -0.201 0) (end -0.201 0.202)
      (stroke (width 0.15) (type solid)) (layer "F.Fab"))
    (fp_line (start -0.201 0.202) (end 0.101 0)
      (stroke (width 0.15) (type solid)) (layer "F.Fab"))
    (fp_line (start 0.101 0) (end -0.201 -0.2)
      (stroke (width 0.15) (type solid)) (layer "F.Fab"))
    (fp_line (start 0.199 -0.2) (end 0.199 -0.1)
      (stroke (width 0.15) (type solid)) (layer "F.Fab"))
    (fp_line (start 0.199 0) (end 0.597 0)
      (stroke (width 0.15) (type solid)) (layer "F.Fab"))
    (fp_line (start 0.199 0.202) (end 0.199 -0.1)
      (stroke (width 0.15) (type solid)) (layer "F.Fab"))
    (fp_rect (start -0.848 -0.4) (end 0.85 0.402)
      (stroke (width 0.15) (type solid)) (fill none) (layer "F.Fab"))
    (pad "1" smd rect (at -0.75 0 180) (size 0.8 0.8) (layers "F.Cu" "F.Paste" "F.Mask")
      (net 329 "Net-(D12-Pad1)") (pintype "passive"))
    (pad "2" smd rect (at 0.75 0 180) (size 0.8 0.8) (layers "F.Cu" "F.Paste" "F.Mask")
      (net 1 "GND") (pinfunction "2") (pintype "passive"))
  )

  (footprint "kria-k26-devboard-footprints:R_0402_1005Metric" (layer "F.Cu")
    (at 176.275 126.975)
    (descr "Resistor SMD 0402")
    (tags "resistor SMD 0402")
    (property "Author" "Antmicro")
    (property "License" "Apache-2.0")
    (property "MPN" "CR0402-FX-2402GLF")
    (property "Manufacturer" "Bourns")
    (property "Sheetfile" "dc-dc-conventers.kicad_sch")
    (property "Sheetname" "DC/DC conventers")
    (property "Tolerance" "1%")
    (property "Val" "24k")
    (property "ki_description" "24k resistor in 0402 package with 1% tolerance")
    (attr smd)
    (fp_text reference "R125" (at -1.345 3.035) (layer "F.SilkS")
        (effects (font (size 0.7 0.7) (thickness 0.15)) (justify left bottom))
    )
    (fp_text value "R_24k_0402" (at 0 1.4) (layer "F.Fab") hide
        (effects (font (size 0.7 0.7) (thickness 0.15)) (justify left bottom))
    )
    (fp_text user "License: Apache-2.0" (at -0.95 5.169) (layer "F.Fab") hide
        (effects (font (size 0.7 0.7) (thickness 0.15)) (justify left bottom))
    )
    (fp_text user "Author: Antmicro" (at -0.95 4.169) (layer "F.Fab") hide
        (effects (font (size 0.7 0.7) (thickness 0.15)) (justify left bottom))
    )
    (fp_text user "${REFERENCE}" (at -0.95 3.168) (layer "F.Fab") hide
        (effects (font (size 0.7 0.7) (thickness 0.15)) (justify left bottom))
    )
    (fp_rect (start -0.93 -0.47) (end 0.93 0.47)
      (stroke (width 0.05) (type solid)) (fill none) (layer "F.CrtYd"))
    (fp_rect (start -0.5 -0.25) (end 0.5 0.25)
      (stroke (width 0.15) (type solid)) (fill none) (layer "F.Fab"))
    (pad "1" smd roundrect (at -0.485 0) (size 0.59 0.64) (layers "F.Cu" "F.Paste" "F.Mask") (roundrect_rratio 0.25)
      (net 255 "Net-(U48-FB)") (pintype "passive"))
    (pad "2" smd roundrect (at 0.485 0) (size 0.59 0.64) (layers "F.Cu" "F.Paste" "F.Mask") (roundrect_rratio 0.25)
      (net 1 "GND") (pintype "passive"))
  )

  (footprint "kria-k26-devboard-footprints:C_0402_1005Metric" (layer "F.Cu")
    (at 176.275 125.025)
    (descr "Capacitor SMD 0402")
    (tags "capacitor SMD 0402")
    (property "Author" "Antmicro")
    (property "Dielectric" "")
    (property "License" "Apache-2.0")
    (property "MPN" "C1005X6S1A105K050BC")
    (property "Manufacturer" "TDK")
    (property "Sheetfile" "dc-dc-conventers.kicad_sch")
    (property "Sheetname" "DC/DC conventers")
    (property "Val" "1u")
    (property "Voltage" "")
    (property "ki_description" " ")
    (attr smd)
    (fp_text reference "C188" (at -1.185 3.175) (layer "F.SilkS")
        (effects (font (size 0.7 0.7) (thickness 0.15)) (justify left bottom))
    )
    (fp_text value "C_1u_0402" (at 0 1.4) (layer "F.Fab") hide
        (effects (font (size 0.7 0.7) (thickness 0.15)) (justify left bottom))
    )
    (fp_text user "License: Apache-2.0" (at -0.932 5.17) (layer "F.Fab") hide
        (effects (font (size 0.7 0.7) (thickness 0.15)) (justify left bottom))
    )
    (fp_text user "${REFERENCE}" (at -0.932 3.168) (layer "F.Fab") hide
        (effects (font (size 0.7 0.7) (thickness 0.15)) (justify left bottom))
    )
    (fp_text user "Author: Antmicro" (at -0.932 4.17) (layer "F.Fab") hide
        (effects (font (size 0.7 0.7) (thickness 0.15)) (justify left bottom))
    )
    (fp_rect (start -0.94 -0.47) (end 0.94 0.47)
      (stroke (width 0.05) (type solid)) (fill none) (layer "F.CrtYd"))
    (fp_rect (start -0.499 -0.249) (end 0.499 0.249)
      (stroke (width 0.15) (type solid)) (fill none) (layer "F.Fab"))
    (pad "1" smd roundrect (at -0.484 0) (size 0.59 0.64) (layers "F.Cu" "F.Paste" "F.Mask") (roundrect_rratio 0.25)
      (net 249 "Net-(U48-PVCC)") (pintype "passive"))
    (pad "2" smd roundrect (at 0.484 0) (size 0.59 0.64) (layers "F.Cu" "F.Paste" "F.Mask") (roundrect_rratio 0.25)
      (net 1 "GND") (pintype "passive"))
  )

  (footprint "kria-k26-devboard-footprints:C_0603_1608Metric" (layer "F.Cu")
    (at 177.46 123.22 -90)
    (descr "Capacitor SMD 0603")
    (tags "capacitor 0603")
    (property "Author" "Antmicro")
    (property "Dielectric" "")
    (property "License" "Apache-2.0")
    (property "MPN" "C1608X5R1E106M080AC")
    (property "Manufacturer" "TDK")
    (property "Sheetfile" "dc-dc-conventers.kicad_sch")
    (property "Sheetname" "DC/DC conventers")
    (property "Val" "10u/25V")
    (property "Voltage" "")
    (property "ki_description" " ")
    (attr smd)
    (fp_text reference "C186" (at 3.655 -2.09 -90) (layer "F.SilkS")
        (effects (font (size 0.7 0.7) (thickness 0.15)) (justify left bottom))
    )
    (fp_text value "C_10u_25V_0603" (at 0 1.6 -90) (layer "F.Fab") hide
        (effects (font (size 0.7 0.7) (thickness 0.15)) (justify left bottom))
    )
    (fp_text user "${REFERENCE}" (at -1.682 3.895 -90) (layer "F.Fab") hide
        (effects (font (size 0.7 0.7) (thickness 0.15)) (justify left bottom))
    )
    (fp_text user "Author: Antmicro" (at -1.682 4.894 -90) (layer "F.Fab") hide
        (effects (font (size 0.7 0.7) (thickness 0.15)) (justify left bottom))
    )
    (fp_text user "License: Apache-2.0" (at -1.682 5.895 -90) (layer "F.Fab") hide
        (effects (font (size 0.7 0.7) (thickness 0.15)) (justify left bottom))
    )
    (fp_line (start -0.3 -0.3) (end 0.3 -0.3)
      (stroke (width 0.15) (type solid)) (layer "F.SilkS"))
    (fp_line (start -0.3 0.3) (end 0.3 0.3)
      (stroke (width 0.15) (type solid)) (layer "F.SilkS"))
    (fp_rect (start -1.24 -0.7) (end 1.24 0.7)
      (stroke (width 0.05) (type solid)) (fill none) (layer "F.CrtYd"))
    (fp_rect (start -0.8 -0.4) (end 0.8 0.4)
      (stroke (width 0.15) (type solid)) (fill none) (layer "F.Fab"))
    (pad "1" smd roundrect (at -0.7 0 270) (size 0.6 0.8) (layers "F.Cu" "F.Paste" "F.Mask") (roundrect_rratio 0.2)
      (net 14 "/Power Supply/DC/DC conventers/DC_MAIN_BUS") (pintype "passive"))
    (pad "2" smd roundrect (at 0.7 0 270) (size 0.6 0.8) (layers "F.Cu" "F.Paste" "F.Mask") (roundrect_rratio 0.2)
      (net 1 "GND") (pintype "passive"))
  )

  (footprint "kria-k26-devboard-footprints:C_0402_1005Metric" (layer "F.Cu")
    (at 171.35 122.85 180)
    (descr "Capacitor SMD 0402")
    (tags "capacitor SMD 0402")
    (property "Author" "Antmicro")
    (property "Dielectric" "X5R")
    (property "License" "Apache-2.0")
    (property "MPN" "GRM155R61H104KE14D")
    (property "Manufacturer" "Murata")
    (property "Sheetfile" "dc-dc-conventers.kicad_sch")
    (property "Sheetname" "DC/DC conventers")
    (property "Val" "100n")
    (property "Voltage" "50V")
    (property "ki_description" " ")
    (attr smd)
    (fp_text reference "C192" (at 0.62 0.48) (layer "F.SilkS")
        (effects (font (size 0.7 0.7) (thickness 0.15)) (justify left bottom))
    )
    (fp_text value "C_100n_0402" (at 0 1.4 180) (layer "F.Fab") hide
        (effects (font (size 0.7 0.7) (thickness 0.15)) (justify left bottom))
    )
    (fp_text user "${REFERENCE}" (at -0.932 3.168 180) (layer "F.Fab") hide
        (effects (font (size 0.7 0.7) (thickness 0.15)) (justify left bottom))
    )
    (fp_text user "Author: Antmicro" (at -0.932 4.17 180) (layer "F.Fab") hide
        (effects (font (size 0.7 0.7) (thickness 0.15)) (justify left bottom))
    )
    (fp_text user "License: Apache-2.0" (at -0.932 5.17 180) (layer "F.Fab") hide
        (effects (font (size 0.7 0.7) (thickness 0.15)) (justify left bottom))
    )
    (fp_rect (start -0.94 -0.47) (end 0.94 0.47)
      (stroke (width 0.05) (type solid)) (fill none) (layer "F.CrtYd"))
    (fp_rect (start -0.499 -0.249) (end 0.499 0.249)
      (stroke (width 0.15) (type solid)) (fill none) (layer "F.Fab"))
    (pad "1" smd roundrect (at -0.484 0 180) (size 0.59 0.64) (layers "F.Cu" "F.Paste" "F.Mask") (roundrect_rratio 0.25)
      (net 253 "Net-(U48-BOOT)") (pintype "passive"))
    (pad "2" smd roundrect (at 0.484 0 180) (size 0.59 0.64) (layers "F.Cu" "F.Paste" "F.Mask") (roundrect_rratio 0.25)
      (net 366 "/Power Supply/DC/DC conventers/SW_SOM_5V") (pintype "passive"))
  )

  (footprint "kria-k26-devboard-footprints:L_Coilcraft-XEL4030" (layer "F.Cu")
    (at 168.2 124.675 180)
    (property "Author" "Antmicro")
    (property "IMax" "")
    (property "ISat" "")
    (property "License" "Apache-2.0")
    (property "MPN" "XEL4030-332MEC")
    (property "Manufacturer" "Coilcraft")
    (property "Sheetfile" "dc-dc-conventers.kicad_sch")
    (property "Sheetname" "DC/DC conventers")
    (property "Size" "4x4")
    (property "Val" "3u3/5.9A")
    (attr smd)
    (fp_text reference "L2" (at 3.54 1.295 180) (layer "F.SilkS")
        (effects (font (size 0.7 0.7) (thickness 0.15)) (justify left bottom))
    )
    (fp_text value "L_3u3_5.9A_XEL4030" (at 0.05 2.996 180) (layer "F.Fab") hide
        (effects (font (size 0.7 0.7) (thickness 0.15)) (justify left bottom))
    )
    (fp_text user "Author: Antmicro" (at -2.15 5.996 180) (layer "F.Fab") hide
        (effects (font (size 0.7 0.7) (thickness 0.15)) (justify left bottom))
    )
    (fp_text user "${REFERENCE}" (at -2.15 4.996 180) (layer "F.Fab") hide
        (effects (font (size 0.7 0.7) (thickness 0.15)) (justify left bottom))
    )
    (fp_text user "License: Apache-2.0" (at -2.15 6.996 180) (layer "F.Fab") hide
        (effects (font (size 0.7 0.7) (thickness 0.15)) (justify left bottom))
    )
    (fp_line (start -1.8 -2.2) (end 1.85 -2.201)
      (stroke (width 0.15) (type solid)) (layer "F.SilkS"))
    (fp_line (start -1.8 2.2) (end 1.85 2.199)
      (stroke (width 0.15) (type solid)) (layer "F.SilkS"))
    (fp_rect (start -2.45 -2.45) (end 2.45 2.45)
      (stroke (width 0.05) (type solid)) (fill none) (layer "F.CrtYd"))
    (fp_line (start -2 -2) (end 1.999 -2)
      (stroke (width 0.15) (type solid)) (layer "F.Fab"))
    (fp_line (start -2 1.999) (end -2 -2)
      (stroke (width 0.15) (type solid)) (layer "F.Fab"))
    (fp_line (start 1.999 -2) (end 1.999 1.999)
      (stroke (width 0.15) (type solid)) (layer "F.Fab"))
    (fp_line (start 1.999 1.999) (end -2 1.999)
      (stroke (width 0.15) (type solid)) (layer "F.Fab"))
    (pad "1" smd rect (at -1.186 0 180) (size 0.98 3.4) (layers "F.Cu" "F.Paste" "F.Mask")
      (net 366 "/Power Supply/DC/DC conventers/SW_SOM_5V") (pintype "passive"))
    (pad "2" smd rect (at 1.185 0 180) (size 0.98 3.4) (layers "F.Cu" "F.Paste" "F.Mask")
      (net 773 "/Power Supply/DC/DC conventers/SOM_5V_OUT") (pintype "passive"))
  )

  (footprint "kria-k26-devboard-footprints:C_0603_1608Metric" (layer "F.Cu")
    (at 176.049999 123.225 -90)
    (descr "Capacitor SMD 0603")
    (tags "capacitor 0603")
    (property "Author" "Antmicro")
    (property "Dielectric" "")
    (property "License" "Apache-2.0")
    (property "MPN" "C1608X5R1E106M080AC")
    (property "Manufacturer" "TDK")
    (property "Sheetfile" "dc-dc-conventers.kicad_sch")
    (property "Sheetname" "DC/DC conventers")
    (property "Val" "10u/25V")
    (property "Voltage" "")
    (property "ki_description" " ")
    (attr smd)
    (fp_text reference "C184" (at 3.665 -2.480001 -90) (layer "F.SilkS")
        (effects (font (size 0.7 0.7) (thickness 0.15)) (justify left bottom))
    )
    (fp_text value "C_10u_25V_0603" (at 0 1.6 -90) (layer "F.Fab") hide
        (effects (font (size 0.7 0.7) (thickness 0.15)) (justify left bottom))
    )
    (fp_text user "Author: Antmicro" (at -1.682 4.894 -90) (layer "F.Fab") hide
        (effects (font (size 0.7 0.7) (thickness 0.15)) (justify left bottom))
    )
    (fp_text user "${REFERENCE}" (at -1.682 3.895 -90) (layer "F.Fab") hide
        (effects (font (size 0.7 0.7) (thickness 0.15)) (justify left bottom))
    )
    (fp_text user "License: Apache-2.0" (at -1.682 5.895 -90) (layer "F.Fab") hide
        (effects (font (size 0.7 0.7) (thickness 0.15)) (justify left bottom))
    )
    (fp_line (start -0.3 -0.3) (end 0.3 -0.3)
      (stroke (width 0.15) (type solid)) (layer "F.SilkS"))
    (fp_line (start -0.3 0.3) (end 0.3 0.3)
      (stroke (width 0.15) (type solid)) (layer "F.SilkS"))
    (fp_rect (start -1.24 -0.7) (end 1.24 0.7)
      (stroke (width 0.05) (type solid)) (fill none) (layer "F.CrtYd"))
    (fp_rect (start -0.8 -0.4) (end 0.8 0.4)
      (stroke (width 0.15) (type solid)) (fill none) (layer "F.Fab"))
    (pad "1" smd roundrect (at -0.7 0 270) (size 0.6 0.8) (layers "F.Cu" "F.Paste" "F.Mask") (roundrect_rratio 0.2)
      (net 14 "/Power Supply/DC/DC conventers/DC_MAIN_BUS") (pintype "passive"))
    (pad "2" smd roundrect (at 0.7 0 270) (size 0.6 0.8) (layers "F.Cu" "F.Paste" "F.Mask") (roundrect_rratio 0.2)
      (net 1 "GND") (pintype "passive"))
  )

  (footprint "kria-k26-devboard-footprints:C_0402_1005Metric" (layer "F.Cu")
    (at 176.15 135.825 -90)
    (descr "Capacitor SMD 0402")
    (tags "capacitor SMD 0402")
    (property "Author" "Antmicro")
    (property "Dielectric" "X5R")
    (property "License" "Apache-2.0")
    (property "MPN" "GRM155R61H104KE14D")
    (property "Manufacturer" "Murata")
    (property "Sheetfile" "dc-dc-conventers.kicad_sch")
    (property "Sheetname" "DC/DC conventers")
    (property "Val" "100n")
    (property "Voltage" "50V")
    (property "ki_description" " ")
    (attr smd)
    (fp_text reference "C221" (at 1.625 0.49 -90) (layer "F.SilkS")
        (effects (font (size 0.7 0.7) (thickness 0.15)) (justify left bottom))
    )
    (fp_text value "C_100n_0402" (at 0 1.4 -90) (layer "F.Fab") hide
        (effects (font (size 0.7 0.7) (thickness 0.15)) (justify left bottom))
    )
    (fp_text user "Author: Antmicro" (at -0.932 4.17 -90) (layer "F.Fab") hide
        (effects (font (size 0.7 0.7) (thickness 0.15)) (justify left bottom))
    )
    (fp_text user "${REFERENCE}" (at -0.932 3.168 -90) (layer "F.Fab") hide
        (effects (font (size 0.7 0.7) (thickness 0.15)) (justify left bottom))
    )
    (fp_text user "License: Apache-2.0" (at -0.932 5.17 -90) (layer "F.Fab") hide
        (effects (font (size 0.7 0.7) (thickness 0.15)) (justify left bottom))
    )
    (fp_rect (start -0.94 -0.47) (end 0.94 0.47)
      (stroke (width 0.05) (type solid)) (fill none) (layer "F.CrtYd"))
    (fp_rect (start -0.499 -0.249) (end 0.499 0.249)
      (stroke (width 0.15) (type solid)) (fill none) (layer "F.Fab"))
    (pad "1" smd roundrect (at -0.484 0 270) (size 0.59 0.64) (layers "F.Cu" "F.Paste" "F.Mask") (roundrect_rratio 0.25)
      (net 325 "Net-(U54-BST)") (pintype "passive"))
    (pad "2" smd roundrect (at 0.484 0 270) (size 0.59 0.64) (layers "F.Cu" "F.Paste" "F.Mask") (roundrect_rratio 0.25)
      (net 315 "/Power Supply/DC/DC conventers/SW_PL_3V3") (pintype "passive"))
  )

  (footprint "kria-k26-devboard-footprints:C_0402_1005Metric" (layer "F.Cu")
    (at 189.4 123 -90)
    (descr "Capacitor SMD 0402")
    (tags "capacitor SMD 0402")
    (property "Author" "Antmicro")
    (property "Dielectric" "X5R")
    (property "License" "Apache-2.0")
    (property "MPN" "GRM155R61H104KE14D")
    (property "Manufacturer" "Murata")
    (property "Sheetfile" "supply-oring.kicad_sch")
    (property "Sheetname" "Supply ORing")
    (property "Val" "100n")
    (property "Voltage" "50V")
    (property "ki_description" " ")
    (attr smd)
    (fp_text reference "C228" (at 3.73 -0.36 -90) (layer "F.SilkS")
        (effects (font (size 0.7 0.7) (thickness 0.15)) (justify left bottom))
    )
    (fp_text value "C_100n_0402" (at 0 1.4 -90) (layer "F.Fab") hide
        (effects (font (size 0.7 0.7) (thickness 0.15)) (justify left bottom))
    )
    (fp_text user "Author: Antmicro" (at -0.932 4.17 -90) (layer "F.Fab") hide
        (effects (font (size 0.7 0.7) (thickness 0.15)) (justify left bottom))
    )
    (fp_text user "${REFERENCE}" (at -0.932 3.168 -90) (layer "F.Fab") hide
        (effects (font (size 0.7 0.7) (thickness 0.15)) (justify left bottom))
    )
    (fp_text user "License: Apache-2.0" (at -0.932 5.17 -90) (layer "F.Fab") hide
        (effects (font (size 0.7 0.7) (thickness 0.15)) (justify left bottom))
    )
    (fp_rect (start -0.94 -0.47) (end 0.94 0.47)
      (stroke (width 0.05) (type solid)) (fill none) (layer "F.CrtYd"))
    (fp_rect (start -0.499 -0.249) (end 0.499 0.249)
      (stroke (width 0.15) (type solid)) (fill none) (layer "F.Fab"))
    (pad "1" smd roundrect (at -0.484 0 270) (size 0.59 0.64) (layers "F.Cu" "F.Paste" "F.Mask") (roundrect_rratio 0.25)
      (net 14 "/Power Supply/DC/DC conventers/DC_MAIN_BUS") (pintype "passive"))
    (pad "2" smd roundrect (at 0.484 0 270) (size 0.59 0.64) (layers "F.Cu" "F.Paste" "F.Mask") (roundrect_rratio 0.25)
      (net 1 "GND") (pintype "passive"))
  )

  (footprint "kria-k26-devboard-footprints:C_0603_1608Metric" (layer "F.Cu")
    (at 169.65 128.589999 -90)
    (descr "Capacitor SMD 0603")
    (tags "capacitor 0603")
    (property "Author" "Antmicro")
    (property "Dielectric" "")
    (property "License" "Apache-2.0")
    (property "MPN" "CL10A226MO7JZNC")
    (property "Manufacturer" "Samsung")
    (property "Sheetfile" "dc-dc-conventers.kicad_sch")
    (property "Sheetname" "DC/DC conventers")
    (property "Val" "22u/16V")
    (property "Voltage" "")
    (property "ki_description" " ")
    (attr smd)
    (fp_text reference "C196" (at -1.555 4.41 -90) (layer "F.SilkS")
        (effects (font (size 0.7 0.7) (thickness 0.15)) (justify left bottom))
    )
    (fp_text value "C_22u_16V_0603" (at 0 1.6 -90) (layer "F.Fab") hide
        (effects (font (size 0.7 0.7) (thickness 0.15)) (justify left bottom))
    )
    (fp_text user "Author: Antmicro" (at -1.682 4.894 -90) (layer "F.Fab") hide
        (effects (font (size 0.7 0.7) (thickness 0.15)) (justify left bottom))
    )
    (fp_text user "${REFERENCE}" (at -1.682 3.895 -90) (layer "F.Fab") hide
        (effects (font (size 0.7 0.7) (thickness 0.15)) (justify left bottom))
    )
    (fp_text user "License: Apache-2.0" (at -1.682 5.895 -90) (layer "F.Fab") hide
        (effects (font (size 0.7 0.7) (thickness 0.15)) (justify left bottom))
    )
    (fp_line (start -0.3 -0.3) (end 0.3 -0.3)
      (stroke (width 0.15) (type solid)) (layer "F.SilkS"))
    (fp_line (start -0.3 0.3) (end 0.3 0.3)
      (stroke (width 0.15) (type solid)) (layer "F.SilkS"))
    (fp_rect (start -1.24 -0.7) (end 1.24 0.7)
      (stroke (width 0.05) (type solid)) (fill none) (layer "F.CrtYd"))
    (fp_rect (start -0.8 -0.4) (end 0.8 0.4)
      (stroke (width 0.15) (type solid)) (fill none) (layer "F.Fab"))
    (pad "1" smd roundrect (at -0.7 0 270) (size 0.6 0.8) (layers "F.Cu" "F.Paste" "F.Mask") (roundrect_rratio 0.2)
      (net 773 "/Power Supply/DC/DC conventers/SOM_5V_OUT") (pintype "passive"))
    (pad "2" smd roundrect (at 0.7 0 270) (size 0.6 0.8) (layers "F.Cu" "F.Paste" "F.Mask") (roundrect_rratio 0.2)
      (net 1 "GND") (pintype "passive"))
  )

  (footprint "kria-k26-devboard-footprints:C_0603_1608Metric" (layer "F.Cu")
    (at 166.75 128.589999 -90)
    (descr "Capacitor SMD 0603")
    (tags "capacitor 0603")
    (property "Author" "Antmicro")
    (property "Dielectric" "")
    (property "License" "Apache-2.0")
    (property "MPN" "CL10A226MO7JZNC")
    (property "Manufacturer" "Samsung")
    (property "Sheetfile" "dc-dc-conventers.kicad_sch")
    (property "Sheetname" "DC/DC conventers")
    (property "Val" "22u/16V")
    (property "Voltage" "")
    (property "ki_description" " ")
    (attr smd)
    (fp_text reference "C200" (at -1.565 3.55 -90) (layer "F.SilkS")
        (effects (font (size 0.7 0.7) (thickness 0.15)) (justify left bottom))
    )
    (fp_text value "C_22u_16V_0603" (at 0 1.6 -90) (layer "F.Fab") hide
        (effects (font (size 0.7 0.7) (thickness 0.15)) (justify left bottom))
    )
    (fp_text user "${REFERENCE}" (at -1.682 3.895 -90) (layer "F.Fab") hide
        (effects (font (size 0.7 0.7) (thickness 0.15)) (justify left bottom))
    )
    (fp_text user "Author: Antmicro" (at -1.682 4.894 -90) (layer "F.Fab") hide
        (effects (font (size 0.7 0.7) (thickness 0.15)) (justify left bottom))
    )
    (fp_text user "License: Apache-2.0" (at -1.682 5.895 -90) (layer "F.Fab") hide
        (effects (font (size 0.7 0.7) (thickness 0.15)) (justify left bottom))
    )
    (fp_line (start -0.3 -0.3) (end 0.3 -0.3)
      (stroke (width 0.15) (type solid)) (layer "F.SilkS"))
    (fp_line (start -0.3 0.3) (end 0.3 0.3)
      (stroke (width 0.15) (type solid)) (layer "F.SilkS"))
    (fp_rect (start -1.24 -0.7) (end 1.24 0.7)
      (stroke (width 0.05) (type solid)) (fill none) (layer "F.CrtYd"))
    (fp_rect (start -0.8 -0.4) (end 0.8 0.4)
      (stroke (width 0.15) (type solid)) (fill none) (layer "F.Fab"))
    (pad "1" smd roundrect (at -0.7 0 270) (size 0.6 0.8) (layers "F.Cu" "F.Paste" "F.Mask") (roundrect_rratio 0.2)
      (net 773 "/Power Supply/DC/DC conventers/SOM_5V_OUT") (pintype "passive"))
    (pad "2" smd roundrect (at 0.7 0 270) (size 0.6 0.8) (layers "F.Cu" "F.Paste" "F.Mask") (roundrect_rratio 0.2)
      (net 1 "GND") (pintype "passive"))
  )

  (footprint "kria-k26-devboard-footprints:C_0402_1005Metric" (layer "F.Cu")
    (at 173.825 127.725 -90)
    (descr "Capacitor SMD 0402")
    (tags "capacitor SMD 0402")
    (property "Author" "Antmicro")
    (property "Dielectric" "")
    (property "License" "Apache-2.0")
    (property "MPN" "CC0402JRNPO9BN220")
    (property "Manufacturer" "Yaego")
    (property "Sheetfile" "dc-dc-conventers.kicad_sch")
    (property "Sheetname" "DC/DC conventers")
    (property "Val" "22p")
    (property "Voltage" "")
    (property "ki_description" " ")
    (attr smd)
    (fp_text reference "C194" (at 1.395 2.595 -90) (layer "F.SilkS")
        (effects (font (size 0.7 0.7) (thickness 0.15)) (justify left bottom))
    )
    (fp_text value "C_22p_0402" (at 0 1.4 -90) (layer "F.Fab") hide
        (effects (font (size 0.7 0.7) (thickness 0.15)) (justify left bottom))
    )
    (fp_text user "License: Apache-2.0" (at -0.932 5.17 -90) (layer "F.Fab") hide
        (effects (font (size 0.7 0.7) (thickness 0.15)) (justify left bottom))
    )
    (fp_text user "${REFERENCE}" (at -0.932 3.168 -90) (layer "F.Fab") hide
        (effects (font (size 0.7 0.7) (thickness 0.15)) (justify left bottom))
    )
    (fp_text user "Author: Antmicro" (at -0.932 4.17 -90) (layer "F.Fab") hide
        (effects (font (size 0.7 0.7) (thickness 0.15)) (justify left bottom))
    )
    (fp_rect (start -0.94 -0.47) (end 0.94 0.47)
      (stroke (width 0.05) (type solid)) (fill none) (layer "F.CrtYd"))
    (fp_rect (start -0.499 -0.249) (end 0.499 0.249)
      (stroke (width 0.15) (type solid)) (fill none) (layer "F.Fab"))
    (pad "1" smd roundrect (at -0.484 0 270) (size 0.59 0.64) (layers "F.Cu" "F.Paste" "F.Mask") (roundrect_rratio 0.25)
      (net 255 "Net-(U48-FB)") (pintype "passive"))
    (pad "2" smd roundrect (at 0.484 0 270) (size 0.59 0.64) (layers "F.Cu" "F.Paste" "F.Mask") (roundrect_rratio 0.25)
      (net 774 "/Power Supply/DC/DC conventers/SOM_5V_FB") (pintype "passive"))
  )

  (footprint "kria-k26-devboard-footprints:C_0603_1608Metric" (layer "F.Cu")
    (at 168.2 128.59 -90)
    (descr "Capacitor SMD 0603")
    (tags "capacitor 0603")
    (property "Author" "Antmicro")
    (property "Dielectric" "")
    (property "License" "Apache-2.0")
    (property "MPN" "CL10A226MO7JZNC")
    (property "Manufacturer" "Samsung")
    (property "Sheetfile" "dc-dc-conventers.kicad_sch")
    (property "Sheetname" "DC/DC conventers")
    (property "Val" "22u/16V")
    (property "Voltage" "")
    (property "ki_description" " ")
    (attr smd)
    (fp_text reference "C198" (at -1.565001 3.91 -90) (layer "F.SilkS")
        (effects (font (size 0.7 0.7) (thickness 0.15)) (justify left bottom))
    )
    (fp_text value "C_22u_16V_0603" (at 0 1.6 -90) (layer "F.Fab") hide
        (effects (font (size 0.7 0.7) (thickness 0.15)) (justify left bottom))
    )
    (fp_text user "License: Apache-2.0" (at -1.682 5.895 -90) (layer "F.Fab") hide
        (effects (font (size 0.7 0.7) (thickness 0.15)) (justify left bottom))
    )
    (fp_text user "${REFERENCE}" (at -1.682 3.895 -90) (layer "F.Fab") hide
        (effects (font (size 0.7 0.7) (thickness 0.15)) (justify left bottom))
    )
    (fp_text user "Author: Antmicro" (at -1.682 4.894 -90) (layer "F.Fab") hide
        (effects (font (size 0.7 0.7) (thickness 0.15)) (justify left bottom))
    )
    (fp_line (start -0.3 -0.3) (end 0.3 -0.3)
      (stroke (width 0.15) (type solid)) (layer "F.SilkS"))
    (fp_line (start -0.3 0.3) (end 0.3 0.3)
      (stroke (width 0.15) (type solid)) (layer "F.SilkS"))
    (fp_rect (start -1.24 -0.7) (end 1.24 0.7)
      (stroke (width 0.05) (type solid)) (fill none) (layer "F.CrtYd"))
    (fp_rect (start -0.8 -0.4) (end 0.8 0.4)
      (stroke (width 0.15) (type solid)) (fill none) (layer "F.Fab"))
    (pad "1" smd roundrect (at -0.7 0 270) (size 0.6 0.8) (layers "F.Cu" "F.Paste" "F.Mask") (roundrect_rratio 0.2)
      (net 773 "/Power Supply/DC/DC conventers/SOM_5V_OUT") (pintype "passive"))
    (pad "2" smd roundrect (at 0.7 0 270) (size 0.6 0.8) (layers "F.Cu" "F.Paste" "F.Mask") (roundrect_rratio 0.2)
      (net 1 "GND") (pintype "passive"))
  )

  (footprint "kria-k26-devboard-footprints:TP_SMD_0.75mm" (layer "F.Cu")
    (at 87.65 123.05)
    (property "Author" "Antmicro")
    (property "License" "Apache-2.0")
    (property "MPN" "")
    (property "Manufacturer" "")
    (property "Sheetfile" "camera.kicad_sch")
    (property "Sheetname" "Camera interface")
    (property "ki_description" "Test Point 0.75mm")
    (attr exclude_from_pos_files)
    (fp_text reference "TP1" (at -0.93 1.23) (layer "F.SilkS")
        (effects (font (size 0.7 0.7) (thickness 0.15)) (justify left bottom))
    )
    (fp_text value "TP_0.75mm_SMD" (at 0 1.2) (layer "F.Fab") hide
        (effects (font (size 0.7 0.7) (thickness 0.15)) (justify left bottom))
    )
    (fp_text user "${REFERENCE}" (at -0.4 2.7) (layer "F.Fab") hide
        (effects (font (size 0.7 0.7) (thickness 0.15)) (justify left bottom))
    )
    (fp_text user "Author: Antmicro" (at -0.4 3.901) (layer "F.Fab") hide
        (effects (font (size 0.7 0.7) (thickness 0.15)) (justify left bottom))
    )
    (fp_text user "License: Apache-2.0" (at -0.4 5.101) (layer "F.Fab") hide
        (effects (font (size 0.7 0.7) (thickness 0.15)) (justify left bottom))
    )
    (pad "1" smd circle (at 0 0) (size 0.75 0.75) (layers "F.Cu" "F.Mask")
      (net 410 "/Camera interface/HDA00_CC") (pinfunction "1") (pintype "passive"))
  )

  (footprint "kria-k26-devboard-footprints:TP_SMD_0.75mm" (layer "F.Cu")
    (at 87.65 122.05)
    (property "Author" "Antmicro")
    (property "License" "Apache-2.0")
    (property "MPN" "")
    (property "Manufacturer" "")
    (property "Sheetfile" "camera.kicad_sch")
    (property "Sheetname" "Camera interface")
    (property "ki_description" "Test Point 0.75mm")
    (attr exclude_from_pos_files)
    (fp_text reference "TP2" (at -0.94 -0.44) (layer "F.SilkS")
        (effects (font (size 0.7 0.7) (thickness 0.15)) (justify left bottom))
    )
    (fp_text value "TP_0.75mm_SMD" (at 0 1.2) (layer "F.Fab") hide
        (effects (font (size 0.7 0.7) (thickness 0.15)) (justify left bottom))
    )
    (fp_text user "License: Apache-2.0" (at -0.4 5.101) (layer "F.Fab") hide
        (effects (font (size 0.7 0.7) (thickness 0.15)) (justify left bottom))
    )
    (fp_text user "${REFERENCE}" (at -0.4 2.7) (layer "F.Fab") hide
        (effects (font (size 0.7 0.7) (thickness 0.15)) (justify left bottom))
    )
    (fp_text user "Author: Antmicro" (at -0.4 3.901) (layer "F.Fab") hide
        (effects (font (size 0.7 0.7) (thickness 0.15)) (justify left bottom))
    )
    (pad "1" smd circle (at 0 0) (size 0.75 0.75) (layers "F.Cu" "F.Mask")
      (net 225 "/Camera interface/HDA01") (pinfunction "1") (pintype "passive"))
  )

  (footprint "kria-k26-devboard-footprints:TP_SMD_0.75mm" (layer "F.Cu")
    (at 83.45 116.9)
    (property "Author" "Antmicro")
    (property "License" "Apache-2.0")
    (property "MPN" "")
    (property "Manufacturer" "")
    (property "Sheetfile" "camera.kicad_sch")
    (property "Sheetname" "Camera interface")
    (property "ki_description" "Test Point 0.75mm")
    (attr exclude_from_pos_files)
    (fp_text reference "TP3" (at 0.26 0.23) (layer "F.SilkS")
        (effects (font (size 0.7 0.7) (thickness 0.15)) (justify left bottom))
    )
    (fp_text value "TP_0.75mm_SMD" (at 0 1.2) (layer "F.Fab") hide
        (effects (font (size 0.7 0.7) (thickness 0.15)) (justify left bottom))
    )
    (fp_text user "License: Apache-2.0" (at -0.4 5.101) (layer "F.Fab") hide
        (effects (font (size 0.7 0.7) (thickness 0.15)) (justify left bottom))
    )
    (fp_text user "${REFERENCE}" (at -0.4 2.7) (layer "F.Fab") hide
        (effects (font (size 0.7 0.7) (thickness 0.15)) (justify left bottom))
    )
    (fp_text user "Author: Antmicro" (at -0.4 3.901) (layer "F.Fab") hide
        (effects (font (size 0.7 0.7) (thickness 0.15)) (justify left bottom))
    )
    (pad "1" smd circle (at 0 0) (size 0.75 0.75) (layers "F.Cu" "F.Mask")
      (net 322 "PL_1V8") (pinfunction "1") (pintype "passive"))
  )

  (footprint "kria-k26-devboard-footprints:TP_SMD_0.75mm" (layer "F.Cu")
    (at 144.3 110.7)
    (property "Author" "Antmicro")
    (property "License" "Apache-2.0")
    (property "MPN" "")
    (property "Manufacturer" "")
    (property "Sheetfile" "debug.kicad_sch")
    (property "Sheetname" "Debug and JTAG")
    (property "ki_description" "Test Point 0.75mm")
    (attr exclude_from_pos_files)
    (fp_text reference "TP25" (at 0.85 -1.76 90) (layer "F.SilkS")
        (effects (font (size 0.7 0.7) (thickness 0.15)) (justify left bottom))
    )
    (fp_text value "TP_0.75mm_SMD" (at 0 1.2) (layer "F.Fab") hide
        (effects (font (size 0.7 0.7) (thickness 0.15)) (justify left bottom))
    )
    (fp_text user "${REFERENCE}" (at -0.4 2.7) (layer "F.Fab") hide
        (effects (font (size 0.7 0.7) (thickness 0.15)) (justify left bottom))
    )
    (fp_text user "Author: Antmicro" (at -0.4 3.901) (layer "F.Fab") hide
        (effects (font (size 0.7 0.7) (thickness 0.15)) (justify left bottom))
    )
    (fp_text user "License: Apache-2.0" (at -0.4 5.101) (layer "F.Fab") hide
        (effects (font (size 0.7 0.7) (thickness 0.15)) (justify left bottom))
    )
    (pad "1" smd circle (at 0 0) (size 0.75 0.75) (layers "F.Cu" "F.Mask")
      (net 133 "/Debug and JTAG/VCC_PD") (pinfunction "1") (pintype "passive"))
  )

  (footprint "kria-k26-devboard-footprints:TP_SMD_0.75mm" (layer "F.Cu")
    (at 151.5 113.45)
    (property "Author" "Antmicro")
    (property "License" "Apache-2.0")
    (property "MPN" "")
    (property "Manufacturer" "")
    (property "Sheetfile" "debug.kicad_sch")
    (property "Sheetname" "Debug and JTAG")
    (property "ki_description" "Test Point 0.75mm")
    (attr exclude_from_pos_files)
    (fp_text reference "TP28" (at 0.26 0.37) (layer "F.SilkS")
        (effects (font (size 0.7 0.7) (thickness 0.15)) (justify left bottom))
    )
    (fp_text value "TP_0.75mm_SMD" (at 0 1.2) (layer "F.Fab") hide
        (effects (font (size 0.7 0.7) (thickness 0.15)) (justify left bottom))
    )
    (fp_text user "Author: Antmicro" (at -0.4 3.901) (layer "F.Fab") hide
        (effects (font (size 0.7 0.7) (thickness 0.15)) (justify left bottom))
    )
    (fp_text user "${REFERENCE}" (at -0.4 2.7) (layer "F.Fab") hide
        (effects (font (size 0.7 0.7) (thickness 0.15)) (justify left bottom))
    )
    (fp_text user "License: Apache-2.0" (at -0.4 5.101) (layer "F.Fab") hide
        (effects (font (size 0.7 0.7) (thickness 0.15)) (justify left bottom))
    )
    (pad "1" smd circle (at 0 0) (size 0.75 0.75) (layers "F.Cu" "F.Mask")
      (net 135 "/Debug and JTAG/VCC_USB") (pinfunction "1") (pintype "passive"))
  )

  (footprint "kria-k26-devboard-footprints:Nexperia_SOD128" (layer "F.Cu")
    (at 185.865 124 -90)
    (property "Author" "Antmicro")
    (property "DNP" "DNP")
    (property "License" "Apache-2.0")
    (property "MPN" "PMEG3050EP,115")
    (property "Manufacturer" "Nexperia")
    (property "Sheetfile" "supply-oring.kicad_sch")
    (property "Sheetname" "Supply ORing")
    (property "dnp" "")
    (property "exclude_from_bom" "")
    (property "ki_description" "SCHOTTKY RECT 30V 5A, Vf=315 mV")
    (attr exclude_from_pos_files exclude_from_bom)
    (fp_text reference "D23" (at 2.65 -2.425 90) (layer "F.SilkS")
        (effects (font (size 0.7 0.7) (thickness 0.15)) (justify left bottom))
    )
    (fp_text value "PMEG3050EP,115" (at -4.37 2.5 -90) (layer "F.Fab") hide
        (effects (font (size 0.7 0.7) (thickness 0.15)) (justify left bottom))
    )
    (fp_text user "Author: Antmicro" (at -4.37 4.5 -90) (layer "F.Fab") hide
        (effects (font (size 0.7 0.7) (thickness 0.15)) (justify left bottom))
    )
    (fp_text user "License: Apache-2.0" (at -4.37 5.7 -90) (layer "F.Fab") hide
        (effects (font (size 0.7 0.7) (thickness 0.15)) (justify left bottom))
    )
    (fp_text user "${REFERENCE}" (at -4.37 6.9 -90) (layer "F.Fab") hide
        (effects (font (size 0.7 0.7) (thickness 0.15)) (justify left bottom))
    )
    (fp_line (start -2.121 -1.474) (end -2.121 -1.287)
      (stroke (width 0.15) (type solid)) (layer "F.SilkS"))
    (fp_line (start -2.121 1.284) (end -2.121 1.473)
      (stroke (width 0.15) (type solid)) (layer "F.SilkS"))
    (fp_line (start -2.121 1.473) (end 2.12 1.473)
      (stroke (width 0.15) (type solid)) (layer "F.SilkS"))
    (fp_line (start -1.6 -1.4) (end -1.6 1.4)
      (stroke (width 0.12) (type solid)) (layer "F.SilkS"))
    (fp_line (start 2.12 -1.474) (end -2.121 -1.474)
      (stroke (width 0.15) (type solid)) (layer "F.SilkS"))
    (fp_line (start 2.12 -1.287) (end 2.12 -1.474)
      (stroke (width 0.15) (type solid)) (layer "F.SilkS"))
    (fp_line (start 2.12 1.473) (end 2.12 1.284)
      (stroke (width 0.15) (type solid)) (layer "F.SilkS"))
    (fp_rect (start -2.8 -1.6) (end 2.8 1.6)
      (stroke (width 0.05) (type solid)) (fill none) (layer "F.CrtYd"))
    (fp_line (start -2.503 -0.954) (end -2.503 0.952)
      (stroke (width 0.15) (type solid)) (layer "F.Fab"))
    (fp_line (start -2.503 0.952) (end -1.994 0.952)
      (stroke (width 0.15) (type solid)) (layer "F.Fab"))
    (fp_line (start -1.994 -1.347) (end -1.994 1.346)
      (stroke (width 0.15) (type solid)) (layer "F.Fab"))
    (fp_line (start -1.994 -0.954) (end -2.503 -0.954)
      (stroke (width 0.15) (type solid)) (layer "F.Fab"))
    (fp_line (start -1.994 -0.675) (end -1.321 -1.347)
      (stroke (width 0.15) (type solid)) (layer "F.Fab"))
    (fp_line (start -1.994 0.673) (end -1.321 1.346)
      (stroke (width 0.15) (type solid)) (layer "F.Fab"))
    (fp_line (start -1.994 0.952) (end -1.994 -0.954)
      (stroke (width 0.15) (type solid)) (layer "F.Fab"))
    (fp_line (start -1.994 1.346) (end 1.993 1.346)
      (stroke (width 0.15) (type solid)) (layer "F.Fab"))
    (fp_line (start 1.993 -1.347) (end -1.994 -1.347)
      (stroke (width 0.15) (type solid)) (layer "F.Fab"))
    (fp_line (start 1.993 -0.954) (end 1.993 0.952)
      (stroke (width 0.15) (type solid)) (layer "F.Fab"))
    (fp_line (start 1.993 0.952) (end 2.5 0.952)
      (stroke (width 0.15) (type solid)) (layer "F.Fab"))
    (fp_line (start 1.993 1.346) (end 1.993 -1.347)
      (stroke (width 0.15) (type solid)) (layer "F.Fab"))
    (fp_line (start 2.5 -0.954) (end 1.993 -0.954)
      (stroke (width 0.15) (type solid)) (layer "F.Fab"))
    (fp_line (start 2.5 0.952) (end 2.5 -0.954)
      (stroke (width 0.15) (type solid)) (layer "F.Fab"))
    (pad "1" smd rect (at -2.298 0 270) (size 0.8096 1.905) (layers "F.Cu" "F.Paste" "F.Mask")
      (net 14 "/Power Supply/DC/DC conventers/DC_MAIN_BUS") (pinfunction "1") (pintype "passive"))
    (pad "2" smd rect (at 2.297 0 270) (size 0.8096 1.905) (layers "F.Cu" "F.Paste" "F.Mask")
      (net 13 "/Power Supply/PoE/POE_12V") (pinfunction "2") (pintype "passive"))
  )

  (footprint "kria-k26-devboard-footprints:C_0402_1005Metric" (layer "F.Cu")
    (at 186.9 114.77)
    (descr "Capacitor SMD 0402")
    (tags "capacitor SMD 0402")
    (property "Author" "Antmicro")
    (property "Dielectric" "X5R")
    (property "License" "Apache-2.0")
    (property "MPN" "GRM155R61H104KE14D")
    (property "Manufacturer" "Murata")
    (property "Sheetfile" "PoE.kicad_sch")
    (property "Sheetname" "PoE")
    (property "Val" "100n")
    (property "Voltage" "50V")
    (property "ki_description" "SMD Multilayer Ceramic Capacitor, 0.1 µF, 50 V, 0402 [1005 Metric], ± 10%, X5R, GRM Series")
    (property "ki_keywords" "0402, SMT, CAPACITOR, PASSIVE, CERAMIC, MLCC")
    (attr smd)
    (fp_text reference "C182" (at -1.48 -0.37) (layer "F.SilkS")
        (effects (font (size 0.7 0.7) (thickness 0.15)) (justify left bottom))
    )
    (fp_text value "C_100n_0402" (at 0 1.4) (layer "F.Fab") hide
        (effects (font (size 0.7 0.7) (thickness 0.15)) (justify left bottom))
    )
    (fp_text user "${REFERENCE}" (at -0.932 3.168) (layer "F.Fab") hide
        (effects (font (size 0.7 0.7) (thickness 0.15)) (justify left bottom))
    )
    (fp_text user "License: Apache-2.0" (at -0.932 5.17) (layer "F.Fab") hide
        (effects (font (size 0.7 0.7) (thickness 0.15)) (justify left bottom))
    )
    (fp_text user "Author: Antmicro" (at -0.932 4.17) (layer "F.Fab") hide
        (effects (font (size 0.7 0.7) (thickness 0.15)) (justify left bottom))
    )
    (fp_rect (start -0.94 -0.47) (end 0.94 0.47)
      (stroke (width 0.05) (type solid)) (fill none) (layer "F.CrtYd"))
    (fp_rect (start -0.499 -0.249) (end 0.499 0.249)
      (stroke (width 0.15) (type solid)) (fill none) (layer "F.Fab"))
    (pad "1" smd roundrect (at -0.484 0) (size 0.59 0.64) (layers "F.Cu" "F.Paste" "F.Mask") (roundrect_rratio 0.25)
      (net 13 "/Power Supply/PoE/POE_12V") (pintype "passive"))
    (pad "2" smd roundrect (at 0.484 0) (size 0.59 0.64) (layers "F.Cu" "F.Paste" "F.Mask") (roundrect_rratio 0.25)
      (net 1 "GND") (pintype "passive"))
  )

  (footprint "kria-k26-devboard-footprints:R_0402_1005Metric" (layer "F.Cu")
    (at 173.25 132.639999 -90)
    (descr "Resistor SMD 0402")
    (tags "resistor SMD 0402")
    (property "Author" "Antmicro")
    (property "License" "Apache-2.0")
    (property "MPN" "CR0402-FX-1002GLF")
    (property "Manufacturer" "Bourns")
    (property "Sheetfile" "dc-dc-conventers.kicad_sch")
    (property "Sheetname" "DC/DC conventers")
    (property "Tolerance" "1%")
    (property "Val" "10k")
    (property "ki_description" "10k resistor in 0402 package with 1% tolerance")
    (attr smd)
    (fp_text reference "R132" (at 1.330001 -1.21 -90) (layer "F.SilkS")
        (effects (font (size 0.7 0.7) (thickness 0.15)) (justify left bottom))
    )
    (fp_text value "R_10k_0402" (at 0 1.4 -90) (layer "F.Fab") hide
        (effects (font (size 0.7 0.7) (thickness 0.15)) (justify left bottom))
    )
    (fp_text user "${REFERENCE}" (at -0.95 3.168 -90) (layer "F.Fab") hide
        (effects (font (size 0.7 0.7) (thickness 0.15)) (justify left bottom))
    )
    (fp_text user "License: Apache-2.0" (at -0.95 5.169 -90) (layer "F.Fab") hide
        (effects (font (size 0.7 0.7) (thickness 0.15)) (justify left bottom))
    )
    (fp_text user "Author: Antmicro" (at -0.95 4.169 -90) (layer "F.Fab") hide
        (effects (font (size 0.7 0.7) (thickness 0.15)) (justify left bottom))
    )
    (fp_rect (start -0.93 -0.47) (end 0.93 0.47)
      (stroke (width 0.05) (type solid)) (fill none) (layer "F.CrtYd"))
    (fp_rect (start -0.5 -0.25) (end 0.5 0.25)
      (stroke (width 0.15) (type solid)) (fill none) (layer "F.Fab"))
    (pad "1" smd roundrect (at -0.485 0 270) (size 0.59 0.64) (layers "F.Cu" "F.Paste" "F.Mask") (roundrect_rratio 0.25)
      (net 688 "Net-(U49-FB)") (pintype "passive"))
    (pad "2" smd roundrect (at 0.485 0 270) (size 0.59 0.64) (layers "F.Cu" "F.Paste" "F.Mask") (roundrect_rratio 0.25)
      (net 1 "GND") (pintype "passive"))
  )

  (footprint "kria-k26-devboard-footprints:R_0402_1005Metric" (layer "F.Cu")
    (at 171.380001 132.375)
    (descr "Resistor SMD 0402")
    (tags "resistor SMD 0402")
    (property "Author" "Antmicro")
    (property "License" "Apache-2.0")
    (property "MPN" "CR0402-FX-3162GLF")
    (property "Manufacturer" "Bourns")
    (property "Sheetfile" "dc-dc-conventers.kicad_sch")
    (property "Sheetname" "DC/DC conventers")
    (property "Tolerance" "1%")
    (property "Val" "31k6")
    (property "ki_description" "31k6 resistor in 0402 package with 1% tolerance")
    (attr smd)
    (fp_text reference "R131" (at 1.049999 2.325) (layer "F.SilkS")
        (effects (font (size 0.7 0.7) (thickness 0.15)) (justify left bottom))
    )
    (fp_text value "R_31k6_0402" (at 0 1.4) (layer "F.Fab") hide
        (effects (font (size 0.7 0.7) (thickness 0.15)) (justify left bottom))
    )
    (fp_text user "License: Apache-2.0" (at -0.95 5.169) (layer "F.Fab") hide
        (effects (font (size 0.7 0.7) (thickness 0.15)) (justify left bottom))
    )
    (fp_text user "${REFERENCE}" (at -0.95 3.168) (layer "F.Fab") hide
        (effects (font (size 0.7 0.7) (thickness 0.15)) (justify left bottom))
    )
    (fp_text user "Author: Antmicro" (at -0.95 4.169) (layer "F.Fab") hide
        (effects (font (size 0.7 0.7) (thickness 0.15)) (justify left bottom))
    )
    (fp_rect (start -0.93 -0.47) (end 0.93 0.47)
      (stroke (width 0.05) (type solid)) (fill none) (layer "F.CrtYd"))
    (fp_rect (start -0.5 -0.25) (end 0.5 0.25)
      (stroke (width 0.15) (type solid)) (fill none) (layer "F.Fab"))
    (pad "1" smd roundrect (at -0.485 0) (size 0.59 0.64) (layers "F.Cu" "F.Paste" "F.Mask") (roundrect_rratio 0.25)
      (net 765 "/Power Supply/DC/DC conventers/PS_3V3_OUT") (pintype "passive"))
    (pad "2" smd roundrect (at 0.485 0) (size 0.59 0.64) (layers "F.Cu" "F.Paste" "F.Mask") (roundrect_rratio 0.25)
      (net 688 "Net-(U49-FB)") (pintype "passive"))
  )

  (footprint "kria-k26-devboard-footprints:TP_SMD_0.75mm" (layer "F.Cu")
    (at 153.265 118.65)
    (property "Author" "Antmicro")
    (property "License" "Apache-2.0")
    (property "MPN" "")
    (property "Manufacturer" "")
    (property "Sheetfile" "debug.kicad_sch")
    (property "Sheetname" "Debug and JTAG")
    (property "ki_description" "Test Point 0.75mm")
    (attr exclude_from_pos_files)
    (fp_text reference "TP24" (at 1.255 1.19 90) (layer "F.SilkS")
        (effects (font (size 0.7 0.7) (thickness 0.15)) (justify left bottom))
    )
    (fp_text value "TP_0.75mm_SMD" (at 0 1.2) (layer "F.Fab") hide
        (effects (font (size 0.7 0.7) (thickness 0.15)) (justify left bottom))
    )
    (fp_text user "${REFERENCE}" (at -0.4 2.7) (layer "F.Fab") hide
        (effects (font (size 0.7 0.7) (thickness 0.15)) (justify left bottom))
    )
    (fp_text user "Author: Antmicro" (at -0.4 3.901) (layer "F.Fab") hide
        (effects (font (size 0.7 0.7) (thickness 0.15)) (justify left bottom))
    )
    (fp_text user "License: Apache-2.0" (at -0.4 5.101) (layer "F.Fab") hide
        (effects (font (size 0.7 0.7) (thickness 0.15)) (justify left bottom))
    )
    (pad "1" smd circle (at 0 0) (size 0.75 0.75) (layers "F.Cu" "F.Mask")
      (net 132 "/Debug and JTAG/USB_1V2") (pinfunction "1") (pintype "passive"))
  )

  (footprint "kria-k26-devboard-footprints:TP_SMD_0.75mm" (layer "F.Cu")
    (at 153.3 123.5)
    (property "Author" "Antmicro")
    (property "License" "Apache-2.0")
    (property "MPN" "")
    (property "Manufacturer" "")
    (property "Sheetfile" "debug.kicad_sch")
    (property "Sheetname" "Debug and JTAG")
    (property "ki_description" "Test Point 0.75mm")
    (attr exclude_from_pos_files)
    (fp_text reference "TP26" (at 1.19 1.11 90) (layer "F.SilkS")
        (effects (font (size 0.7 0.7) (thickness 0.15)) (justify left bottom))
    )
    (fp_text value "TP_0.75mm_SMD" (at 0 1.2) (layer "F.Fab") hide
        (effects (font (size 0.7 0.7) (thickness 0.15)) (justify left bottom))
    )
    (fp_text user "${REFERENCE}" (at -0.4 2.7) (layer "F.Fab") hide
        (effects (font (size 0.7 0.7) (thickness 0.15)) (justify left bottom))
    )
    (fp_text user "License: Apache-2.0" (at -0.4 5.101) (layer "F.Fab") hide
        (effects (font (size 0.7 0.7) (thickness 0.15)) (justify left bottom))
    )
    (fp_text user "Author: Antmicro" (at -0.4 3.901) (layer "F.Fab") hide
        (effects (font (size 0.7 0.7) (thickness 0.15)) (justify left bottom))
    )
    (pad "1" smd circle (at 0 0) (size 0.75 0.75) (layers "F.Cu" "F.Mask")
      (net 134 "/Debug and JTAG/VREGIN") (pinfunction "1") (pintype "passive"))
  )

  (footprint "kria-k26-devboard-footprints:C_0402_1005Metric" (layer "F.Cu")
    (at 185.6 135.825 -90)
    (descr "Capacitor SMD 0402")
    (tags "capacitor SMD 0402")
    (property "Author" "Antmicro")
    (property "Dielectric" "X5R")
    (property "License" "Apache-2.0")
    (property "MPN" "GRM155R61H104KE14D")
    (property "Manufacturer" "Murata")
    (property "Sheetfile" "dc-dc-conventers.kicad_sch")
    (property "Sheetname" "DC/DC conventers")
    (property "Val" "100n")
    (property "Voltage" "50V")
    (property "ki_description" " ")
    (attr smd)
    (fp_text reference "C222" (at -6.225 1.65 180) (layer "F.SilkS")
        (effects (font (size 0.7 0.7) (thickness 0.15)) (justify left bottom))
    )
    (fp_text value "C_100n_0402" (at 0 1.4 -90) (layer "F.Fab") hide
        (effects (font (size 0.7 0.7) (thickness 0.15)) (justify left bottom))
    )
    (fp_text user "${REFERENCE}" (at -0.932 3.168 -90) (layer "F.Fab") hide
        (effects (font (size 0.7 0.7) (thickness 0.15)) (justify left bottom))
    )
    (fp_text user "Author: Antmicro" (at -0.932 4.17 -90) (layer "F.Fab") hide
        (effects (font (size 0.7 0.7) (thickness 0.15)) (justify left bottom))
    )
    (fp_text user "License: Apache-2.0" (at -0.932 5.17 -90) (layer "F.Fab") hide
        (effects (font (size 0.7 0.7) (thickness 0.15)) (justify left bottom))
    )
    (fp_rect (start -0.94 -0.47) (end 0.94 0.47)
      (stroke (width 0.05) (type solid)) (fill none) (layer "F.CrtYd"))
    (fp_rect (start -0.499 -0.249) (end 0.499 0.249)
      (stroke (width 0.15) (type solid)) (fill none) (layer "F.Fab"))
    (pad "1" smd roundrect (at -0.484 0 270) (size 0.59 0.64) (layers "F.Cu" "F.Paste" "F.Mask") (roundrect_rratio 0.25)
      (net 326 "Net-(U55-BST)") (pintype "passive"))
    (pad "2" smd roundrect (at 0.484 0 270) (size 0.59 0.64) (layers "F.Cu" "F.Paste" "F.Mask") (roundrect_rratio 0.25)
      (net 316 "/Power Supply/DC/DC conventers/SW_PL_1V2") (pintype "passive"))
  )

  (footprint "kria-k26-devboard-footprints:TP_SMD_0.75mm" (layer "F.Cu")
    (at 165.725 128.35)
    (property "Author" "Antmicro")
    (property "License" "Apache-2.0")
    (property "MPN" "")
    (property "Manufacturer" "")
    (property "Sheetfile" "dc-dc-conventers.kicad_sch")
    (property "Sheetname" "DC/DC conventers")
    (property "ki_description" "Test Point 0.75mm")
    (attr exclude_from_pos_files)
    (fp_text reference "TP50" (at -3.495 -1.65 90) (layer "F.SilkS")
        (effects (font (size 0.7 0.7) (thickness 0.15)) (justify left bottom))
    )
    (fp_text value "TP_0.75mm_SMD" (at 0 1.2) (layer "F.Fab") hide
        (effects (font (size 0.7 0.7) (thickness 0.15)) (justify left bottom))
    )
    (fp_text user "Author: Antmicro" (at -0.4 3.901) (layer "F.Fab") hide
        (effects (font (size 0.7 0.7) (thickness 0.15)) (justify left bottom))
    )
    (fp_text user "License: Apache-2.0" (at -0.4 5.101) (layer "F.Fab") hide
        (effects (font (size 0.7 0.7) (thickness 0.15)) (justify left bottom))
    )
    (fp_text user "${REFERENCE}" (at -0.4 2.7) (layer "F.Fab") hide
        (effects (font (size 0.7 0.7) (thickness 0.15)) (justify left bottom))
    )
    (pad "1" smd circle (at 0 0) (size 0.75 0.75) (layers "F.Cu" "F.Mask")
      (net 773 "/Power Supply/DC/DC conventers/SOM_5V_OUT") (pinfunction "1") (pintype "passive"))
  )

  (footprint "kria-k26-devboard-footprints:TP_SMD_0.75mm" (layer "F.Cu")
    (at 149.75 79.0008)
    (property "Author" "Antmicro")
    (property "License" "Apache-2.0")
    (property "MPN" "")
    (property "Manufacturer" "")
    (property "Sheetfile" "dc-dc-conventers.kicad_sch")
    (property "Sheetname" "DC/DC conventers")
    (property "ki_description" "Test Point 0.75mm")
    (attr exclude_from_pos_files)
    (fp_text reference "TP51" (at -1.3 1.2192) (layer "F.SilkS")
        (effects (font (size 0.7 0.7) (thickness 0.15)) (justify left bottom))
    )
    (fp_text value "TP_0.75mm_SMD" (at 0 1.2) (layer "F.Fab") hide
        (effects (font (size 0.7 0.7) (thickness 0.15)) (justify left bottom))
    )
    (fp_text user "Author: Antmicro" (at -0.4 3.901) (layer "F.Fab") hide
        (effects (font (size 0.7 0.7) (thickness 0.15)) (justify left bottom))
    )
    (fp_text user "${REFERENCE}" (at -0.4 2.7) (layer "F.Fab") hide
        (effects (font (size 0.7 0.7) (thickness 0.15)) (justify left bottom))
    )
    (fp_text user "License: Apache-2.0" (at -0.4 5.101) (layer "F.Fab") hide
        (effects (font (size 0.7 0.7) (thickness 0.15)) (justify left bottom))
    )
    (pad "1" smd circle (at 0 0) (size 0.75 0.75) (layers "F.Cu" "F.Mask")
      (net 772 "/Power Supply/DC/DC conventers/USB_5V_OUT") (pinfunction "1") (pintype "passive"))
  )

  (footprint "kria-k26-devboard-footprints:R_0402_1005Metric" (layer "F.Cu")
    (at 179.2 137.725001 180)
    (descr "Resistor SMD 0402")
    (tags "resistor SMD 0402")
    (property "Author" "Antmicro")
    (property "License" "Apache-2.0")
    (property "MPN" "CR0402-FX-1001GLF")
    (property "Manufacturer" "Bourns")
    (property "Sheetfile" "dc-dc-conventers.kicad_sch")
    (property "Sheetname" "DC/DC conventers")
    (property "Tolerance" "1%")
    (property "Val" "1k")
    (property "ki_description" "1k resistor in 0402 package with 1% tolerance")
    (attr smd)
    (fp_text reference "R142" (at 0.33 -3.194999 270) (layer "F.SilkS")
        (effects (font (size 0.7 0.7) (thickness 0.15)) (justify left bottom))
    )
    (fp_text value "R_1k_0402" (at 0 1.4 180) (layer "F.Fab") hide
        (effects (font (size 0.7 0.7) (thickness 0.15)) (justify left bottom))
    )
    (fp_text user "License: Apache-2.0" (at -0.95 5.169 180) (layer "F.Fab") hide
        (effects (font (size 0.7 0.7) (thickness 0.15)) (justify left bottom))
    )
    (fp_text user "${REFERENCE}" (at -0.95 3.168 180) (layer "F.Fab") hide
        (effects (font (size 0.7 0.7) (thickness 0.15)) (justify left bottom))
    )
    (fp_text user "Author: Antmicro" (at -0.95 4.169 180) (layer "F.Fab") hide
        (effects (font (size 0.7 0.7) (thickness 0.15)) (justify left bottom))
    )
    (fp_rect (start -0.93 -0.47) (end 0.93 0.47)
      (stroke (width 0.05) (type solid)) (fill none) (layer "F.CrtYd"))
    (fp_rect (start -0.5 -0.25) (end 0.5 0.25)
      (stroke (width 0.15) (type solid)) (fill none) (layer "F.Fab"))
    (pad "1" smd roundrect (at -0.485 0 180) (size 0.59 0.64) (layers "F.Cu" "F.Paste" "F.Mask") (roundrect_rratio 0.25)
      (net 770 "/Power Supply/DC/DC conventers/PL_3V3_OUT") (pintype "passive"))
    (pad "2" smd roundrect (at 0.485 0 180) (size 0.59 0.64) (layers "F.Cu" "F.Paste" "F.Mask") (roundrect_rratio 0.25)
      (net 191 "Net-(D19-Pad1)") (pintype "passive"))
  )

  (footprint "kria-k26-devboard-footprints:USON-10_2.5x1mm_P0.5mm" (layer "F.Cu")
    (at 110.402 73.3305 90)
    (descr "USON-10 2.5x1mm_ Pitch 0.5mm")
    (tags "USON-10 2.5x1mm Pitch 0.5mm")
    (property "Author" "Antmicro")
    (property "License" "Apache-2.0")
    (property "MPN" "TPD4E05U06QDQARQ1")
    (property "Manufacturer" "Texas Instruments")
    (property "Sheetfile" "usb.kicad_sch")
    (property "Sheetname" "USB")
    (property "ki_description" "ESD protection")
    (property "ki_keywords" "SMT, DIODE, IC, TVS, ESD")
    (attr smd)
    (fp_text reference "U25" (at 0.018 -1.7 90) (layer "F.SilkS")
        (effects (font (size 0.7 0.7) (thickness 0.15)) (justify left bottom))
    )
    (fp_text value "TPD4E05U06QDQARQ1" (at 0.018 2.499 90) (layer "F.Fab")
        (effects (font (size 0.7 0.7) (thickness 0.15)) (justify left bottom))
    )
    (fp_text user "License: Apache-2.0" (at -0.802 6.9 90) (layer "F.Fab") hide
        (effects (font (size 0.7 0.7) (thickness 0.15)) (justify left bottom))
    )
    (fp_text user "${REFERENCE}" (at -0.802 4.498 90) (layer "F.Fab") hide
        (effects (font (size 0.7 0.7) (thickness 0.15)) (justify left bottom))
    )
    (fp_text user "Author: Antmicro" (at -0.802 5.7 90) (layer "F.Fab") hide
        (effects (font (size 0.7 0.7) (thickness 0.15)) (justify left bottom))
    )
    (fp_line (start 0.498 -1.401) (end -0.5 -1.401)
      (stroke (width 0.15) (type solid)) (layer "F.SilkS"))
    (fp_line (start 0.498 1.398) (end -0.5 1.398)
      (stroke (width 0.15) (type solid)) (layer "F.SilkS"))
    (fp_circle (center -0.68 -1.27) (end -0.63 -1.27)
      (stroke (width 0.15) (type solid)) (fill solid) (layer "F.SilkS"))
    (fp_rect (start -0.8 -1.5) (end 0.8 1.499)
      (stroke (width 0.05) (type solid)) (fill none) (layer "F.CrtYd"))
    (fp_line (start -0.5 -1) (end -0.5 1.249)
      (stroke (width 0.15) (type solid)) (layer "F.Fab"))
    (fp_line (start -0.5 1.249) (end 0.498 1.249)
      (stroke (width 0.15) (type solid)) (layer "F.Fab"))
    (fp_line (start -0.25 -1.25) (end -0.5 -1)
      (stroke (width 0.15) (type solid)) (layer "F.Fab"))
    (fp_line (start 0.498 -1.25) (end -0.25 -1.25)
      (stroke (width 0.15) (type solid)) (layer "F.Fab"))
    (fp_line (start 0.498 -1.25) (end 0.498 1.249)
      (stroke (width 0.15) (type solid)) (layer "F.Fab"))
    (pad "1" smd roundrect (at -0.387 -1) (size 0.25 0.55) (layers "F.Cu" "F.Paste" "F.Mask") (roundrect_rratio 0.25)
      (net 73 "/USB/USB4_RX_N") (pintype "passive"))
    (pad "2" smd roundrect (at -0.387 -0.5) (size 0.25 0.55) (layers "F.Cu" "F.Paste" "F.Mask") (roundrect_rratio 0.25)
      (net 74 "/USB/USB4_RX_P") (pintype "passive"))
    (pad "3" smd roundrect (at -0.387 0) (size 0.4 0.55) (layers "F.Cu" "F.Paste" "F.Mask") (roundrect_rratio 0.25)
      (net 1 "GND") (pintype "power_in"))
    (pad "4" smd roundrect (at -0.387 0.498) (size 0.25 0.55) (layers "F.Cu" "F.Paste" "F.Mask") (roundrect_rratio 0.25)
      (net 284 "/USB/USB4_TX_C_N") (pintype "passive"))
    (pad "5" smd roundrect (at -0.387 0.998) (size 0.25 0.55) (layers "F.Cu" "F.Paste" "F.Mask") (roundrect_rratio 0.25)
      (net 285 "/USB/USB4_TX_C_P") (pintype "passive"))
    (pad "6" smd roundrect (at 0.385 0.998) (size 0.25 0.55) (layers "F.Cu" "F.Paste" "F.Mask") (roundrect_rratio 0.25)
      (net 285 "/USB/USB4_TX_C_P") (pintype "passive"))
    (pad "7" smd roundrect (at 0.385 0.498) (size 0.25 0.55) (layers "F.Cu" "F.Paste" "F.Mask") (roundrect_rratio 0.25)
      (net 284 "/USB/USB4_TX_C_N") (pintype "passive"))
    (pad "8" smd roundrect (at 0.385 0) (size 0.4 0.55) (layers "F.Cu" "F.Paste" "F.Mask") (roundrect_rratio 0.25)
      (net 1 "GND") (pintype "passive"))
    (pad "9" smd roundrect (at 0.385 -0.5) (size 0.25 0.55) (layers "F.Cu" "F.Paste" "F.Mask") (roundrect_rratio 0.25)
      (net 74 "/USB/USB4_RX_P") (pintype "passive"))
    (pad "10" smd roundrect (at 0.385 -1) (size 0.25 0.55) (layers "F.Cu" "F.Paste" "F.Mask") (roundrect_rratio 0.25)
      (net 73 "/USB/USB4_RX_N") (pintype "passive"))
  )

  (footprint "kria-k26-devboard-footprints:C_0805_2012Metric" (layer "F.Cu")
    (at 86.2 97.7 180)
    (descr "Capacitor SMD 0805")
    (tags "capacitor SMD 0805")
    (property "Author" "Antmicro")
    (property "Dielectric" "")
    (property "License" "Apache-2.0")
    (property "MPN" "C0805C476M9PACTU")
    (property "Manufacturer" "KEMET")
    (property "Sheetfile" "k26_som.kicad_sch")
    (property "Sheetname" "Xilinx K26 SOM")
    (property "Val" "47u")
    (property "Voltage" "")
    (property "ki_description" " ")
    (attr smd)
    (fp_text reference "C116" (at 4.55 -0.36 180) (layer "F.SilkS")
        (effects (font (size 0.7 0.7) (thickness 0.15)) (justify left bottom))
    )
    (fp_text value "C_47u_0805" (at 0 1.947 180) (layer "F.Fab") hide
        (effects (font (size 0.7 0.7) (thickness 0.15)) (justify left bottom))
    )
    (fp_text user "Author: Antmicro" (at -1.9 5.947 180) (layer "F.Fab") hide
        (effects (font (size 0.7 0.7) (thickness 0.15)) (justify left bottom))
    )
    (fp_text user "${REFERENCE}" (at -1.9 3.947 180) (layer "F.Fab") hide
        (effects (font (size 0.7 0.7) (thickness 0.15)) (justify left bottom))
    )
    (fp_text user "License: Apache-2.0" (at -1.9 4.947 180) (layer "F.Fab") hide
        (effects (font (size 0.7 0.7) (thickness 0.15)) (justify left bottom))
    )
    (fp_line (start -0.3 -0.8) (end 0.3 -0.8)
      (stroke (width 0.15) (type solid)) (layer "F.SilkS"))
    (fp_line (start -0.3 0.8) (end 0.3 0.8)
      (stroke (width 0.15) (type solid)) (layer "F.SilkS"))
    (fp_rect (start -1.9 -0.93) (end 1.9 0.93)
      (stroke (width 0.05) (type solid)) (fill none) (layer "F.CrtYd"))
    (fp_rect (start -0.95 -0.675) (end 0.95 0.675)
      (stroke (width 0.15) (type solid)) (fill none) (layer "F.Fab"))
    (pad "1" smd rect (at -1.05 0 180) (size 1.2 1.2) (layers "F.Cu" "F.Paste" "F.Mask")
      (net 8 "SOM_5V0") (pintype "passive"))
    (pad "2" smd rect (at 1.05 0 180) (size 1.2 1.2) (layers "F.Cu" "F.Paste" "F.Mask")
      (net 1 "GND") (pintype "passive"))
  )

  (footprint "kria-k26-devboard-footprints:TP_SMD_0.75mm" (layer "F.Cu")
    (at 109.3 146.5)
    (property "Author" "Antmicro")
    (property "License" "Apache-2.0")
    (property "MPN" "")
    (property "Manufacturer" "")
    (property "Sheetfile" "reset.kicad_sch")
    (property "Sheetname" "Reset logic")
    (property "ki_description" "Test Point 0.75mm")
    (attr exclude_from_pos_files)
    (fp_text reference "TP17" (at 7.33 0.86 90) (layer "F.SilkS")
        (effects (font (size 0.7 0.7) (thickness 0.15)) (justify left bottom))
    )
    (fp_text value "TP_0.75mm_SMD" (at 0 1.2) (layer "F.Fab") hide
        (effects (font (size 0.7 0.7) (thickness 0.15)) (justify left bottom))
    )
    (fp_text user "License: Apache-2.0" (at -0.4 5.101) (layer "F.Fab") hide
        (effects (font (size 0.7 0.7) (thickness 0.15)) (justify left bottom))
    )
    (fp_text user "${REFERENCE}" (at -0.4 2.7) (layer "F.Fab") hide
        (effects (font (size 0.7 0.7) (thickness 0.15)) (justify left bottom))
    )
    (fp_text user "Author: Antmicro" (at -0.4 3.901) (layer "F.Fab") hide
        (effects (font (size 0.7 0.7) (thickness 0.15)) (justify left bottom))
    )
    (pad "1" smd circle (at 0 0) (size 0.75 0.75) (layers "F.Cu" "F.Mask")
      (net 177 "/Reset logic/~{SD_CARD_RESET}") (pinfunction "1") (pintype "passive"))
  )

  (footprint "kria-k26-devboard-footprints:TP_SMD_0.75mm" (layer "F.Cu")
    (at 110.3 146.5)
    (property "Author" "Antmicro")
    (property "License" "Apache-2.0")
    (property "MPN" "")
    (property "Manufacturer" "")
    (property "Sheetfile" "reset.kicad_sch")
    (property "Sheetname" "Reset logic")
    (property "ki_description" "Test Point 0.75mm")
    (attr exclude_from_pos_files)
    (fp_text reference "TP18" (at 7.33 0.86 90) (layer "F.SilkS")
        (effects (font (size 0.7 0.7) (thickness 0.15)) (justify left bottom))
    )
    (fp_text value "TP_0.75mm_SMD" (at 0 1.2) (layer "F.Fab") hide
        (effects (font (size 0.7 0.7) (thickness 0.15)) (justify left bottom))
    )
    (fp_text user "${REFERENCE}" (at -0.4 2.7) (layer "F.Fab") hide
        (effects (font (size 0.7 0.7) (thickness 0.15)) (justify left bottom))
    )
    (fp_text user "Author: Antmicro" (at -0.4 3.901) (layer "F.Fab") hide
        (effects (font (size 0.7 0.7) (thickness 0.15)) (justify left bottom))
    )
    (fp_text user "License: Apache-2.0" (at -0.4 5.101) (layer "F.Fab") hide
        (effects (font (size 0.7 0.7) (thickness 0.15)) (justify left bottom))
    )
    (pad "1" smd circle (at 0 0) (size 0.75 0.75) (layers "F.Cu" "F.Mask")
      (net 178 "/Reset logic/~{USB_PHY_RESET}") (pinfunction "1") (pintype "passive"))
  )

  (footprint "kria-k26-devboard-footprints:TP_SMD_0.75mm" (layer "F.Cu")
    (at 112.3 146.5)
    (property "Author" "Antmicro")
    (property "License" "Apache-2.0")
    (property "MPN" "")
    (property "Manufacturer" "")
    (property "Sheetfile" "reset.kicad_sch")
    (property "Sheetname" "Reset logic")
    (property "ki_description" "Test Point 0.75mm")
    (attr exclude_from_pos_files)
    (fp_text reference "TP20" (at 7.33 0.86 90) (layer "F.SilkS")
        (effects (font (size 0.7 0.7) (thickness 0.15)) (justify left bottom))
    )
    (fp_text value "TP_0.75mm_SMD" (at 0 1.2) (layer "F.Fab") hide
        (effects (font (size 0.7 0.7) (thickness 0.15)) (justify left bottom))
    )
    (fp_text user "Author: Antmicro" (at -0.4 3.901) (layer "F.Fab") hide
        (effects (font (size 0.7 0.7) (thickness 0.15)) (justify left bottom))
    )
    (fp_text user "License: Apache-2.0" (at -0.4 5.101) (layer "F.Fab") hide
        (effects (font (size 0.7 0.7) (thickness 0.15)) (justify left bottom))
    )
    (fp_text user "${REFERENCE}" (at -0.4 2.7) (layer "F.Fab") hide
        (effects (font (size 0.7 0.7) (thickness 0.15)) (justify left bottom))
    )
    (pad "1" smd circle (at 0 0) (size 0.75 0.75) (layers "F.Cu" "F.Mask")
      (net 176 "/Ethernet/~{ETH_RESET}") (pinfunction "1") (pintype "passive"))
  )

  (footprint "kria-k26-devboard-footprints:TP_SMD_0.75mm" (layer "F.Cu")
    (at 115.3 146.5)
    (property "Author" "Antmicro")
    (property "License" "Apache-2.0")
    (property "MPN" "")
    (property "Manufacturer" "")
    (property "Sheetfile" "reset.kicad_sch")
    (property "Sheetname" "Reset logic")
    (property "ki_description" "Test Point 0.75mm")
    (attr exclude_from_pos_files)
    (fp_text reference "TP21" (at 7.33 0.86 90) (layer "F.SilkS")
        (effects (font (size 0.7 0.7) (thickness 0.15)) (justify left bottom))
    )
    (fp_text value "TP_0.75mm_SMD" (at 0 1.2) (layer "F.Fab") hide
        (effects (font (size 0.7 0.7) (thickness 0.15)) (justify left bottom))
    )
    (fp_text user "Author: Antmicro" (at -0.4 3.901) (layer "F.Fab") hide
        (effects (font (size 0.7 0.7) (thickness 0.15)) (justify left bottom))
    )
    (fp_text user "License: Apache-2.0" (at -0.4 5.101) (layer "F.Fab") hide
        (effects (font (size 0.7 0.7) (thickness 0.15)) (justify left bottom))
    )
    (fp_text user "${REFERENCE}" (at -0.4 2.7) (layer "F.Fab") hide
        (effects (font (size 0.7 0.7) (thickness 0.15)) (justify left bottom))
    )
    (pad "1" smd circle (at 0 0) (size 0.75 0.75) (layers "F.Cu" "F.Mask")
      (net 1 "GND") (pinfunction "1") (pintype "passive"))
  )

  (footprint "kria-k26-devboard-footprints:TP_SMD_0.75mm" (layer "F.Cu")
    (at 113.3 146.49)
    (property "Author" "Antmicro")
    (property "License" "Apache-2.0")
    (property "MPN" "")
    (property "Manufacturer" "")
    (property "Sheetfile" "reset.kicad_sch")
    (property "Sheetname" "Reset logic")
    (property "ki_description" "Test Point 0.75mm")
    (attr exclude_from_pos_files)
    (fp_text reference "TP22" (at 7.33 0.86 90) (layer "F.SilkS")
        (effects (font (size 0.7 0.7) (thickness 0.15)) (justify left bottom))
    )
    (fp_text value "TP_0.75mm_SMD" (at 0 1.2) (layer "F.Fab") hide
        (effects (font (size 0.7 0.7) (thickness 0.15)) (justify left bottom))
    )
    (fp_text user "${REFERENCE}" (at -0.4 2.7) (layer "F.Fab") hide
        (effects (font (size 0.7 0.7) (thickness 0.15)) (justify left bottom))
    )
    (fp_text user "License: Apache-2.0" (at -0.4 5.101) (layer "F.Fab") hide
        (effects (font (size 0.7 0.7) (thickness 0.15)) (justify left bottom))
    )
    (fp_text user "Author: Antmicro" (at -0.4 3.901) (layer "F.Fab") hide
        (effects (font (size 0.7 0.7) (thickness 0.15)) (justify left bottom))
    )
    (pad "1" smd circle (at 0 0) (size 0.75 0.75) (layers "F.Cu" "F.Mask")
      (net 198 "/Camera interface/CAM0_RST") (pinfunction "1") (pintype "passive"))
  )

  (footprint "kria-k26-devboard-footprints:TP_SMD_0.75mm" (layer "F.Cu")
    (at 114.3 146.5)
    (property "Author" "Antmicro")
    (property "License" "Apache-2.0")
    (property "MPN" "")
    (property "Manufacturer" "")
    (property "Sheetfile" "reset.kicad_sch")
    (property "Sheetname" "Reset logic")
    (property "ki_description" "Test Point 0.75mm")
    (attr exclude_from_pos_files)
    (fp_text reference "TP23" (at 7.33 0.86 90) (layer "F.SilkS")
        (effects (font (size 0.7 0.7) (thickness 0.15)) (justify left bottom))
    )
    (fp_text value "TP_0.75mm_SMD" (at 0 1.2) (layer "F.Fab") hide
        (effects (font (size 0.7 0.7) (thickness 0.15)) (justify left bottom))
    )
    (fp_text user "License: Apache-2.0" (at -0.4 5.101) (layer "F.Fab") hide
        (effects (font (size 0.7 0.7) (thickness 0.15)) (justify left bottom))
    )
    (fp_text user "Author: Antmicro" (at -0.4 3.901) (layer "F.Fab") hide
        (effects (font (size 0.7 0.7) (thickness 0.15)) (justify left bottom))
    )
    (fp_text user "${REFERENCE}" (at -0.4 2.7) (layer "F.Fab") hide
        (effects (font (size 0.7 0.7) (thickness 0.15)) (justify left bottom))
    )
    (pad "1" smd circle (at 0 0) (size 0.75 0.75) (layers "F.Cu" "F.Mask")
      (net 221 "/PCIE M2 key E /~{M2_PERST}") (pinfunction "1") (pintype "passive"))
  )

  (footprint "kria-k26-devboard-footprints:USON-10_2.5x1mm_P0.5mm" (layer "F.Cu")
    (at 86 68.75 90)
    (descr "USON-10 2.5x1mm_ Pitch 0.5mm")
    (tags "USON-10 2.5x1mm Pitch 0.5mm")
    (property "Author" "Antmicro")
    (property "License" "Apache-2.0")
    (property "MPN" "TPD4E05U06QDQARQ1")
    (property "Manufacturer" "Texas Instruments")
    (property "Sheetfile" "dp.kicad_sch")
    (property "Sheetname" "Display Port")
    (property "ki_description" "ESD protection")
    (property "ki_keywords" "SMT, DIODE, IC, TVS, ESD")
    (attr smd)
    (fp_text reference "U3" (at 0.018 -1.7 90) (layer "F.SilkS")
        (effects (font (size 0.7 0.7) (thickness 0.15)) (justify left bottom))
    )
    (fp_text value "TPD4E05U06QDQARQ1" (at 0.018 2.499 90) (layer "F.Fab")
        (effects (font (size 0.7 0.7) (thickness 0.15)) (justify left bottom))
    )
    (fp_text user "${REFERENCE}" (at -0.802 4.498 90) (layer "F.Fab") hide
        (effects (font (size 0.7 0.7) (thickness 0.15)) (justify left bottom))
    )
    (fp_text user "License: Apache-2.0" (at -0.802 6.9 90) (layer "F.Fab") hide
        (effects (font (size 0.7 0.7) (thickness 0.15)) (justify left bottom))
    )
    (fp_text user "Author: Antmicro" (at -0.802 5.7 90) (layer "F.Fab") hide
        (effects (font (size 0.7 0.7) (thickness 0.15)) (justify left bottom))
    )
    (fp_line (start 0.498 -1.401) (end -0.5 -1.401)
      (stroke (width 0.15) (type solid)) (layer "F.SilkS"))
    (fp_line (start 0.498 1.398) (end -0.5 1.398)
      (stroke (width 0.15) (type solid)) (layer "F.SilkS"))
    (fp_circle (center -0.68 -1.27) (end -0.63 -1.27)
      (stroke (width 0.15) (type solid)) (fill solid) (layer "F.SilkS"))
    (fp_rect (start -0.8 -1.5) (end 0.8 1.499)
      (stroke (width 0.05) (type solid)) (fill none) (layer "F.CrtYd"))
    (fp_line (start -0.5 -1) (end -0.5 1.249)
      (stroke (width 0.15) (type solid)) (layer "F.Fab"))
    (fp_line (start -0.5 1.249) (end 0.498 1.249)
      (stroke (width 0.15) (type solid)) (layer "F.Fab"))
    (fp_line (start -0.25 -1.25) (end -0.5 -1)
      (stroke (width 0.15) (type solid)) (layer "F.Fab"))
    (fp_line (start 0.498 -1.25) (end -0.25 -1.25)
      (stroke (width 0.15) (type solid)) (layer "F.Fab"))
    (fp_line (start 0.498 -1.25) (end 0.498 1.249)
      (stroke (width 0.15) (type solid)) (layer "F.Fab"))
    (pad "1" smd roundrect (at -0.387 -1) (size 0.25 0.55) (layers "F.Cu" "F.Paste" "F.Mask") (roundrect_rratio 0.25)
      (net 93 "/Display Port/GTR_DP1_M2C_C_P") (pintype "passive"))
    (pad "2" smd roundrect (at -0.387 -0.5) (size 0.25 0.55) (layers "F.Cu" "F.Paste" "F.Mask") (roundrect_rratio 0.25)
      (net 95 "/Display Port/GTR_DP1_M2C_C_N") (pintype "passive"))
    (pad "3" smd roundrect (at -0.387 0) (size 0.4 0.55) (layers "F.Cu" "F.Paste" "F.Mask") (roundrect_rratio 0.25)
      (net 1 "GND") (pintype "power_in"))
    (pad "4" smd roundrect (at -0.387 0.498) (size 0.25 0.55) (layers "F.Cu" "F.Paste" "F.Mask") (roundrect_rratio 0.25)
      (net 101 "/Display Port/GTR_DP0_M2C_C_P") (pintype "passive"))
    (pad "5" smd roundrect (at -0.387 0.998) (size 0.25 0.55) (layers "F.Cu" "F.Paste" "F.Mask") (roundrect_rratio 0.25)
      (net 103 "/Display Port/GTR_DP0_M2C_C_N") (pintype "passive"))
    (pad "6" smd roundrect (at 0.385 0.998) (size 0.25 0.55) (layers "F.Cu" "F.Paste" "F.Mask") (roundrect_rratio 0.25)
      (net 103 "/Display Port/GTR_DP0_M2C_C_N") (pintype "passive"))
    (pad "7" smd roundrect (at 0.385 0.498) (size 0.25 0.55) (layers "F.Cu" "F.Paste" "F.Mask") (roundrect_rratio 0.25)
      (net 101 "/Display Port/GTR_DP0_M2C_C_P") (pintype "passive"))
    (pad "8" smd roundrect (at 0.385 0) (size 0.4 0.55) (layers "F.Cu" "F.Paste" "F.Mask") (roundrect_rratio 0.25)
      (net 1 "GND") (pintype "passive"))
    (pad "9" smd roundrect (at 0.385 -0.5) (size 0.25 0.55) (layers "F.Cu" "F.Paste" "F.Mask") (roundrect_rratio 0.25)
      (net 95 "/Display Port/GTR_DP1_M2C_C_N") (pintype "passive"))
    (pad "10" smd roundrect (at 0.385 -1) (size 0.25 0.55) (layers "F.Cu" "F.Paste" "F.Mask") (roundrect_rratio 0.25)
      (net 93 "/Display Port/GTR_DP1_M2C_C_P") (pintype "passive"))
  )

  (footprint "kria-k26-devboard-footprints:R_0402_1005Metric" (layer "F.Cu")
    (at 114.326942 87.874861)
    (descr "Resistor SMD 0402")
    (tags "resistor SMD 0402")
    (property "Author" "Antmicro")
    (property "License" "Apache-2.0")
    (property "MPN" "CR0402-FX-2003GLF")
    (property "Manufacturer" "Bourns")
    (property "Sheetfile" "usb.kicad_sch")
    (property "Sheetname" "USB")
    (property "Tolerance" "1%")
    (property "Val" "200k")
    (property "ki_description" "200k resistor in 0402 package with 1% tolerance")
    (attr smd)
    (fp_text reference "R42" (at -3.156942 0.655139) (layer "F.SilkS")
        (effects (font (size 0.7 0.7) (thickness 0.15)) (justify left bottom))
    )
    (fp_text value "R_200k_0402" (at 0 1.4) (layer "F.Fab") hide
        (effects (font (size 0.7 0.7) (thickness 0.15)) (justify left bottom))
    )
    (fp_text user "License: Apache-2.0" (at -0.95 5.169) (layer "F.Fab") hide
        (effects (font (size 0.7 0.7) (thickness 0.15)) (justify left bottom))
    )
    (fp_text user "${REFERENCE}" (at -0.95 3.168) (layer "F.Fab") hide
        (effects (font (size 0.7 0.7) (thickness 0.15)) (justify left bottom))
    )
    (fp_text user "Author: Antmicro" (at -0.95 4.169) (layer "F.Fab") hide
        (effects (font (size 0.7 0.7) (thickness 0.15)) (justify left bottom))
    )
    (fp_rect (start -0.93 -0.47) (end 0.93 0.47)
      (stroke (width 0.05) (type solid)) (fill none) (layer "F.CrtYd"))
    (fp_rect (start -0.5 -0.25) (end 0.5 0.25)
      (stroke (width 0.15) (type solid)) (fill none) (layer "F.Fab"))
    (pad "1" smd roundrect (at -0.485 0) (size 0.59 0.64) (layers "F.Cu" "F.Paste" "F.Mask") (roundrect_rratio 0.25)
      (net 1 "GND") (pintype "passive"))
    (pad "2" smd roundrect (at 0.485 0) (size 0.59 0.64) (layers "F.Cu" "F.Paste" "F.Mask") (roundrect_rratio 0.25)
      (net 645 "Net-(U17-SPI_D0{slash}CFG_BC_EN{slash}PF22)") (pintype "passive"))
  )

  (footprint "kria-k26-devboard-footprints:R_0402_1005Metric" (layer "F.Cu")
    (at 114.326939 86.87486)
    (descr "Resistor SMD 0402")
    (tags "resistor SMD 0402")
    (property "Author" "Antmicro")
    (property "License" "Apache-2.0")
    (property "MPN" "CR0402-FX-2003GLF")
    (property "Manufacturer" "Bourns")
    (property "Sheetfile" "usb.kicad_sch")
    (property "Sheetname" "USB")
    (property "Tolerance" "1%")
    (property "Val" "200k")
    (property "ki_description" "200k resistor in 0402 package with 1% tolerance")
    (attr smd)
    (fp_text reference "R40" (at -3.166939 0.58514) (layer "F.SilkS")
        (effects (font (size 0.7 0.7) (thickness 0.15)) (justify left bottom))
    )
    (fp_text value "R_200k_0402" (at 0 1.4) (layer "F.Fab") hide
        (effects (font (size 0.7 0.7) (thickness 0.15)) (justify left bottom))
    )
    (fp_text user "${REFERENCE}" (at -0.95 3.168) (layer "F.Fab") hide
        (effects (font (size 0.7 0.7) (thickness 0.15)) (justify left bottom))
    )
    (fp_text user "License: Apache-2.0" (at -0.95 5.169) (layer "F.Fab") hide
        (effects (font (size 0.7 0.7) (thickness 0.15)) (justify left bottom))
    )
    (fp_text user "Author: Antmicro" (at -0.95 4.169) (layer "F.Fab") hide
        (effects (font (size 0.7 0.7) (thickness 0.15)) (justify left bottom))
    )
    (fp_rect (start -0.93 -0.47) (end 0.93 0.47)
      (stroke (width 0.05) (type solid)) (fill none) (layer "F.CrtYd"))
    (fp_rect (start -0.5 -0.25) (end 0.5 0.25)
      (stroke (width 0.15) (type solid)) (fill none) (layer "F.Fab"))
    (pad "1" smd roundrect (at -0.485 0) (size 0.59 0.64) (layers "F.Cu" "F.Paste" "F.Mask") (roundrect_rratio 0.25)
      (net 1 "GND") (pintype "passive"))
    (pad "2" smd roundrect (at 0.485 0) (size 0.59 0.64) (layers "F.Cu" "F.Paste" "F.Mask") (roundrect_rratio 0.25)
      (net 643 "Net-(U17-SPI_CLK{slash}PF21)") (pintype "passive"))
  )

  (footprint "kria-k26-devboard-footprints:R_0402_1005Metric" (layer "F.Cu")
    (at 114.311942 88.874862)
    (descr "Resistor SMD 0402")
    (tags "resistor SMD 0402")
    (property "Author" "Antmicro")
    (property "License" "Apache-2.0")
    (property "MPN" "CR0402-FX-2003GLF")
    (property "Manufacturer" "Bourns")
    (property "Sheetfile" "usb.kicad_sch")
    (property "Sheetname" "USB")
    (property "Tolerance" "1%")
    (property "Val" "200k")
    (property "ki_description" "200k resistor in 0402 package with 1% tolerance")
    (attr smd)
    (fp_text reference "R44" (at -3.156942 0.655139) (layer "F.SilkS")
        (effects (font (size 0.7 0.7) (thickness 0.15)) (justify left bottom))
    )
    (fp_text value "R_200k_0402" (at 0 1.4) (layer "F.Fab") hide
        (effects (font (size 0.7 0.7) (thickness 0.15)) (justify left bottom))
    )
    (fp_text user "License: Apache-2.0" (at -0.95 5.169) (layer "F.Fab") hide
        (effects (font (size 0.7 0.7) (thickness 0.15)) (justify left bottom))
    )
    (fp_text user "Author: Antmicro" (at -0.95 4.169) (layer "F.Fab") hide
        (effects (font (size 0.7 0.7) (thickness 0.15)) (justify left bottom))
    )
    (fp_text user "${REFERENCE}" (at -0.95 3.168) (layer "F.Fab") hide
        (effects (font (size 0.7 0.7) (thickness 0.15)) (justify left bottom))
    )
    (fp_rect (start -0.93 -0.47) (end 0.93 0.47)
      (stroke (width 0.05) (type solid)) (fill none) (layer "F.CrtYd"))
    (fp_rect (start -0.5 -0.25) (end 0.5 0.25)
      (stroke (width 0.15) (type solid)) (fill none) (layer "F.Fab"))
    (pad "1" smd roundrect (at -0.485 0) (size 0.59 0.64) (layers "F.Cu" "F.Paste" "F.Mask") (roundrect_rratio 0.25)
      (net 1 "GND") (pintype "passive"))
    (pad "2" smd roundrect (at 0.485 0) (size 0.59 0.64) (layers "F.Cu" "F.Paste" "F.Mask") (roundrect_rratio 0.25)
      (net 647 "Net-(U17-SPI_D2{slash}PF24)") (pintype "passive"))
  )

  (footprint "kria-k26-devboard-footprints:Oscillator_SMD_ECS_2016MV_2x1.6x0.85mm" (layer "F.Cu")
    (at 127.25 93.28 180)
    (property "Author" "Antmicro")
    (property "License" "Apache-2.0")
    (property "MPN" "ECS-2016MV-250-CN-TR")
    (property "Manufacturer" "ECS Inc. International")
    (property "Sheetfile" "usb.kicad_sch")
    (property "Sheetname" "USB")
    (property "Val" "25 MHz")
    (property "ki_description" "Oscillator, 25 MHz, HCMOS, SMD, 2mm x 1.6mm, MultiVolt ECS-2016MV Series")
    (property "ki_keywords" "OSCILLATOR")
    (attr smd)
    (fp_text reference "Y4" (at -0.99 -0.4) (layer "F.SilkS")
        (effects (font (size 0.7 0.7) (thickness 0.15)) (justify left bottom))
    )
    (fp_text value "Oscillator_25MHz_ESC_2016MV" (at 0 2.2 180) (layer "F.Fab") hide
        (effects (font (size 0.7 0.7) (thickness 0.15)) (justify left bottom))
    )
    (fp_text user "Author: Antmicro" (at -1.05 4.6 180) (layer "F.Fab") hide
        (effects (font (size 0.7 0.7) (thickness 0.15)) (justify left bottom))
    )
    (fp_text user "${REFERENCE}" (at -1.05 3.4 180) (layer "F.Fab") hide
        (effects (font (size 0.7 0.7) (thickness 0.15)) (justify left bottom))
    )
    (fp_text user "License: Apache-2.0" (at -1.05 5.8 180) (layer "F.Fab") hide
        (effects (font (size 0.7 0.7) (thickness 0.15)) (justify left bottom))
    )
    (fp_line (start -0.95 0.4) (end -0.95 -0.4)
      (stroke (width 0.15) (type solid)) (layer "F.SilkS"))
    (fp_line (start -0.4 -1.15) (end 0.4 -1.15)
      (stroke (width 0.15) (type solid)) (layer "F.SilkS"))
    (fp_line (start -0.4 1.15) (end 0.4 1.15)
      (stroke (width 0.15) (type solid)) (layer "F.SilkS"))
    (fp_line (start 0.95 0.4) (end 0.95 -0.4)
      (stroke (width 0.15) (type solid)) (layer "F.SilkS"))
    (fp_circle (center -0.95 -1.15) (end -0.9 -1.15)
      (stroke (width 0.15) (type solid)) (fill solid) (layer "F.SilkS"))
    (fp_rect (start -1.05 -1.25) (end 1.05 1.24)
      (stroke (width 0.05) (type solid)) (fill none) (layer "F.CrtYd"))
    (fp_rect (start -0.85 -1.054) (end 0.852 1.054)
      (stroke (width 0.15) (type solid)) (fill none) (layer "F.Fab"))
    (pad "1" smd rect (at -0.486 -0.637 180) (size 0.6858 0.7874) (layers "F.Cu" "F.Paste" "F.Mask")
      (net 798 "unconnected-(Y4-EN-Pad1)") (pinfunction "EN") (pintype "input+no_connect"))
    (pad "2" smd rect (at -0.486 0.636 180) (size 0.6858 0.7874) (layers "F.Cu" "F.Paste" "F.Mask")
      (net 1 "GND") (pinfunction "GND") (pintype "power_in"))
    (pad "3" smd rect (at 0.487 0.636 180) (size 0.6858 0.7874) (layers "F.Cu" "F.Paste" "F.Mask")
      (net 294 "/USB/CLK_IN") (pinfunction "OUT") (pintype "output"))
    (pad "4" smd rect (at 0.487 -0.637 180) (size 0.6858 0.7874) (layers "F.Cu" "F.Paste" "F.Mask")
      (net 15 "PS_3V3") (pinfunction "VDD") (pintype "power_in"))
  )

  (footprint "kria-k26-devboard-footprints:SOT-416" (layer "F.Cu")
    (at 151.2 67.79 180)
    (descr "SOT-416")
    (tags "SOT-416")
    (property "Author" "Antmicro")
    (property "License" "Apache-2.0")
    (property "MPN" "DTC014TEBTL")
    (property "Manufacturer" "ROHM Semiconductor")
    (property "Sheetfile" "usbc-socket.kicad_sch")
    (property "Sheetname" "USB-C socket")
    (property "ki_description" "Digital NPN Transistor, 10k/NONE, EMT-3")
    (attr smd)
    (fp_text reference "Q17" (at 1.6 -1.94 180) (layer "F.SilkS")
        (effects (font (size 0.7 0.7) (thickness 0.15)) (justify left bottom))
    )
    (fp_text value "DTC014T_SOT-416" (at 0 2 180) (layer "F.Fab") hide
        (effects (font (size 0.7 0.7) (thickness 0.15)) (justify left bottom))
    )
    (fp_text user "License: Apache-2.0" (at -1 5.802 180) (layer "F.Fab") hide
        (effects (font (size 0.7 0.7) (thickness 0.15)) (justify left bottom))
    )
    (fp_text user "${REFERENCE}" (at -1 3.4 180) (layer "F.Fab") hide
        (effects (font (size 0.7 0.7) (thickness 0.15)) (justify left bottom))
    )
    (fp_text user "Author: Antmicro" (at -1 4.602 180) (layer "F.Fab") hide
        (effects (font (size 0.7 0.7) (thickness 0.15)) (justify left bottom))
    )
    (fp_line (start -0.5 -0.15) (end -0.5 0.15)
      (stroke (width 0.15) (type solid)) (layer "F.SilkS"))
    (fp_line (start 0.5 0.9) (end -0.5 0.9)
      (stroke (width 0.15) (type solid)) (layer "F.SilkS"))
    (fp_line (start 0.5 0.9) (end 0.5 0.7)
      (stroke (width 0.15) (type solid)) (layer "F.SilkS"))
    (fp_line (start 0.508 -0.9) (end -0.5 -0.9)
      (stroke (width 0.15) (type solid)) (layer "F.SilkS"))
    (fp_line (start 0.508 -0.9) (end 0.508 -0.592)
      (stroke (width 0.15) (type solid)) (layer "F.SilkS"))
    (fp_rect (start -1 -1.05) (end 1 1.05)
      (stroke (width 0.05) (type solid)) (fill none) (layer "F.CrtYd"))
    (fp_line (start -0.05 -0.9) (end -0.45 -0.5)
      (stroke (width 0.15) (type solid)) (layer "F.Fab"))
    (fp_rect (start 0.45 0.9) (end -0.45 -0.9)
      (stroke (width 0.15) (type solid)) (fill none) (layer "F.Fab"))
    (pad "1" smd rect (at -0.652 -0.5 180) (size 0.6 0.5) (layers "F.Cu" "F.Paste" "F.Mask")
      (net 229 "/Debug and JTAG/PD_EN") (pinfunction "B") (pintype "input"))
    (pad "2" smd rect (at -0.652 0.498 180) (size 0.6 0.5) (layers "F.Cu" "F.Paste" "F.Mask")
      (net 1 "GND") (pinfunction "E") (pintype "passive"))
    (pad "3" smd rect (at 0.65 0 180) (size 0.6 0.5) (layers "F.Cu" "F.Paste" "F.Mask")
      (net 433 "Net-(Q16-G)") (pinfunction "C") (pintype "passive"))
  )

  (footprint "kria-k26-devboard-footprints:C_0402_1005Metric" (layer "F.Cu")
    (at 91.535 140.61 -90)
    (descr "Capacitor SMD 0402")
    (tags "capacitor SMD 0402")
    (property "Author" "Antmicro")
    (property "Dielectric" "X5R")
    (property "License" "Apache-2.0")
    (property "MPN" "GRM155R61H104KE14D")
    (property "Manufacturer" "Murata")
    (property "Sheetfile" "k26_som.kicad_sch")
    (property "Sheetname" "Xilinx K26 SOM")
    (property "Val" "100n")
    (property "Voltage" "50V")
    (property "ki_description" " ")
    (attr smd)
    (fp_text reference "C124" (at -0.92 -3.605 -90) (layer "F.SilkS")
        (effects (font (size 0.7 0.7) (thickness 0.15)) (justify left bottom))
    )
    (fp_text value "C_100n_0402" (at 0 1.4 -90) (layer "F.Fab") hide
        (effects (font (size 0.7 0.7) (thickness 0.15)) (justify left bottom))
    )
    (fp_text user "${REFERENCE}" (at -0.932 3.168 -90) (layer "F.Fab") hide
        (effects (font (size 0.7 0.7) (thickness 0.15)) (justify left bottom))
    )
    (fp_text user "Author: Antmicro" (at -0.932 4.17 -90) (layer "F.Fab") hide
        (effects (font (size 0.7 0.7) (thickness 0.15)) (justify left bottom))
    )
    (fp_text user "License: Apache-2.0" (at -0.932 5.17 -90) (layer "F.Fab") hide
        (effects (font (size 0.7 0.7) (thickness 0.15)) (justify left bottom))
    )
    (fp_rect (start -0.94 -0.47) (end 0.94 0.47)
      (stroke (width 0.05) (type solid)) (fill none) (layer "F.CrtYd"))
    (fp_rect (start -0.499 -0.249) (end 0.499 0.249)
      (stroke (width 0.15) (type solid)) (fill none) (layer "F.Fab"))
    (pad "1" smd roundrect (at -0.484 0 270) (size 0.59 0.64) (layers "F.Cu" "F.Paste" "F.Mask") (roundrect_rratio 0.25)
      (net 21 "PL_1V2") (pintype "passive"))
    (pad "2" smd roundrect (at 0.484 0 270) (size 0.59 0.64) (layers "F.Cu" "F.Paste" "F.Mask") (roundrect_rratio 0.25)
      (net 1 "GND") (pintype "passive"))
  )

  (footprint "kria-k26-devboard-footprints:C_0402_1005Metric" (layer "F.Cu")
    (at 93.43 140.61 -90)
    (descr "Capacitor SMD 0402")
    (tags "capacitor SMD 0402")
    (property "Author" "Antmicro")
    (property "Dielectric" "")
    (property "License" "Apache-2.0")
    (property "MPN" "GRM155R61A475MEAAD")
    (property "Manufacturer" "Murata")
    (property "Sheetfile" "k26_som.kicad_sch")
    (property "Sheetname" "Xilinx K26 SOM")
    (property "Val" "4u7")
    (property "Voltage" "")
    (property "ki_description" " ")
    (attr smd)
    (fp_text reference "C123" (at -0.92 -3.605 -90) (layer "F.SilkS")
        (effects (font (size 0.7 0.7) (thickness 0.15)) (justify left bottom))
    )
    (fp_text value "C_4u7_0402" (at 0 1.4 -90) (layer "F.Fab") hide
        (effects (font (size 0.7 0.7) (thickness 0.15)) (justify left bottom))
    )
    (fp_text user "Author: Antmicro" (at -0.932 4.17 -90) (layer "F.Fab") hide
        (effects (font (size 0.7 0.7) (thickness 0.15)) (justify left bottom))
    )
    (fp_text user "${REFERENCE}" (at -0.932 3.168 -90) (layer "F.Fab") hide
        (effects (font (size 0.7 0.7) (thickness 0.15)) (justify left bottom))
    )
    (fp_text user "License: Apache-2.0" (at -0.932 5.17 -90) (layer "F.Fab") hide
        (effects (font (size 0.7 0.7) (thickness 0.15)) (justify left bottom))
    )
    (fp_rect (start -0.94 -0.47) (end 0.94 0.47)
      (stroke (width 0.05) (type solid)) (fill none) (layer "F.CrtYd"))
    (fp_rect (start -0.499 -0.249) (end 0.499 0.249)
      (stroke (width 0.15) (type solid)) (fill none) (layer "F.Fab"))
    (pad "1" smd roundrect (at -0.484 0 270) (size 0.59 0.64) (layers "F.Cu" "F.Paste" "F.Mask") (roundrect_rratio 0.25)
      (net 21 "PL_1V2") (pintype "passive"))
    (pad "2" smd roundrect (at 0.484 0 270) (size 0.59 0.64) (layers "F.Cu" "F.Paste" "F.Mask") (roundrect_rratio 0.25)
      (net 1 "GND") (pintype "passive"))
  )

  (footprint "kria-k26-devboard-footprints:C_0402_1005Metric" (layer "F.Cu")
    (at 92.48 140.61 -90)
    (descr "Capacitor SMD 0402")
    (tags "capacitor SMD 0402")
    (property "Author" "Antmicro")
    (property "Dielectric" "X5R")
    (property "License" "Apache-2.0")
    (property "MPN" "GRM155R61H104KE14D")
    (property "Manufacturer" "Murata")
    (property "Sheetfile" "k26_som.kicad_sch")
    (property "Sheetname" "Xilinx K26 SOM")
    (property "Val" "100n")
    (property "Voltage" "50V")
    (property "ki_description" " ")
    (attr smd)
    (fp_text reference "C125" (at -0.92 -3.605 -90) (layer "F.SilkS")
        (effects (font (size 0.7 0.7) (thickness 0.15)) (justify left bottom))
    )
    (fp_text value "C_100n_0402" (at 0 1.4 -90) (layer "F.Fab") hide
        (effects (font (size 0.7 0.7) (thickness 0.15)) (justify left bottom))
    )
    (fp_text user "Author: Antmicro" (at -0.932 4.17 -90) (layer "F.Fab") hide
        (effects (font (size 0.7 0.7) (thickness 0.15)) (justify left bottom))
    )
    (fp_text user "License: Apache-2.0" (at -0.932 5.17 -90) (layer "F.Fab") hide
        (effects (font (size 0.7 0.7) (thickness 0.15)) (justify left bottom))
    )
    (fp_text user "${REFERENCE}" (at -0.932 3.168 -90) (layer "F.Fab") hide
        (effects (font (size 0.7 0.7) (thickness 0.15)) (justify left bottom))
    )
    (fp_rect (start -0.94 -0.47) (end 0.94 0.47)
      (stroke (width 0.05) (type solid)) (fill none) (layer "F.CrtYd"))
    (fp_rect (start -0.499 -0.249) (end 0.499 0.249)
      (stroke (width 0.15) (type solid)) (fill none) (layer "F.Fab"))
    (pad "1" smd roundrect (at -0.484 0 270) (size 0.59 0.64) (layers "F.Cu" "F.Paste" "F.Mask") (roundrect_rratio 0.25)
      (net 21 "PL_1V2") (pintype "passive"))
    (pad "2" smd roundrect (at 0.484 0 270) (size 0.59 0.64) (layers "F.Cu" "F.Paste" "F.Mask") (roundrect_rratio 0.25)
      (net 1 "GND") (pintype "passive"))
  )

  (footprint "kria-k26-devboard-footprints:DFN-14-1EP_4x3mm_P0.5mm" (layer "F.Cu")
    (at 187.975 64.75)
    (property "Author" "Antmicro")
    (property "License" "Apache-2.0")
    (property "MPN" "LTC4358CDE#PBF")
    (property "Manufacturer" "Analog Devices")
    (property "Sheetfile" "supply-oring.kicad_sch")
    (property "Sheetname" "Supply ORing")
    (property "ki_description" "Ideal diode")
    (property "ki_keywords" "SMT, PMIC, IC, POWER, MANAGEMENT, DIODE, CONTROLLER")
    (attr smd)
    (fp_text reference "U58" (at -2.195 2.51 90) (layer "F.SilkS")
        (effects (font (size 0.7 0.7) (thickness 0.15)) (justify left bottom))
    )
    (fp_text value "LTC4358CDE" (at 0 3.2) (layer "F.Fab") hide
        (effects (font (size 0.7 0.7) (thickness 0.15)) (justify left bottom))
    )
    (fp_text user "License: Apache-2.0" (at -0.659 8.198) (layer "F.Fab") hide
        (effects (font (size 0.7 0.7) (thickness 0.15)) (justify left bottom))
    )
    (fp_text user "Author: Antmicro" (at -0.659 6.998) (layer "F.Fab") hide
        (effects (font (size 0.7 0.7) (thickness 0.15)) (justify left bottom))
    )
    (fp_text user "${REFERENCE}" (at -0.659 5.797) (layer "F.Fab") hide
        (effects (font (size 0.7 0.7) (thickness 0.15)) (justify left bottom))
    )
    (fp_line (start -1.6 -2.045) (end 1.5995 -2.045)
      (stroke (width 0.15) (type solid)) (layer "F.SilkS"))
    (fp_line (start -1.6 2.044) (end 1.6 2.044)
      (stroke (width 0.15) (type solid)) (layer "F.SilkS"))
    (fp_circle (center -1.85 -1.9) (end -1.8 -1.9)
      (stroke (width 0.15) (type solid)) (fill solid) (layer "F.SilkS"))
    (fp_line (start -2.1 -1.87) (end -1.79 -1.87)
      (stroke (width 0.05) (type solid)) (layer "F.CrtYd"))
    (fp_line (start -2.1 1.9) (end -2.1 -1.87)
      (stroke (width 0.05) (type solid)) (layer "F.CrtYd"))
    (fp_line (start -1.79 -2.28) (end 1.81 -2.28)
      (stroke (width 0.05) (type solid)) (layer "F.CrtYd"))
    (fp_line (start -1.79 -1.87) (end -1.79 -2.28)
      (stroke (width 0.05) (type solid)) (layer "F.CrtYd"))
    (fp_line (start -1.79 1.9) (end -2.1 1.9)
      (stroke (width 0.05) (type solid)) (layer "F.CrtYd"))
    (fp_line (start -1.79 2.31) (end -1.79 1.9)
      (stroke (width 0.05) (type solid)) (layer "F.CrtYd"))
    (fp_line (start 1.81 -2.28) (end 1.81 -1.87)
      (stroke (width 0.05) (type solid)) (layer "F.CrtYd"))
    (fp_line (start 1.81 1.9) (end 1.81 2.31)
      (stroke (width 0.05) (type solid)) (layer "F.CrtYd"))
    (fp_line (start 1.81 2.31) (end -1.79 2.31)
      (stroke (width 0.05) (type solid)) (layer "F.CrtYd"))
    (fp_line (start 2.1 -1.87) (end 1.81 -1.87)
      (stroke (width 0.05) (type solid)) (layer "F.CrtYd"))
    (fp_line (start 2.1 -1.87) (end 2.1 1.9)
      (stroke (width 0.05) (type solid)) (layer "F.CrtYd"))
    (fp_line (start 2.1 1.9) (end 1.81 1.9)
      (stroke (width 0.05) (type solid)) (layer "F.CrtYd"))
    (fp_line (start -1.55 -2.045) (end -1.55 2.044)
      (stroke (width 0.15) (type solid)) (layer "F.Fab"))
    (fp_line (start -1.55 2.044) (end 1.549 2.044)
      (stroke (width 0.15) (type solid)) (layer "F.Fab"))
    (fp_line (start 1.549 -2.045) (end -1.55 -2.045)
      (stroke (width 0.15) (type solid)) (layer "F.Fab"))
    (fp_line (start 1.549 2.044) (end 1.549 -2.045)
      (stroke (width 0.15) (type solid)) (layer "F.Fab"))
    (pad "" smd roundrect (at 0 -0.8) (size 1.3 1.3) (layers "F.Paste") (roundrect_rratio 0.05))
    (pad "" smd roundrect (at 0 0.8) (size 1.3 1.3) (layers "F.Paste") (roundrect_rratio 0.05))
    (pad "1" smd roundrect (at -1.445 -1.499) (size 0.807999 0.2548) (layers "F.Cu" "F.Paste" "F.Mask") (roundrect_rratio 0.25)
      (net 22 "/Power Supply/DC Input/DC_IN") (pinfunction "IN") (pintype "input"))
    (pad "2" smd roundrect (at -1.445 -1.001) (size 0.807999 0.2548) (layers "F.Cu" "F.Paste" "F.Mask") (roundrect_rratio 0.25)
      (net 22 "/Power Supply/DC Input/DC_IN") (pinfunction "IN") (pintype "passive"))
    (pad "3" smd roundrect (at -1.445 -0.5) (size 0.807999 0.2548) (layers "F.Cu" "F.Paste" "F.Mask") (roundrect_rratio 0.25)
      (net 22 "/Power Supply/DC Input/DC_IN") (pinfunction "IN") (pintype "passive"))
    (pad "4" smd roundrect (at -1.445 0) (size 0.807999 0.2548) (layers "F.Cu" "F.Paste" "F.Mask") (roundrect_rratio 0.25)
      (net 22 "/Power Supply/DC Input/DC_IN") (pinfunction "IN") (pintype "passive"))
    (pad "5" smd roundrect (at -1.445 0.5) (size 0.807999 0.2548) (layers "F.Cu" "F.Paste" "F.Mask") (roundrect_rratio 0.25)
      (net 791 "unconnected-(U58-GATE-Pad5)") (pinfunction "GATE") (pintype "output+no_connect"))
    (pad "6" smd roundrect (at -1.445 1) (size 0.807999 0.2548) (layers "F.Cu" "F.Paste" "F.Mask") (roundrect_rratio 0.25)
      (net 792 "unconnected-(U58-NC-Pad6)") (pinfunction "NC") (pintype "no_connect"))
    (pad "7" smd roundrect (at -1.445 1.5) (size 0.807999 0.2548) (layers "F.Cu" "F.Paste" "F.Mask") (roundrect_rratio 0.25)
      (net 331 "Net-(U58-GND)") (pinfunction "GND") (pintype "power_in"))
    (pad "8" smd roundrect (at 1.445 1.5) (size 0.807999 0.2548) (layers "F.Cu" "F.Paste" "F.Mask") (roundrect_rratio 0.25)
      (net 328 "Net-(U58-VDD)") (pinfunction "VDD") (pintype "passive"))
    (pad "9" smd roundrect (at 1.445 1) (size 0.807999 0.2548) (layers "F.Cu" "F.Paste" "F.Mask") (roundrect_rratio 0.25)
      (net 14 "/Power Supply/DC/DC conventers/DC_MAIN_BUS") (pinfunction "OUT") (pintype "passive"))
    (pad "10" smd roundrect (at 1.445 0.5) (size 0.807999 0.2548) (layers "F.Cu" "F.Paste" "F.Mask") (roundrect_rratio 0.25)
      (net 793 "unconnected-(U58-NC-Pad10)") (pinfunction "NC") (pintype "no_connect"))
    (pad "11" smd roundrect (at 1.445 0) (size 0.807999 0.2548) (layers "F.Cu" "F.Paste" "F.Mask") (roundrect_rratio 0.25)
      (net 22 "/Power Supply/DC Input/DC_IN") (pinfunction "IN") (pintype "passive"))
    (pad "12" smd roundrect (at 1.445 -0.501) (size 0.807999 0.2548) (layers "F.Cu" "F.Paste" "F.Mask") (roundrect_rratio 0.25)
      (net 22 "/Power Supply/DC Input/DC_IN") (pinfunction "IN") (pintype "passive"))
    (pad "13" smd roundrect (at 1.445 -1.001) (size 0.807999 0.2548) (layers "F.Cu" "F.Paste" "F.Mask") (roundrect_rratio 0.25)
      (net 22 "/Power Supply/DC Input/DC_IN") (pinfunction "IN") (pintype "passive"))
    (pad "14" smd roundrect (at 1.445 -1.499) (size 0.807999 0.2548) (layers "F.Cu" "F.Paste" "F.Mask") (roundrect_rratio 0.25)
      (net 22 "/Power Supply/DC Input/DC_IN") (pinfunction "IN") (pintype "passive"))
    (pad "15" smd roundrect (at 0 0) (size 1.8034 3.4036) (layers "F.Cu" "F.Mask") (roundrect_rratio 0.05)
      (net 14 "/Power Supply/DC/DC conventers/DC_MAIN_BUS") (pinfunction "DRAIN") (pintype "passive"))
  )

  (footprint "kria-k26-devboard-footprints:VQFN-100-1EP_12x12x0.85mm_P0.4mm" (layer "F.Cu")
    (at 122.118942 84.534861 180)
    (property "Author" "Antmicro")
    (property "License" "Apache-2.0")
    (property "MPN" "USB7016/KDX")
    (property "Manufacturer" "Microchip Technology")
    (property "Sheetfile" "usb.kicad_sch")
    (property "Sheetname" "USB")
    (property "ki_description" "USB hub controller")
    (property "ki_keywords" "SMT, INTERFACE, CONTROLLER, IC, USB, HUB")
    (attr smd)
    (fp_text reference "U17" (at 6.678942 4.194861 270) (layer "F.SilkS")
        (effects (font (size 0.7 0.7) (thickness 0.15)) (justify left bottom))
    )
    (fp_text value "USB7016_KDX" (at 0 7.6 180) (layer "F.Fab")
        (effects (font (size 0.7 0.7) (thickness 0.15)) (justify left bottom))
    )
    (fp_text user "${REFERENCE}" (at -7.101 8.121 180) (layer "F.Fab") hide
        (effects (font (size 0.7 0.7) (thickness 0.15)) (justify left bottom))
    )
    (fp_text user "License: Apache-2.0" (at -7.101 10.121 180) (layer "F.Fab") hide
        (effects (font (size 0.7 0.7) (thickness 0.15)) (justify left bottom))
    )
    (fp_text user "Author: Antmicro" (at -7.101 9.121 180) (layer "F.Fab") hide
        (effects (font (size 0.7 0.7) (thickness 0.15)) (justify left bottom))
    )
    (fp_rect (start -3.4 -3.4) (end -1.6 -1.6)
      (stroke (width 0.12) (type solid)) (fill solid) (layer "F.Paste"))
    (fp_rect (start -3.4 1.6) (end -1.6 3.4)
      (stroke (width 0.12) (type solid)) (fill solid) (layer "F.Paste"))
    (fp_rect (start -0.9 -0.9) (end 0.9 0.9)
      (stroke (width 0.12) (type solid)) (fill solid) (layer "F.Paste"))
    (fp_rect (start 1.6 -3.351) (end 3.4 -1.551)
      (stroke (width 0.12) (type solid)) (fill solid) (layer "F.Paste"))
    (fp_rect (start 1.6 1.6) (end 3.4 3.4)
      (stroke (width 0.12) (type solid)) (fill solid) (layer "F.Paste"))
    (fp_line (start -6.122 -6.122) (end -6.122 -5.236)
      (stroke (width 0.15) (type solid)) (layer "F.SilkS"))
    (fp_line (start -6.122 5.233) (end -6.122 6.121)
      (stroke (width 0.15) (type solid)) (layer "F.SilkS"))
    (fp_line (start -6.122 6.121) (end -5.236 6.121)
      (stroke (width 0.15) (type solid)) (layer "F.SilkS"))
    (fp_line (start -5.236 -6.122) (end -6.122 -6.122)
      (stroke (width 0.15) (type solid)) (layer "F.SilkS"))
    (fp_line (start 5.233 6.121) (end 6.121 6.121)
      (stroke (width 0.15) (type solid)) (layer "F.SilkS"))
    (fp_line (start 6.121 -6.122) (end 5.233 -6.122)
      (stroke (width 0.15) (type solid)) (layer "F.SilkS"))
    (fp_line (start 6.121 -5.236) (end 6.121 -6.122)
      (stroke (width 0.15) (type solid)) (layer "F.SilkS"))
    (fp_line (start 6.121 6.121) (end 6.121 5.233)
      (stroke (width 0.15) (type solid)) (layer "F.SilkS"))
    (fp_circle (center -6.4 -5.1) (end -6.35 -5.05)
      (stroke (width 0.15) (type solid)) (fill solid) (layer "F.SilkS"))
    (fp_rect (start -6.55 -6.55) (end 6.55 6.55)
      (stroke (width 0.05) (type solid)) (fill none) (layer "F.CrtYd"))
    (fp_line (start -5.995 -5.995) (end -5.995 -5.995)
      (stroke (width 0.15) (type solid)) (layer "F.Fab"))
    (fp_line (start -5.995 -5.995) (end -5.995 5.993)
      (stroke (width 0.15) (type solid)) (layer "F.Fab"))
    (fp_line (start -5.995 -4.928) (end -5.995 -4.928)
      (stroke (width 0.15) (type solid)) (layer "F.Fab"))
    (fp_line (start -5.995 -4.928) (end -5.995 -4.673)
      (stroke (width 0.15) (type solid)) (layer "F.Fab"))
    (fp_line (start -5.995 -4.726) (end -4.726 -5.995)
      (stroke (width 0.15) (type solid)) (layer "F.Fab"))
    (fp_line (start -5.995 -4.673) (end -5.995 -4.928)
      (stroke (width 0.15) (type solid)) (layer "F.Fab"))
    (fp_line (start -5.995 -4.673) (end -5.995 -4.673)
      (stroke (width 0.15) (type solid)) (layer "F.Fab"))
    (fp_line (start -5.995 -4.529) (end -5.995 -4.529)
      (stroke (width 0.15) (type solid)) (layer "F.Fab"))
    (fp_line (start -5.995 -4.529) (end -5.995 -4.273)
      (stroke (width 0.15) (type solid)) (layer "F.Fab"))
    (fp_line (start -5.995 -4.273) (end -5.995 -4.529)
      (stroke (width 0.15) (type solid)) (layer "F.Fab"))
    (fp_line (start -5.995 -4.273) (end -5.995 -4.273)
      (stroke (width 0.15) (type solid)) (layer "F.Fab"))
    (fp_line (start -5.995 -4.127) (end -5.995 -4.127)
      (stroke (width 0.15) (type solid)) (layer "F.Fab"))
    (fp_line (start -5.995 -4.127) (end -5.995 -3.875)
      (stroke (width 0.15) (type solid)) (layer "F.Fab"))
    (fp_line (start -5.995 -3.875) (end -5.995 -4.127)
      (stroke (width 0.15) (type solid)) (layer "F.Fab"))
    (fp_line (start -5.995 -3.875) (end -5.995 -3.875)
      (stroke (width 0.15) (type solid)) (layer "F.Fab"))
    (fp_line (start -5.995 -3.727) (end -5.995 -3.727)
      (stroke (width 0.15) (type solid)) (layer "F.Fab"))
    (fp_line (start -5.995 -3.727) (end -5.995 -3.473)
      (stroke (width 0.15) (type solid)) (layer "F.Fab"))
    (fp_line (start -5.995 -3.473) (end -5.995 -3.727)
      (stroke (width 0.15) (type solid)) (layer "F.Fab"))
    (fp_line (start -5.995 -3.473) (end -5.995 -3.473)
      (stroke (width 0.15) (type solid)) (layer "F.Fab"))
    (fp_line (start -5.995 -3.327) (end -5.995 -3.327)
      (stroke (width 0.15) (type solid)) (layer "F.Fab"))
    (fp_line (start -5.995 -3.327) (end -5.995 -3.073)
      (stroke (width 0.15) (type solid)) (layer "F.Fab"))
    (fp_line (start -5.995 -3.073) (end -5.995 -3.327)
      (stroke (width 0.15) (type solid)) (layer "F.Fab"))
    (fp_line (start -5.995 -3.073) (end -5.995 -3.073)
      (stroke (width 0.15) (type solid)) (layer "F.Fab"))
    (fp_line (start -5.995 -2.927) (end -5.995 -2.927)
      (stroke (width 0.15) (type solid)) (layer "F.Fab"))
    (fp_line (start -5.995 -2.927) (end -5.995 -2.673)
      (stroke (width 0.15) (type solid)) (layer "F.Fab"))
    (fp_line (start -5.995 -2.673) (end -5.995 -2.927)
      (stroke (width 0.15) (type solid)) (layer "F.Fab"))
    (fp_line (start -5.995 -2.673) (end -5.995 -2.673)
      (stroke (width 0.15) (type solid)) (layer "F.Fab"))
    (fp_line (start -5.995 -2.528) (end -5.995 -2.528)
      (stroke (width 0.15) (type solid)) (layer "F.Fab"))
    (fp_line (start -5.995 -2.528) (end -5.995 -2.274)
      (stroke (width 0.15) (type solid)) (layer "F.Fab"))
    (fp_line (start -5.995 -2.274) (end -5.995 -2.528)
      (stroke (width 0.15) (type solid)) (layer "F.Fab"))
    (fp_line (start -5.995 -2.274) (end -5.995 -2.274)
      (stroke (width 0.15) (type solid)) (layer "F.Fab"))
    (fp_line (start -5.995 -2.128) (end -5.995 -2.128)
      (stroke (width 0.15) (type solid)) (layer "F.Fab"))
    (fp_line (start -5.995 -2.128) (end -5.995 -1.873)
      (stroke (width 0.15) (type solid)) (layer "F.Fab"))
    (fp_line (start -5.995 -1.873) (end -5.995 -2.128)
      (stroke (width 0.15) (type solid)) (layer "F.Fab"))
    (fp_line (start -5.995 -1.873) (end -5.995 -1.873)
      (stroke (width 0.15) (type solid)) (layer "F.Fab"))
    (fp_line (start -5.995 -1.728) (end -5.995 -1.728)
      (stroke (width 0.15) (type solid)) (layer "F.Fab"))
    (fp_line (start -5.995 -1.728) (end -5.995 -1.474)
      (stroke (width 0.15) (type solid)) (layer "F.Fab"))
    (fp_line (start -5.995 -1.474) (end -5.995 -1.728)
      (stroke (width 0.15) (type solid)) (layer "F.Fab"))
    (fp_line (start -5.995 -1.474) (end -5.995 -1.474)
      (stroke (width 0.15) (type solid)) (layer "F.Fab"))
    (fp_line (start -5.995 -1.327) (end -5.995 -1.327)
      (stroke (width 0.15) (type solid)) (layer "F.Fab"))
    (fp_line (start -5.995 -1.327) (end -5.995 -1.073)
      (stroke (width 0.15) (type solid)) (layer "F.Fab"))
    (fp_line (start -5.995 -1.073) (end -5.995 -1.327)
      (stroke (width 0.15) (type solid)) (layer "F.Fab"))
    (fp_line (start -5.995 -1.073) (end -5.995 -1.073)
      (stroke (width 0.15) (type solid)) (layer "F.Fab"))
    (fp_line (start -5.995 -0.929) (end -5.995 -0.929)
      (stroke (width 0.15) (type solid)) (layer "F.Fab"))
    (fp_line (start -5.995 -0.929) (end -5.995 -0.675)
      (stroke (width 0.15) (type solid)) (layer "F.Fab"))
    (fp_line (start -5.995 -0.675) (end -5.995 -0.929)
      (stroke (width 0.15) (type solid)) (layer "F.Fab"))
    (fp_line (start -5.995 -0.675) (end -5.995 -0.675)
      (stroke (width 0.15) (type solid)) (layer "F.Fab"))
    (fp_line (start -5.995 -0.529) (end -5.995 -0.529)
      (stroke (width 0.15) (type solid)) (layer "F.Fab"))
    (fp_line (start -5.995 -0.529) (end -5.995 -0.275)
      (stroke (width 0.15) (type solid)) (layer "F.Fab"))
    (fp_line (start -5.995 -0.275) (end -5.995 -0.529)
      (stroke (width 0.15) (type solid)) (layer "F.Fab"))
    (fp_line (start -5.995 -0.275) (end -5.995 -0.275)
      (stroke (width 0.15) (type solid)) (layer "F.Fab"))
    (fp_line (start -5.995 -0.127) (end -5.995 -0.127)
      (stroke (width 0.15) (type solid)) (layer "F.Fab"))
    (fp_line (start -5.995 -0.127) (end -5.995 0.125)
      (stroke (width 0.15) (type solid)) (layer "F.Fab"))
    (fp_line (start -5.995 0.125) (end -5.995 -0.127)
      (stroke (width 0.15) (type solid)) (layer "F.Fab"))
    (fp_line (start -5.995 0.125) (end -5.995 0.125)
      (stroke (width 0.15) (type solid)) (layer "F.Fab"))
    (fp_line (start -5.995 0.273) (end -5.995 0.273)
      (stroke (width 0.15) (type solid)) (layer "F.Fab"))
    (fp_line (start -5.995 0.273) (end -5.995 0.527)
      (stroke (width 0.15) (type solid)) (layer "F.Fab"))
    (fp_line (start -5.995 0.527) (end -5.995 0.273)
      (stroke (width 0.15) (type solid)) (layer "F.Fab"))
    (fp_line (start -5.995 0.527) (end -5.995 0.527)
      (stroke (width 0.15) (type solid)) (layer "F.Fab"))
    (fp_line (start -5.995 0.673) (end -5.995 0.673)
      (stroke (width 0.15) (type solid)) (layer "F.Fab"))
    (fp_line (start -5.995 0.673) (end -5.995 0.927)
      (stroke (width 0.15) (type solid)) (layer "F.Fab"))
    (fp_line (start -5.995 0.927) (end -5.995 0.673)
      (stroke (width 0.15) (type solid)) (layer "F.Fab"))
    (fp_line (start -5.995 0.927) (end -5.995 0.927)
      (stroke (width 0.15) (type solid)) (layer "F.Fab"))
    (fp_line (start -5.995 1.072) (end -5.995 1.072)
      (stroke (width 0.15) (type solid)) (layer "F.Fab"))
    (fp_line (start -5.995 1.072) (end -5.995 1.326)
      (stroke (width 0.15) (type solid)) (layer "F.Fab"))
    (fp_line (start -5.995 1.326) (end -5.995 1.072)
      (stroke (width 0.15) (type solid)) (layer "F.Fab"))
    (fp_line (start -5.995 1.326) (end -5.995 1.326)
      (stroke (width 0.15) (type solid)) (layer "F.Fab"))
    (fp_line (start -5.995 1.473) (end -5.995 1.473)
      (stroke (width 0.15) (type solid)) (layer "F.Fab"))
    (fp_line (start -5.995 1.473) (end -5.995 1.727)
      (stroke (width 0.15) (type solid)) (layer "F.Fab"))
    (fp_line (start -5.995 1.727) (end -5.995 1.473)
      (stroke (width 0.15) (type solid)) (layer "F.Fab"))
    (fp_line (start -5.995 1.727) (end -5.995 1.727)
      (stroke (width 0.15) (type solid)) (layer "F.Fab"))
    (fp_line (start -5.995 1.872) (end -5.995 1.872)
      (stroke (width 0.15) (type solid)) (layer "F.Fab"))
    (fp_line (start -5.995 1.872) (end -5.995 2.125)
      (stroke (width 0.15) (type solid)) (layer "F.Fab"))
    (fp_line (start -5.995 2.125) (end -5.995 1.872)
      (stroke (width 0.15) (type solid)) (layer "F.Fab"))
    (fp_line (start -5.995 2.125) (end -5.995 2.125)
      (stroke (width 0.15) (type solid)) (layer "F.Fab"))
    (fp_line (start -5.995 2.273) (end -5.995 2.273)
      (stroke (width 0.15) (type solid)) (layer "F.Fab"))
    (fp_line (start -5.995 2.273) (end -5.995 2.527)
      (stroke (width 0.15) (type solid)) (layer "F.Fab"))
    (fp_line (start -5.995 2.527) (end -5.995 2.273)
      (stroke (width 0.15) (type solid)) (layer "F.Fab"))
    (fp_line (start -5.995 2.527) (end -5.995 2.527)
      (stroke (width 0.15) (type solid)) (layer "F.Fab"))
    (fp_line (start -5.995 2.672) (end -5.995 2.672)
      (stroke (width 0.15) (type solid)) (layer "F.Fab"))
    (fp_line (start -5.995 2.672) (end -5.995 2.926)
      (stroke (width 0.15) (type solid)) (layer "F.Fab"))
    (fp_line (start -5.995 2.926) (end -5.995 2.672)
      (stroke (width 0.15) (type solid)) (layer "F.Fab"))
    (fp_line (start -5.995 2.926) (end -5.995 2.926)
      (stroke (width 0.15) (type solid)) (layer "F.Fab"))
    (fp_line (start -5.995 3.072) (end -5.995 3.072)
      (stroke (width 0.15) (type solid)) (layer "F.Fab"))
    (fp_line (start -5.995 3.072) (end -5.995 3.325)
      (stroke (width 0.15) (type solid)) (layer "F.Fab"))
    (fp_line (start -5.995 3.325) (end -5.995 3.072)
      (stroke (width 0.15) (type solid)) (layer "F.Fab"))
    (fp_line (start -5.995 3.325) (end -5.995 3.325)
      (stroke (width 0.15) (type solid)) (layer "F.Fab"))
    (fp_line (start -5.995 3.471) (end -5.995 3.471)
      (stroke (width 0.15) (type solid)) (layer "F.Fab"))
    (fp_line (start -5.995 3.471) (end -5.995 3.725)
      (stroke (width 0.15) (type solid)) (layer "F.Fab"))
    (fp_line (start -5.995 3.725) (end -5.995 3.471)
      (stroke (width 0.15) (type solid)) (layer "F.Fab"))
    (fp_line (start -5.995 3.725) (end -5.995 3.725)
      (stroke (width 0.15) (type solid)) (layer "F.Fab"))
    (fp_line (start -5.995 3.871) (end -5.995 3.871)
      (stroke (width 0.15) (type solid)) (layer "F.Fab"))
    (fp_line (start -5.995 3.871) (end -5.995 4.126)
      (stroke (width 0.15) (type solid)) (layer "F.Fab"))
    (fp_line (start -5.995 4.126) (end -5.995 3.871)
      (stroke (width 0.15) (type solid)) (layer "F.Fab"))
    (fp_line (start -5.995 4.126) (end -5.995 4.126)
      (stroke (width 0.15) (type solid)) (layer "F.Fab"))
    (fp_line (start -5.995 4.272) (end -5.995 4.272)
      (stroke (width 0.15) (type solid)) (layer "F.Fab"))
    (fp_line (start -5.995 4.272) (end -5.995 4.525)
      (stroke (width 0.15) (type solid)) (layer "F.Fab"))
    (fp_line (start -5.995 4.525) (end -5.995 4.272)
      (stroke (width 0.15) (type solid)) (layer "F.Fab"))
    (fp_line (start -5.995 4.525) (end -5.995 4.525)
      (stroke (width 0.15) (type solid)) (layer "F.Fab"))
    (fp_line (start -5.995 4.671) (end -5.995 4.671)
      (stroke (width 0.15) (type solid)) (layer "F.Fab"))
    (fp_line (start -5.995 4.671) (end -5.995 4.926)
      (stroke (width 0.15) (type solid)) (layer "F.Fab"))
    (fp_line (start -5.995 4.926) (end -5.995 4.671)
      (stroke (width 0.15) (type solid)) (layer "F.Fab"))
    (fp_line (start -5.995 4.926) (end -5.995 4.926)
      (stroke (width 0.15) (type solid)) (layer "F.Fab"))
    (fp_line (start -5.995 5.993) (end -5.995 5.993)
      (stroke (width 0.15) (type solid)) (layer "F.Fab"))
    (fp_line (start -5.995 5.993) (end 5.993 5.993)
      (stroke (width 0.15) (type solid)) (layer "F.Fab"))
    (fp_line (start -4.928 -5.995) (end -4.928 -5.995)
      (stroke (width 0.15) (type solid)) (layer "F.Fab"))
    (fp_line (start -4.928 -5.995) (end -4.673 -5.995)
      (stroke (width 0.15) (type solid)) (layer "F.Fab"))
    (fp_line (start -4.928 5.993) (end -4.928 5.993)
      (stroke (width 0.15) (type solid)) (layer "F.Fab"))
    (fp_line (start -4.928 5.993) (end -4.673 5.993)
      (stroke (width 0.15) (type solid)) (layer "F.Fab"))
    (fp_line (start -4.673 -5.995) (end -4.928 -5.995)
      (stroke (width 0.15) (type solid)) (layer "F.Fab"))
    (fp_line (start -4.673 -5.995) (end -4.673 -5.995)
      (stroke (width 0.15) (type solid)) (layer "F.Fab"))
    (fp_line (start -4.673 5.993) (end -4.928 5.993)
      (stroke (width 0.15) (type solid)) (layer "F.Fab"))
    (fp_line (start -4.673 5.993) (end -4.673 5.993)
      (stroke (width 0.15) (type solid)) (layer "F.Fab"))
    (fp_line (start -4.529 5.993) (end -4.529 5.993)
      (stroke (width 0.15) (type solid)) (layer "F.Fab"))
    (fp_line (start -4.529 5.993) (end -4.273 5.993)
      (stroke (width 0.15) (type solid)) (layer "F.Fab"))
    (fp_line (start -4.528 -5.995) (end -4.528 -5.995)
      (stroke (width 0.15) (type solid)) (layer "F.Fab"))
    (fp_line (start -4.528 -5.995) (end -4.273 -5.995)
      (stroke (width 0.15) (type solid)) (layer "F.Fab"))
    (fp_line (start -4.273 -5.995) (end -4.528 -5.995)
      (stroke (width 0.15) (type solid)) (layer "F.Fab"))
    (fp_line (start -4.273 -5.995) (end -4.273 -5.995)
      (stroke (width 0.15) (type solid)) (layer "F.Fab"))
    (fp_line (start -4.273 5.993) (end -4.529 5.993)
      (stroke (width 0.15) (type solid)) (layer "F.Fab"))
    (fp_line (start -4.273 5.993) (end -4.273 5.993)
      (stroke (width 0.15) (type solid)) (layer "F.Fab"))
    (fp_line (start -4.127 -5.995) (end -4.127 -5.995)
      (stroke (width 0.15) (type solid)) (layer "F.Fab"))
    (fp_line (start -4.127 -5.995) (end -3.874 -5.995)
      (stroke (width 0.15) (type solid)) (layer "F.Fab"))
    (fp_line (start -4.127 5.993) (end -4.127 5.993)
      (stroke (width 0.15) (type solid)) (layer "F.Fab"))
    (fp_line (start -4.127 5.993) (end -3.875 5.993)
      (stroke (width 0.15) (type solid)) (layer "F.Fab"))
    (fp_line (start -3.875 5.993) (end -4.127 5.993)
      (stroke (width 0.15) (type solid)) (layer "F.Fab"))
    (fp_line (start -3.875 5.993) (end -3.875 5.993)
      (stroke (width 0.15) (type solid)) (layer "F.Fab"))
    (fp_line (start -3.874 -5.995) (end -4.127 -5.995)
      (stroke (width 0.15) (type solid)) (layer "F.Fab"))
    (fp_line (start -3.874 -5.995) (end -3.874 -5.995)
      (stroke (width 0.15) (type solid)) (layer "F.Fab"))
    (fp_line (start -3.727 -5.995) (end -3.727 -5.995)
      (stroke (width 0.15) (type solid)) (layer "F.Fab"))
    (fp_line (start -3.727 -5.995) (end -3.473 -5.995)
      (stroke (width 0.15) (type solid)) (layer "F.Fab"))
    (fp_line (start -3.727 5.993) (end -3.727 5.993)
      (stroke (width 0.15) (type solid)) (layer "F.Fab"))
    (fp_line (start -3.727 5.993) (end -3.473 5.993)
      (stroke (width 0.15) (type solid)) (layer "F.Fab"))
    (fp_line (start -3.473 -5.995) (end -3.727 -5.995)
      (stroke (width 0.15) (type solid)) (layer "F.Fab"))
    (fp_line (start -3.473 -5.995) (end -3.473 -5.995)
      (stroke (width 0.15) (type solid)) (layer "F.Fab"))
    (fp_line (start -3.473 5.993) (end -3.727 5.993)
      (stroke (width 0.15) (type solid)) (layer "F.Fab"))
    (fp_line (start -3.473 5.993) (end -3.473 5.993)
      (stroke (width 0.15) (type solid)) (layer "F.Fab"))
    (fp_line (start -3.327 -5.995) (end -3.327 -5.995)
      (stroke (width 0.15) (type solid)) (layer "F.Fab"))
    (fp_line (start -3.327 -5.995) (end -3.073 -5.995)
      (stroke (width 0.15) (type solid)) (layer "F.Fab"))
    (fp_line (start -3.327 5.993) (end -3.327 5.993)
      (stroke (width 0.15) (type solid)) (layer "F.Fab"))
    (fp_line (start -3.327 5.993) (end -3.073 5.993)
      (stroke (width 0.15) (type solid)) (layer "F.Fab"))
    (fp_line (start -3.073 -5.995) (end -3.327 -5.995)
      (stroke (width 0.15) (type solid)) (layer "F.Fab"))
    (fp_line (start -3.073 -5.995) (end -3.073 -5.995)
      (stroke (width 0.15) (type solid)) (layer "F.Fab"))
    (fp_line (start -3.073 5.993) (end -3.327 5.993)
      (stroke (width 0.15) (type solid)) (layer "F.Fab"))
    (fp_line (start -3.073 5.993) (end -3.073 5.993)
      (stroke (width 0.15) (type solid)) (layer "F.Fab"))
    (fp_line (start -2.927 -5.995) (end -2.927 -5.995)
      (stroke (width 0.15) (type solid)) (layer "F.Fab"))
    (fp_line (start -2.927 -5.995) (end -2.673 -5.995)
      (stroke (width 0.15) (type solid)) (layer "F.Fab"))
    (fp_line (start -2.927 5.993) (end -2.927 5.993)
      (stroke (width 0.15) (type solid)) (layer "F.Fab"))
    (fp_line (start -2.927 5.993) (end -2.673 5.993)
      (stroke (width 0.15) (type solid)) (layer "F.Fab"))
    (fp_line (start -2.673 -5.995) (end -2.927 -5.995)
      (stroke (width 0.15) (type solid)) (layer "F.Fab"))
    (fp_line (start -2.673 -5.995) (end -2.673 -5.995)
      (stroke (width 0.15) (type solid)) (layer "F.Fab"))
    (fp_line (start -2.673 5.993) (end -2.927 5.993)
      (stroke (width 0.15) (type solid)) (layer "F.Fab"))
    (fp_line (start -2.673 5.993) (end -2.673 5.993)
      (stroke (width 0.15) (type solid)) (layer "F.Fab"))
    (fp_line (start -2.528 -5.995) (end -2.528 -5.995)
      (stroke (width 0.15) (type solid)) (layer "F.Fab"))
    (fp_line (start -2.528 -5.995) (end -2.274 -5.995)
      (stroke (width 0.15) (type solid)) (layer "F.Fab"))
    (fp_line (start -2.528 5.993) (end -2.528 5.993)
      (stroke (width 0.15) (type solid)) (layer "F.Fab"))
    (fp_line (start -2.528 5.993) (end -2.274 5.993)
      (stroke (width 0.15) (type solid)) (layer "F.Fab"))
    (fp_line (start -2.274 -5.995) (end -2.528 -5.995)
      (stroke (width 0.15) (type solid)) (layer "F.Fab"))
    (fp_line (start -2.274 -5.995) (end -2.274 -5.995)
      (stroke (width 0.15) (type solid)) (layer "F.Fab"))
    (fp_line (start -2.274 5.993) (end -2.528 5.993)
      (stroke (width 0.15) (type solid)) (layer "F.Fab"))
    (fp_line (start -2.274 5.993) (end -2.274 5.993)
      (stroke (width 0.15) (type solid)) (layer "F.Fab"))
    (fp_line (start -2.128 -5.995) (end -2.128 -5.995)
      (stroke (width 0.15) (type solid)) (layer "F.Fab"))
    (fp_line (start -2.128 -5.995) (end -1.873 -5.995)
      (stroke (width 0.15) (type solid)) (layer "F.Fab"))
    (fp_line (start -2.128 5.993) (end -2.128 5.993)
      (stroke (width 0.15) (type solid)) (layer "F.Fab"))
    (fp_line (start -2.128 5.993) (end -1.873 5.993)
      (stroke (width 0.15) (type solid)) (layer "F.Fab"))
    (fp_line (start -1.873 -5.995) (end -2.128 -5.995)
      (stroke (width 0.15) (type solid)) (layer "F.Fab"))
    (fp_line (start -1.873 -5.995) (end -1.873 -5.995)
      (stroke (width 0.15) (type solid)) (layer "F.Fab"))
    (fp_line (start -1.873 5.993) (end -2.128 5.993)
      (stroke (width 0.15) (type solid)) (layer "F.Fab"))
    (fp_line (start -1.873 5.993) (end -1.873 5.993)
      (stroke (width 0.15) (type solid)) (layer "F.Fab"))
    (fp_line (start -1.728 -5.995) (end -1.728 -5.995)
      (stroke (width 0.15) (type solid)) (layer "F.Fab"))
    (fp_line (start -1.728 -5.995) (end -1.474 -5.995)
      (stroke (width 0.15) (type solid)) (layer "F.Fab"))
    (fp_line (start -1.728 5.993) (end -1.728 5.993)
      (stroke (width 0.15) (type solid)) (layer "F.Fab"))
    (fp_line (start -1.728 5.993) (end -1.474 5.993)
      (stroke (width 0.15) (type solid)) (layer "F.Fab"))
    (fp_line (start -1.474 -5.995) (end -1.728 -5.995)
      (stroke (width 0.15) (type solid)) (layer "F.Fab"))
    (fp_line (start -1.474 -5.995) (end -1.474 -5.995)
      (stroke (width 0.15) (type solid)) (layer "F.Fab"))
    (fp_line (start -1.474 5.993) (end -1.728 5.993)
      (stroke (width 0.15) (type solid)) (layer "F.Fab"))
    (fp_line (start -1.474 5.993) (end -1.474 5.993)
      (stroke (width 0.15) (type solid)) (layer "F.Fab"))
    (fp_line (start -1.327 -5.995) (end -1.327 -5.995)
      (stroke (width 0.15) (type solid)) (layer "F.Fab"))
    (fp_line (start -1.327 -5.995) (end -1.073 -5.995)
      (stroke (width 0.15) (type solid)) (layer "F.Fab"))
    (fp_line (start -1.327 5.993) (end -1.327 5.993)
      (stroke (width 0.15) (type solid)) (layer "F.Fab"))
    (fp_line (start -1.327 5.993) (end -1.073 5.993)
      (stroke (width 0.15) (type solid)) (layer "F.Fab"))
    (fp_line (start -1.073 -5.995) (end -1.327 -5.995)
      (stroke (width 0.15) (type solid)) (layer "F.Fab"))
    (fp_line (start -1.073 -5.995) (end -1.073 -5.995)
      (stroke (width 0.15) (type solid)) (layer "F.Fab"))
    (fp_line (start -1.073 5.993) (end -1.327 5.993)
      (stroke (width 0.15) (type solid)) (layer "F.Fab"))
    (fp_line (start -1.073 5.993) (end -1.073 5.993)
      (stroke (width 0.15) (type solid)) (layer "F.Fab"))
    (fp_line (start -0.929 -5.995) (end -0.929 -5.995)
      (stroke (width 0.15) (type solid)) (layer "F.Fab"))
    (fp_line (start -0.929 -5.995) (end -0.675 -5.995)
      (stroke (width 0.15) (type solid)) (layer "F.Fab"))
    (fp_line (start -0.929 5.993) (end -0.929 5.993)
      (stroke (width 0.15) (type solid)) (layer "F.Fab"))
    (fp_line (start -0.929 5.993) (end -0.675 5.993)
      (stroke (width 0.15) (type solid)) (layer "F.Fab"))
    (fp_line (start -0.675 -5.995) (end -0.929 -5.995)
      (stroke (width 0.15) (type solid)) (layer "F.Fab"))
    (fp_line (start -0.675 -5.995) (end -0.675 -5.995)
      (stroke (width 0.15) (type solid)) (layer "F.Fab"))
    (fp_line (start -0.675 5.993) (end -0.929 5.993)
      (stroke (width 0.15) (type solid)) (layer "F.Fab"))
    (fp_line (start -0.675 5.993) (end -0.675 5.993)
      (stroke (width 0.15) (type solid)) (layer "F.Fab"))
    (fp_line (start -0.529 -5.995) (end -0.529 -5.995)
      (stroke (width 0.15) (type solid)) (layer "F.Fab"))
    (fp_line (start -0.529 -5.995) (end -0.275 -5.995)
      (stroke (width 0.15) (type solid)) (layer "F.Fab"))
    (fp_line (start -0.529 5.993) (end -0.529 5.993)
      (stroke (width 0.15) (type solid)) (layer "F.Fab"))
    (fp_line (start -0.529 5.993) (end -0.275 5.993)
      (stroke (width 0.15) (type solid)) (layer "F.Fab"))
    (fp_line (start -0.275 -5.995) (end -0.529 -5.995)
      (stroke (width 0.15) (type solid)) (layer "F.Fab"))
    (fp_line (start -0.275 -5.995) (end -0.275 -5.995)
      (stroke (width 0.15) (type solid)) (layer "F.Fab"))
    (fp_line (start -0.275 5.993) (end -0.529 5.993)
      (stroke (width 0.15) (type solid)) (layer "F.Fab"))
    (fp_line (start -0.275 5.993) (end -0.275 5.993)
      (stroke (width 0.15) (type solid)) (layer "F.Fab"))
    (fp_line (start -0.127 -5.995) (end -0.127 -5.995)
      (stroke (width 0.15) (type solid)) (layer "F.Fab"))
    (fp_line (start -0.127 -5.995) (end 0.125 -5.995)
      (stroke (width 0.15) (type solid)) (layer "F.Fab"))
    (fp_line (start -0.127 5.993) (end -0.127 5.993)
      (stroke (width 0.15) (type solid)) (layer "F.Fab"))
    (fp_line (start -0.127 5.993) (end 0.125 5.993)
      (stroke (width 0.15) (type solid)) (layer "F.Fab"))
    (fp_line (start 0.125 -5.995) (end -0.127 -5.995)
      (stroke (width 0.15) (type solid)) (layer "F.Fab"))
    (fp_line (start 0.125 -5.995) (end 0.125 -5.995)
      (stroke (width 0.15) (type solid)) (layer "F.Fab"))
    (fp_line (start 0.125 5.993) (end -0.127 5.993)
      (stroke (width 0.15) (type solid)) (layer "F.Fab"))
    (fp_line (start 0.125 5.993) (end 0.125 5.993)
      (stroke (width 0.15) (type solid)) (layer "F.Fab"))
    (fp_line (start 0.273 -5.995) (end 0.273 -5.995)
      (stroke (width 0.15) (type solid)) (layer "F.Fab"))
    (fp_line (start 0.273 -5.995) (end 0.527 -5.995)
      (stroke (width 0.15) (type solid)) (layer "F.Fab"))
    (fp_line (start 0.273 5.993) (end 0.273 5.993)
      (stroke (width 0.15) (type solid)) (layer "F.Fab"))
    (fp_line (start 0.273 5.993) (end 0.527 5.993)
      (stroke (width 0.15) (type solid)) (layer "F.Fab"))
    (fp_line (start 0.527 -5.995) (end 0.273 -5.995)
      (stroke (width 0.15) (type solid)) (layer "F.Fab"))
    (fp_line (start 0.527 -5.995) (end 0.527 -5.995)
      (stroke (width 0.15) (type solid)) (layer "F.Fab"))
    (fp_line (start 0.527 5.993) (end 0.273 5.993)
      (stroke (width 0.15) (type solid)) (layer "F.Fab"))
    (fp_line (start 0.527 5.993) (end 0.527 5.993)
      (stroke (width 0.15) (type solid)) (layer "F.Fab"))
    (fp_line (start 0.673 -5.995) (end 0.673 -5.995)
      (stroke (width 0.15) (type solid)) (layer "F.Fab"))
    (fp_line (start 0.673 -5.995) (end 0.927 -5.995)
      (stroke (width 0.15) (type solid)) (layer "F.Fab"))
    (fp_line (start 0.673 5.993) (end 0.673 5.993)
      (stroke (width 0.15) (type solid)) (layer "F.Fab"))
    (fp_line (start 0.673 5.993) (end 0.927 5.993)
      (stroke (width 0.15) (type solid)) (layer "F.Fab"))
    (fp_line (start 0.927 -5.995) (end 0.673 -5.995)
      (stroke (width 0.15) (type solid)) (layer "F.Fab"))
    (fp_line (start 0.927 -5.995) (end 0.927 -5.995)
      (stroke (width 0.15) (type solid)) (layer "F.Fab"))
    (fp_line (start 0.927 5.993) (end 0.673 5.993)
      (stroke (width 0.15) (type solid)) (layer "F.Fab"))
    (fp_line (start 0.927 5.993) (end 0.927 5.993)
      (stroke (width 0.15) (type solid)) (layer "F.Fab"))
    (fp_line (start 1.072 -5.995) (end 1.072 -5.995)
      (stroke (width 0.15) (type solid)) (layer "F.Fab"))
    (fp_line (start 1.072 -5.995) (end 1.326 -5.995)
      (stroke (width 0.15) (type solid)) (layer "F.Fab"))
    (fp_line (start 1.072 5.993) (end 1.072 5.993)
      (stroke (width 0.15) (type solid)) (layer "F.Fab"))
    (fp_line (start 1.072 5.993) (end 1.326 5.993)
      (stroke (width 0.15) (type solid)) (layer "F.Fab"))
    (fp_line (start 1.326 -5.995) (end 1.072 -5.995)
      (stroke (width 0.15) (type solid)) (layer "F.Fab"))
    (fp_line (start 1.326 -5.995) (end 1.326 -5.995)
      (stroke (width 0.15) (type solid)) (layer "F.Fab"))
    (fp_line (start 1.326 5.993) (end 1.072 5.993)
      (stroke (width 0.15) (type solid)) (layer "F.Fab"))
    (fp_line (start 1.326 5.993) (end 1.326 5.993)
      (stroke (width 0.15) (type solid)) (layer "F.Fab"))
    (fp_line (start 1.473 -5.995) (end 1.473 -5.995)
      (stroke (width 0.15) (type solid)) (layer "F.Fab"))
    (fp_line (start 1.473 -5.995) (end 1.727 -5.995)
      (stroke (width 0.15) (type solid)) (layer "F.Fab"))
    (fp_line (start 1.473 5.993) (end 1.473 5.993)
      (stroke (width 0.15) (type solid)) (layer "F.Fab"))
    (fp_line (start 1.473 5.993) (end 1.727 5.993)
      (stroke (width 0.15) (type solid)) (layer "F.Fab"))
    (fp_line (start 1.727 -5.995) (end 1.473 -5.995)
      (stroke (width 0.15) (type solid)) (layer "F.Fab"))
    (fp_line (start 1.727 -5.995) (end 1.727 -5.995)
      (stroke (width 0.15) (type solid)) (layer "F.Fab"))
    (fp_line (start 1.727 5.993) (end 1.473 5.993)
      (stroke (width 0.15) (type solid)) (layer "F.Fab"))
    (fp_line (start 1.727 5.993) (end 1.727 5.993)
      (stroke (width 0.15) (type solid)) (layer "F.Fab"))
    (fp_line (start 1.872 -5.995) (end 1.872 -5.995)
      (stroke (width 0.15) (type solid)) (layer "F.Fab"))
    (fp_line (start 1.872 -5.995) (end 2.125 -5.995)
      (stroke (width 0.15) (type solid)) (layer "F.Fab"))
    (fp_line (start 1.872 5.993) (end 1.872 5.993)
      (stroke (width 0.15) (type solid)) (layer "F.Fab"))
    (fp_line (start 1.872 5.993) (end 2.125 5.993)
      (stroke (width 0.15) (type solid)) (layer "F.Fab"))
    (fp_line (start 2.125 -5.995) (end 1.872 -5.995)
      (stroke (width 0.15) (type solid)) (layer "F.Fab"))
    (fp_line (start 2.125 -5.995) (end 2.125 -5.995)
      (stroke (width 0.15) (type solid)) (layer "F.Fab"))
    (fp_line (start 2.125 5.993) (end 1.872 5.993)
      (stroke (width 0.15) (type solid)) (layer "F.Fab"))
    (fp_line (start 2.125 5.993) (end 2.125 5.993)
      (stroke (width 0.15) (type solid)) (layer "F.Fab"))
    (fp_line (start 2.273 -5.995) (end 2.273 -5.995)
      (stroke (width 0.15) (type solid)) (layer "F.Fab"))
    (fp_line (start 2.273 -5.995) (end 2.527 -5.995)
      (stroke (width 0.15) (type solid)) (layer "F.Fab"))
    (fp_line (start 2.273 5.993) (end 2.273 5.993)
      (stroke (width 0.15) (type solid)) (layer "F.Fab"))
    (fp_line (start 2.273 5.993) (end 2.527 5.993)
      (stroke (width 0.15) (type solid)) (layer "F.Fab"))
    (fp_line (start 2.527 -5.995) (end 2.273 -5.995)
      (stroke (width 0.15) (type solid)) (layer "F.Fab"))
    (fp_line (start 2.527 -5.995) (end 2.527 -5.995)
      (stroke (width 0.15) (type solid)) (layer "F.Fab"))
    (fp_line (start 2.527 5.993) (end 2.273 5.993)
      (stroke (width 0.15) (type solid)) (layer "F.Fab"))
    (fp_line (start 2.527 5.993) (end 2.527 5.993)
      (stroke (width 0.15) (type solid)) (layer "F.Fab"))
    (fp_line (start 2.672 -5.995) (end 2.672 -5.995)
      (stroke (width 0.15) (type solid)) (layer "F.Fab"))
    (fp_line (start 2.672 -5.995) (end 2.926 -5.995)
      (stroke (width 0.15) (type solid)) (layer "F.Fab"))
    (fp_line (start 2.672 5.993) (end 2.672 5.993)
      (stroke (width 0.15) (type solid)) (layer "F.Fab"))
    (fp_line (start 2.672 5.993) (end 2.926 5.993)
      (stroke (width 0.15) (type solid)) (layer "F.Fab"))
    (fp_line (start 2.926 -5.995) (end 2.672 -5.995)
      (stroke (width 0.15) (type solid)) (layer "F.Fab"))
    (fp_line (start 2.926 -5.995) (end 2.926 -5.995)
      (stroke (width 0.15) (type solid)) (layer "F.Fab"))
    (fp_line (start 2.926 5.993) (end 2.672 5.993)
      (stroke (width 0.15) (type solid)) (layer "F.Fab"))
    (fp_line (start 2.926 5.993) (end 2.926 5.993)
      (stroke (width 0.15) (type solid)) (layer "F.Fab"))
    (fp_line (start 3.072 -5.995) (end 3.072 -5.995)
      (stroke (width 0.15) (type solid)) (layer "F.Fab"))
    (fp_line (start 3.072 -5.995) (end 3.325 -5.995)
      (stroke (width 0.15) (type solid)) (layer "F.Fab"))
    (fp_line (start 3.072 5.993) (end 3.072 5.993)
      (stroke (width 0.15) (type solid)) (layer "F.Fab"))
    (fp_line (start 3.072 5.993) (end 3.325 5.993)
      (stroke (width 0.15) (type solid)) (layer "F.Fab"))
    (fp_line (start 3.325 -5.995) (end 3.072 -5.995)
      (stroke (width 0.15) (type solid)) (layer "F.Fab"))
    (fp_line (start 3.325 -5.995) (end 3.325 -5.995)
      (stroke (width 0.15) (type solid)) (layer "F.Fab"))
    (fp_line (start 3.325 5.993) (end 3.072 5.993)
      (stroke (width 0.15) (type solid)) (layer "F.Fab"))
    (fp_line (start 3.325 5.993) (end 3.325 5.993)
      (stroke (width 0.15) (type solid)) (layer "F.Fab"))
    (fp_line (start 3.471 -5.995) (end 3.471 -5.995)
      (stroke (width 0.15) (type solid)) (layer "F.Fab"))
    (fp_line (start 3.471 -5.995) (end 3.725 -5.995)
      (stroke (width 0.15) (type solid)) (layer "F.Fab"))
    (fp_line (start 3.471 5.993) (end 3.471 5.993)
      (stroke (width 0.15) (type solid)) (layer "F.Fab"))
    (fp_line (start 3.471 5.993) (end 3.725 5.993)
      (stroke (width 0.15) (type solid)) (layer "F.Fab"))
    (fp_line (start 3.725 -5.995) (end 3.471 -5.995)
      (stroke (width 0.15) (type solid)) (layer "F.Fab"))
    (fp_line (start 3.725 -5.995) (end 3.725 -5.995)
      (stroke (width 0.15) (type solid)) (layer "F.Fab"))
    (fp_line (start 3.725 5.993) (end 3.471 5.993)
      (stroke (width 0.15) (type solid)) (layer "F.Fab"))
    (fp_line (start 3.725 5.993) (end 3.725 5.993)
      (stroke (width 0.15) (type solid)) (layer "F.Fab"))
    (fp_line (start 3.871 5.993) (end 3.871 5.993)
      (stroke (width 0.15) (type solid)) (layer "F.Fab"))
    (fp_line (start 3.871 5.993) (end 4.126 5.993)
      (stroke (width 0.15) (type solid)) (layer "F.Fab"))
    (fp_line (start 3.873 -5.995) (end 3.873 -5.995)
      (stroke (width 0.15) (type solid)) (layer "F.Fab"))
    (fp_line (start 3.873 -5.995) (end 4.126 -5.995)
      (stroke (width 0.15) (type solid)) (layer "F.Fab"))
    (fp_line (start 4.126 -5.995) (end 3.873 -5.995)
      (stroke (width 0.15) (type solid)) (layer "F.Fab"))
    (fp_line (start 4.126 -5.995) (end 4.126 -5.995)
      (stroke (width 0.15) (type solid)) (layer "F.Fab"))
    (fp_line (start 4.126 5.993) (end 3.871 5.993)
      (stroke (width 0.15) (type solid)) (layer "F.Fab"))
    (fp_line (start 4.126 5.993) (end 4.126 5.993)
      (stroke (width 0.15) (type solid)) (layer "F.Fab"))
    (fp_line (start 4.272 -5.995) (end 4.272 -5.995)
      (stroke (width 0.15) (type solid)) (layer "F.Fab"))
    (fp_line (start 4.272 -5.995) (end 4.527 -5.995)
      (stroke (width 0.15) (type solid)) (layer "F.Fab"))
    (fp_line (start 4.272 5.993) (end 4.272 5.993)
      (stroke (width 0.15) (type solid)) (layer "F.Fab"))
    (fp_line (start 4.272 5.993) (end 4.525 5.993)
      (stroke (width 0.15) (type solid)) (layer "F.Fab"))
    (fp_line (start 4.525 5.993) (end 4.272 5.993)
      (stroke (width 0.15) (type solid)) (layer "F.Fab"))
    (fp_line (start 4.525 5.993) (end 4.525 5.993)
      (stroke (width 0.15) (type solid)) (layer "F.Fab"))
    (fp_line (start 4.527 -5.995) (end 4.272 -5.995)
      (stroke (width 0.15) (type solid)) (layer "F.Fab"))
    (fp_line (start 4.527 -5.995) (end 4.527 -5.995)
      (stroke (width 0.15) (type solid)) (layer "F.Fab"))
    (fp_line (start 4.671 -5.995) (end 4.671 -5.995)
      (stroke (width 0.15) (type solid)) (layer "F.Fab"))
    (fp_line (start 4.671 -5.995) (end 4.926 -5.995)
      (stroke (width 0.15) (type solid)) (layer "F.Fab"))
    (fp_line (start 4.671 5.993) (end 4.671 5.993)
      (stroke (width 0.15) (type solid)) (layer "F.Fab"))
    (fp_line (start 4.671 5.993) (end 4.926 5.993)
      (stroke (width 0.15) (type solid)) (layer "F.Fab"))
    (fp_line (start 4.926 -5.995) (end 4.671 -5.995)
      (stroke (width 0.15) (type solid)) (layer "F.Fab"))
    (fp_line (start 4.926 -5.995) (end 4.926 -5.995)
      (stroke (width 0.15) (type solid)) (layer "F.Fab"))
    (fp_line (start 4.926 5.993) (end 4.671 5.993)
      (stroke (width 0.15) (type solid)) (layer "F.Fab"))
    (fp_line (start 4.926 5.993) (end 4.926 5.993)
      (stroke (width 0.15) (type solid)) (layer "F.Fab"))
    (fp_line (start 5.993 -5.995) (end -5.995 -5.995)
      (stroke (width 0.15) (type solid)) (layer "F.Fab"))
    (fp_line (start 5.993 -5.995) (end 5.993 -5.995)
      (stroke (width 0.15) (type solid)) (layer "F.Fab"))
    (fp_line (start 5.993 -4.928) (end 5.993 -4.928)
      (stroke (width 0.15) (type solid)) (layer "F.Fab"))
    (fp_line (start 5.993 -4.928) (end 5.993 -4.673)
      (stroke (width 0.15) (type solid)) (layer "F.Fab"))
    (fp_line (start 5.993 -4.673) (end 5.993 -4.928)
      (stroke (width 0.15) (type solid)) (layer "F.Fab"))
    (fp_line (start 5.993 -4.673) (end 5.993 -4.673)
      (stroke (width 0.15) (type solid)) (layer "F.Fab"))
    (fp_line (start 5.993 -4.528) (end 5.993 -4.528)
      (stroke (width 0.15) (type solid)) (layer "F.Fab"))
    (fp_line (start 5.993 -4.528) (end 5.993 -4.273)
      (stroke (width 0.15) (type solid)) (layer "F.Fab"))
    (fp_line (start 5.993 -4.273) (end 5.993 -4.528)
      (stroke (width 0.15) (type solid)) (layer "F.Fab"))
    (fp_line (start 5.993 -4.273) (end 5.993 -4.273)
      (stroke (width 0.15) (type solid)) (layer "F.Fab"))
    (fp_line (start 5.993 -4.127) (end 5.993 -4.127)
      (stroke (width 0.15) (type solid)) (layer "F.Fab"))
    (fp_line (start 5.993 -4.127) (end 5.993 -3.874)
      (stroke (width 0.15) (type solid)) (layer "F.Fab"))
    (fp_line (start 5.993 -3.874) (end 5.993 -4.127)
      (stroke (width 0.15) (type solid)) (layer "F.Fab"))
    (fp_line (start 5.993 -3.874) (end 5.993 -3.874)
      (stroke (width 0.15) (type solid)) (layer "F.Fab"))
    (fp_line (start 5.993 -3.727) (end 5.993 -3.727)
      (stroke (width 0.15) (type solid)) (layer "F.Fab"))
    (fp_line (start 5.993 -3.727) (end 5.993 -3.473)
      (stroke (width 0.15) (type solid)) (layer "F.Fab"))
    (fp_line (start 5.993 -3.473) (end 5.993 -3.727)
      (stroke (width 0.15) (type solid)) (layer "F.Fab"))
    (fp_line (start 5.993 -3.473) (end 5.993 -3.473)
      (stroke (width 0.15) (type solid)) (layer "F.Fab"))
    (fp_line (start 5.993 -3.327) (end 5.993 -3.327)
      (stroke (width 0.15) (type solid)) (layer "F.Fab"))
    (fp_line (start 5.993 -3.327) (end 5.993 -3.073)
      (stroke (width 0.15) (type solid)) (layer "F.Fab"))
    (fp_line (start 5.993 -3.073) (end 5.993 -3.327)
      (stroke (width 0.15) (type solid)) (layer "F.Fab"))
    (fp_line (start 5.993 -3.073) (end 5.993 -3.073)
      (stroke (width 0.15) (type solid)) (layer "F.Fab"))
    (fp_line (start 5.993 -2.927) (end 5.993 -2.927)
      (stroke (width 0.15) (type solid)) (layer "F.Fab"))
    (fp_line (start 5.993 -2.927) (end 5.993 -2.673)
      (stroke (width 0.15) (type solid)) (layer "F.Fab"))
    (fp_line (start 5.993 -2.673) (end 5.993 -2.927)
      (stroke (width 0.15) (type solid)) (layer "F.Fab"))
    (fp_line (start 5.993 -2.673) (end 5.993 -2.673)
      (stroke (width 0.15) (type solid)) (layer "F.Fab"))
    (fp_line (start 5.993 -2.528) (end 5.993 -2.528)
      (stroke (width 0.15) (type solid)) (layer "F.Fab"))
    (fp_line (start 5.993 -2.528) (end 5.993 -2.274)
      (stroke (width 0.15) (type solid)) (layer "F.Fab"))
    (fp_line (start 5.993 -2.274) (end 5.993 -2.528)
      (stroke (width 0.15) (type solid)) (layer "F.Fab"))
    (fp_line (start 5.993 -2.274) (end 5.993 -2.274)
      (stroke (width 0.15) (type solid)) (layer "F.Fab"))
    (fp_line (start 5.993 -2.128) (end 5.993 -2.128)
      (stroke (width 0.15) (type solid)) (layer "F.Fab"))
    (fp_line (start 5.993 -2.128) (end 5.993 -1.873)
      (stroke (width 0.15) (type solid)) (layer "F.Fab"))
    (fp_line (start 5.993 -1.873) (end 5.993 -2.128)
      (stroke (width 0.15) (type solid)) (layer "F.Fab"))
    (fp_line (start 5.993 -1.873) (end 5.993 -1.873)
      (stroke (width 0.15) (type solid)) (layer "F.Fab"))
    (fp_line (start 5.993 -1.728) (end 5.993 -1.728)
      (stroke (width 0.15) (type solid)) (layer "F.Fab"))
    (fp_line (start 5.993 -1.728) (end 5.993 -1.474)
      (stroke (width 0.15) (type solid)) (layer "F.Fab"))
    (fp_line (start 5.993 -1.474) (end 5.993 -1.728)
      (stroke (width 0.15) (type solid)) (layer "F.Fab"))
    (fp_line (start 5.993 -1.474) (end 5.993 -1.474)
      (stroke (width 0.15) (type solid)) (layer "F.Fab"))
    (fp_line (start 5.993 -1.327) (end 5.993 -1.327)
      (stroke (width 0.15) (type solid)) (layer "F.Fab"))
    (fp_line (start 5.993 -1.327) (end 5.993 -1.073)
      (stroke (width 0.15) (type solid)) (layer "F.Fab"))
    (fp_line (start 5.993 -1.073) (end 5.993 -1.327)
      (stroke (width 0.15) (type solid)) (layer "F.Fab"))
    (fp_line (start 5.993 -1.073) (end 5.993 -1.073)
      (stroke (width 0.15) (type solid)) (layer "F.Fab"))
    (fp_line (start 5.993 -0.929) (end 5.993 -0.929)
      (stroke (width 0.15) (type solid)) (layer "F.Fab"))
    (fp_line (start 5.993 -0.929) (end 5.993 -0.675)
      (stroke (width 0.15) (type solid)) (layer "F.Fab"))
    (fp_line (start 5.993 -0.675) (end 5.993 -0.929)
      (stroke (width 0.15) (type solid)) (layer "F.Fab"))
    (fp_line (start 5.993 -0.675) (end 5.993 -0.675)
      (stroke (width 0.15) (type solid)) (layer "F.Fab"))
    (fp_line (start 5.993 -0.529) (end 5.993 -0.529)
      (stroke (width 0.15) (type solid)) (layer "F.Fab"))
    (fp_line (start 5.993 -0.529) (end 5.993 -0.275)
      (stroke (width 0.15) (type solid)) (layer "F.Fab"))
    (fp_line (start 5.993 -0.275) (end 5.993 -0.529)
      (stroke (width 0.15) (type solid)) (layer "F.Fab"))
    (fp_line (start 5.993 -0.275) (end 5.993 -0.275)
      (stroke (width 0.15) (type solid)) (layer "F.Fab"))
    (fp_line (start 5.993 -0.127) (end 5.993 -0.127)
      (stroke (width 0.15) (type solid)) (layer "F.Fab"))
    (fp_line (start 5.993 -0.127) (end 5.993 0.125)
      (stroke (width 0.15) (type solid)) (layer "F.Fab"))
    (fp_line (start 5.993 0.125) (end 5.993 -0.127)
      (stroke (width 0.15) (type solid)) (layer "F.Fab"))
    (fp_line (start 5.993 0.125) (end 5.993 0.125)
      (stroke (width 0.15) (type solid)) (layer "F.Fab"))
    (fp_line (start 5.993 0.273) (end 5.993 0.273)
      (stroke (width 0.15) (type solid)) (layer "F.Fab"))
    (fp_line (start 5.993 0.273) (end 5.993 0.527)
      (stroke (width 0.15) (type solid)) (layer "F.Fab"))
    (fp_line (start 5.993 0.527) (end 5.993 0.273)
      (stroke (width 0.15) (type solid)) (layer "F.Fab"))
    (fp_line (start 5.993 0.527) (end 5.993 0.527)
      (stroke (width 0.15) (type solid)) (layer "F.Fab"))
    (fp_line (start 5.993 0.673) (end 5.993 0.673)
      (stroke (width 0.15) (type solid)) (layer "F.Fab"))
    (fp_line (start 5.993 0.673) (end 5.993 0.927)
      (stroke (width 0.15) (type solid)) (layer "F.Fab"))
    (fp_line (start 5.993 0.927) (end 5.993 0.673)
      (stroke (width 0.15) (type solid)) (layer "F.Fab"))
    (fp_line (start 5.993 0.927) (end 5.993 0.927)
      (stroke (width 0.15) (type solid)) (layer "F.Fab"))
    (fp_line (start 5.993 1.072) (end 5.993 1.072)
      (stroke (width 0.15) (type solid)) (layer "F.Fab"))
    (fp_line (start 5.993 1.072) (end 5.993 1.326)
      (stroke (width 0.15) (type solid)) (layer "F.Fab"))
    (fp_line (start 5.993 1.326) (end 5.993 1.072)
      (stroke (width 0.15) (type solid)) (layer "F.Fab"))
    (fp_line (start 5.993 1.326) (end 5.993 1.326)
      (stroke (width 0.15) (type solid)) (layer "F.Fab"))
    (fp_line (start 5.993 1.473) (end 5.993 1.473)
      (stroke (width 0.15) (type solid)) (layer "F.Fab"))
    (fp_line (start 5.993 1.473) (end 5.993 1.727)
      (stroke (width 0.15) (type solid)) (layer "F.Fab"))
    (fp_line (start 5.993 1.727) (end 5.993 1.473)
      (stroke (width 0.15) (type solid)) (layer "F.Fab"))
    (fp_line (start 5.993 1.727) (end 5.993 1.727)
      (stroke (width 0.15) (type solid)) (layer "F.Fab"))
    (fp_line (start 5.993 1.872) (end 5.993 1.872)
      (stroke (width 0.15) (type solid)) (layer "F.Fab"))
    (fp_line (start 5.993 1.872) (end 5.993 2.125)
      (stroke (width 0.15) (type solid)) (layer "F.Fab"))
    (fp_line (start 5.993 2.125) (end 5.993 1.872)
      (stroke (width 0.15) (type solid)) (layer "F.Fab"))
    (fp_line (start 5.993 2.125) (end 5.993 2.125)
      (stroke (width 0.15) (type solid)) (layer "F.Fab"))
    (fp_line (start 5.993 2.273) (end 5.993 2.273)
      (stroke (width 0.15) (type solid)) (layer "F.Fab"))
    (fp_line (start 5.993 2.273) (end 5.993 2.527)
      (stroke (width 0.15) (type solid)) (layer "F.Fab"))
    (fp_line (start 5.993 2.527) (end 5.993 2.273)
      (stroke (width 0.15) (type solid)) (layer "F.Fab"))
    (fp_line (start 5.993 2.527) (end 5.993 2.527)
      (stroke (width 0.15) (type solid)) (layer "F.Fab"))
    (fp_line (start 5.993 2.672) (end 5.993 2.672)
      (stroke (width 0.15) (type solid)) (layer "F.Fab"))
    (fp_line (start 5.993 2.672) (end 5.993 2.926)
      (stroke (width 0.15) (type solid)) (layer "F.Fab"))
    (fp_line (start 5.993 2.926) (end 5.993 2.672)
      (stroke (width 0.15) (type solid)) (layer "F.Fab"))
    (fp_line (start 5.993 2.926) (end 5.993 2.926)
      (stroke (width 0.15) (type solid)) (layer "F.Fab"))
    (fp_line (start 5.993 3.072) (end 5.993 3.072)
      (stroke (width 0.15) (type solid)) (layer "F.Fab"))
    (fp_line (start 5.993 3.072) (end 5.993 3.325)
      (stroke (width 0.15) (type solid)) (layer "F.Fab"))
    (fp_line (start 5.993 3.325) (end 5.993 3.072)
      (stroke (width 0.15) (type solid)) (layer "F.Fab"))
    (fp_line (start 5.993 3.325) (end 5.993 3.325)
      (stroke (width 0.15) (type solid)) (layer "F.Fab"))
    (fp_line (start 5.993 3.471) (end 5.993 3.471)
      (stroke (width 0.15) (type solid)) (layer "F.Fab"))
    (fp_line (start 5.993 3.471) (end 5.993 3.725)
      (stroke (width 0.15) (type solid)) (layer "F.Fab"))
    (fp_line (start 5.993 3.725) (end 5.993 3.471)
      (stroke (width 0.15) (type solid)) (layer "F.Fab"))
    (fp_line (start 5.993 3.725) (end 5.993 3.725)
      (stroke (width 0.15) (type solid)) (layer "F.Fab"))
    (fp_line (start 5.993 3.873) (end 5.993 3.873)
      (stroke (width 0.15) (type solid)) (layer "F.Fab"))
    (fp_line (start 5.993 3.873) (end 5.993 4.126)
      (stroke (width 0.15) (type solid)) (layer "F.Fab"))
    (fp_line (start 5.993 4.126) (end 5.993 3.873)
      (stroke (width 0.15) (type solid)) (layer "F.Fab"))
    (fp_line (start 5.993 4.126) (end 5.993 4.126)
      (stroke (width 0.15) (type solid)) (layer "F.Fab"))
    (fp_line (start 5.993 4.272) (end 5.993 4.272)
      (stroke (width 0.15) (type solid)) (layer "F.Fab"))
    (fp_line (start 5.993 4.272) (end 5.993 4.527)
      (stroke (width 0.15) (type solid)) (layer "F.Fab"))
    (fp_line (start 5.993 4.527) (end 5.993 4.272)
      (stroke (width 0.15) (type solid)) (layer "F.Fab"))
    (fp_line (start 5.993 4.527) (end 5.993 4.527)
      (stroke (width 0.15) (type solid)) (layer "F.Fab"))
    (fp_line (start 5.993 4.671) (end 5.993 4.671)
      (stroke (width 0.15) (type solid)) (layer "F.Fab"))
    (fp_line (start 5.993 4.671) (end 5.993 4.926)
      (stroke (width 0.15) (type solid)) (layer "F.Fab"))
    (fp_line (start 5.993 4.926) (end 5.993 4.671)
      (stroke (width 0.15) (type solid)) (layer "F.Fab"))
    (fp_line (start 5.993 4.926) (end 5.993 4.926)
      (stroke (width 0.15) (type solid)) (layer "F.Fab"))
    (fp_line (start 5.993 5.993) (end 5.993 -5.995)
      (stroke (width 0.15) (type solid)) (layer "F.Fab"))
    (fp_line (start 5.993 5.993) (end 5.993 5.993)
      (stroke (width 0.15) (type solid)) (layer "F.Fab"))
    (pad "1" smd roundrect (at -5.789 -4.802 270) (size 0.204 1.011199) (layers "F.Cu" "F.Paste" "F.Mask") (roundrect_rratio 0.25)
      (net 175 "/Reset logic/~{USB_HUB_RESET}") (pinfunction "RESET_N") (pintype "input"))
    (pad "2" smd roundrect (at -5.789 -4.401 270) (size 0.204 1.011199) (layers "F.Cu" "F.Paste" "F.Mask") (roundrect_rratio 0.25)
      (net 663 "Net-(U17-PF30)") (pinfunction "PF30") (pintype "bidirectional"))
    (pad "3" smd roundrect (at -5.789 -4 270) (size 0.204 1.011199) (layers "F.Cu" "F.Paste" "F.Mask") (roundrect_rratio 0.25)
      (net 664 "Net-(U17-PF31)") (pinfunction "PF31") (pintype "bidirectional"))
    (pad "4" smd roundrect (at -5.789 -3.601 270) (size 0.204 1.011199) (layers "F.Cu" "F.Paste" "F.Mask") (roundrect_rratio 0.25)
      (net 697 "Net-(U17-DP1_VBUS_MON)") (pinfunction "DP1_VBUS_MON") (pintype "bidirectional"))
    (pad "5" smd roundrect (at -5.789 -3.201 270) (size 0.204 1.011199) (layers "F.Cu" "F.Paste" "F.Mask") (roundrect_rratio 0.25)
      (net 68 "/USB/USB1_P") (pinfunction "USB2DN_DP1/PRT_DIS_P1") (pintype "bidirectional"))
    (pad "6" smd roundrect (at -5.789 -2.801 270) (size 0.204 1.011199) (layers "F.Cu" "F.Paste" "F.Mask") (roundrect_rratio 0.25)
      (net 67 "/USB/USB1_N") (pinfunction "USB2DN_DM1/PRT_DIS_M1") (pintype "bidirectional"))
    (pad "7" smd roundrect (at -5.789 -2.4 270) (size 0.204 1.011199) (layers "F.Cu" "F.Paste" "F.Mask") (roundrect_rratio 0.25)
      (net 61 "/USB/USB1_TX_P") (pinfunction "USB3DN_TXDP1A") (pintype "bidirectional"))
    (pad "8" smd roundrect (at -5.789 -2.001 270) (size 0.204 1.011199) (layers "F.Cu" "F.Paste" "F.Mask") (roundrect_rratio 0.25)
      (net 60 "/USB/USB1_TX_N") (pinfunction "USB3DN_TXDM1A") (pintype "bidirectional"))
    (pad "9" smd roundrect (at -5.789 -1.601 270) (size 0.204 1.011199) (layers "F.Cu" "F.Paste" "F.Mask") (roundrect_rratio 0.25)
      (net 18 "PS_1V2") (pinfunction "VCORE") (pintype "passive"))
    (pad "10" smd roundrect (at -5.789 -1.2 270) (size 0.204 1.011199) (layers "F.Cu" "F.Paste" "F.Mask") (roundrect_rratio 0.25)
      (net 84 "/USB/USB1_RX_P") (pinfunction "USB3DN_RXDP1A") (pintype "bidirectional"))
    (pad "11" smd roundrect (at -5.789 -0.802 270) (size 0.204 1.011199) (layers "F.Cu" "F.Paste" "F.Mask") (roundrect_rratio 0.25)
      (net 83 "/USB/USB1_RX_N") (pinfunction "USB3DN_RXDM1A") (pintype "bidirectional"))
    (pad "12" smd roundrect (at -5.789 -0.401 270) (size 0.204 1.011199) (layers "F.Cu" "F.Paste" "F.Mask") (roundrect_rratio 0.25)
      (net 665 "Net-(U17-DP1_CC1)") (pinfunction "DP1_CC1") (pintype "bidirectional"))
    (pad "13" smd roundrect (at -5.789 0 270) (size 0.204 1.011199) (layers "F.Cu" "F.Paste" "F.Mask") (roundrect_rratio 0.25)
      (net 696 "Net-(U17-DP1_CC2)") (pinfunction "DP1_CC2") (pintype "bidirectional"))
    (pad "14" smd roundrect (at -5.789 0.399 270) (size 0.204 1.011199) (layers "F.Cu" "F.Paste" "F.Mask") (roundrect_rratio 0.25)
      (net 361 "/PCIE M2 key E /M2_USB_P") (pinfunction "USB2DN_DP5/PRT_DIS_P5") (pintype "bidirectional"))
    (pad "15" smd roundrect (at -5.789 0.8 270) (size 0.204 1.011199) (layers "F.Cu" "F.Paste" "F.Mask") (roundrect_rratio 0.25)
      (net 360 "/PCIE M2 key E /M2_USB_N") (pinfunction "USB2DN_DM5/PRT_DIS_M5") (pintype "bidirectional"))
    (pad "16" smd roundrect (at -5.789 1.199 270) (size 0.204 1.011199) (layers "F.Cu" "F.Paste" "F.Mask") (roundrect_rratio 0.25)
      (net 710 "unconnected-(U17-USB3DN_TXDP1B-Pad16)") (pinfunction "USB3DN_TXDP1B") (pintype "bidirectional+no_connect"))
    (pad "17" smd roundrect (at -5.789 1.598 270) (size 0.204 1.011199) (layers "F.Cu" "F.Paste" "F.Mask") (roundrect_rratio 0.25)
      (net 711 "unconnected-(U17-USB3DN_TXDM1B-Pad17)") (pinfunction "USB3DN_TXDM1B") (pintype "bidirectional+no_connect"))
    (pad "18" smd roundrect (at -5.789 1.999 270) (size 0.204 1.011199) (layers "F.Cu" "F.Paste" "F.Mask") (roundrect_rratio 0.25)
      (net 18 "PS_1V2") (pinfunction "VCORE") (pintype "power_in"))
    (pad "19" smd roundrect (at -5.789 2.398 270) (size 0.204 1.011199) (layers "F.Cu" "F.Paste" "F.Mask") (roundrect_rratio 0.25)
      (net 712 "unconnected-(U17-USB3DN_RXDP1B-Pad19)") (pinfunction "USB3DN_RXDP1B") (pintype "bidirectional+no_connect"))
    (pad "20" smd roundrect (at -5.789 2.798 270) (size 0.204 1.011199) (layers "F.Cu" "F.Paste" "F.Mask") (roundrect_rratio 0.25)
      (net 713 "unconnected-(U17-USB3DN_RXDM1B-Pad20)") (pinfunction "USB3DN_RXDM1B") (pintype "bidirectional+no_connect"))
    (pad "21" smd roundrect (at -5.789 3.199 270) (size 0.204 1.011199) (layers "F.Cu" "F.Paste" "F.Mask") (roundrect_rratio 0.25)
      (net 652 "Net-(U17-CFG_STRAP1)") (pinfunction "CFG_STRAP1") (pintype "input"))
    (pad "22" smd roundrect (at -5.789 3.6 270) (size 0.204 1.011199) (layers "F.Cu" "F.Paste" "F.Mask") (roundrect_rratio 0.25)
      (net 653 "Net-(U17-CFG_STRAP2)") (pinfunction "CFG_STRAP2") (pintype "input"))
    (pad "23" smd roundrect (at -5.789 3.999 270) (size 0.204 1.011199) (layers "F.Cu" "F.Paste" "F.Mask") (roundrect_rratio 0.25)
      (net 654 "Net-(U17-CFG_STRAP3)") (pinfunction "CFG_STRAP3") (pintype "input"))
    (pad "24" smd roundrect (at -5.789 4.398 270) (size 0.204 1.011199) (layers "F.Cu" "F.Paste" "F.Mask") (roundrect_rratio 0.25)
      (net 1 "GND") (pinfunction "TESTEN") (pintype "bidirectional"))
    (pad "25" smd roundrect (at -5.789 4.799 270) (size 0.204 1.011199) (layers "F.Cu" "F.Paste" "F.Mask") (roundrect_rratio 0.25)
      (net 18 "PS_1V2") (pinfunction "VCORE") (pintype "passive"))
    (pad "26" smd roundrect (at -4.802 5.788 180) (size 0.204 1.011199) (layers "F.Cu" "F.Paste" "F.Mask") (roundrect_rratio 0.25)
      (net 15 "PS_3V3") (pinfunction "VDD33") (pintype "power_in"))
    (pad "27" smd roundrect (at -4.401 5.788 180) (size 0.204 1.011199) (layers "F.Cu" "F.Paste" "F.Mask") (roundrect_rratio 0.25)
      (net 70 "/USB/USB2_P") (pinfunction "USB2DN_DP2/PRT_DIS_P2") (pintype "bidirectional"))
    (pad "28" smd roundrect (at -4 5.788 180) (size 0.204 1.011199) (layers "F.Cu" "F.Paste" "F.Mask") (roundrect_rratio 0.25)
      (net 69 "/USB/USB2_N") (pinfunction "USB2DN_DM2/PRT_DIS_M2") (pintype "bidirectional"))
    (pad "29" smd roundrect (at -3.601 5.788 180) (size 0.204 1.011199) (layers "F.Cu" "F.Paste" "F.Mask") (roundrect_rratio 0.25)
      (net 63 "/USB/USB2_TX_P") (pinfunction "USB3DN_TXDP2") (pintype "bidirectional"))
    (pad "30" smd roundrect (at -3.201 5.788 180) (size 0.204 1.011199) (layers "F.Cu" "F.Paste" "F.Mask") (roundrect_rratio 0.25)
      (net 62 "/USB/USB2_TX_N") (pinfunction "USB3DN_TXDM2") (pintype "bidirectional"))
    (pad "31" smd roundrect (at -2.801 5.788 180) (size 0.204 1.011199) (layers "F.Cu" "F.Paste" "F.Mask") (roundrect_rratio 0.25)
      (net 18 "PS_1V2") (pinfunction "VCORE") (pintype "passive"))
    (pad "32" smd roundrect (at -2.4 5.788 180) (size 0.204 1.011199) (layers "F.Cu" "F.Paste" "F.Mask") (roundrect_rratio 0.25)
      (net 82 "/USB/USB2_RX_P") (pinfunction "USB3DN_RXDP2") (pintype "bidirectional"))
    (pad "33" smd roundrect (at -2.001 5.788 180) (size 0.204 1.011199) (layers "F.Cu" "F.Paste" "F.Mask") (roundrect_rratio 0.25)
      (net 81 "/USB/USB2_RX_N") (pinfunction "USB3DN_RXDM2") (pintype "bidirectional"))
    (pad "34" smd roundrect (at -1.601 5.788 180) (size 0.204 1.011199) (layers "F.Cu" "F.Paste" "F.Mask") (roundrect_rratio 0.25)
      (net 72 "/USB/USB3_P") (pinfunction "USB2DN_DP3/PRT_DIS_P3") (pintype "bidirectional"))
    (pad "35" smd roundrect (at -1.2 5.788 180) (size 0.204 1.011199) (layers "F.Cu" "F.Paste" "F.Mask") (roundrect_rratio 0.25)
      (net 71 "/USB/USB3_N") (pinfunction "USB2DN_DM3/PRT_DIS_M3") (pintype "bidirectional"))
    (pad "36" smd roundrect (at -0.802 5.788 180) (size 0.204 1.011199) (layers "F.Cu" "F.Paste" "F.Mask") (roundrect_rratio 0.25)
      (net 66 "/USB/USB3_TX_P") (pinfunction "USB3DN_TXDP3") (pintype "bidirectional"))
    (pad "37" smd roundrect (at -0.401 5.788 180) (size 0.204 1.011199) (layers "F.Cu" "F.Paste" "F.Mask") (roundrect_rratio 0.25)
      (net 65 "/USB/USB3_TX_N") (pinfunction "USB3DN_TXDM3") (pintype "bidirectional"))
    (pad "38" smd roundrect (at 0 5.788 180) (size 0.204 1.011199) (layers "F.Cu" "F.Paste" "F.Mask") (roundrect_rratio 0.25)
      (net 18 "PS_1V2") (pinfunction "VCORE") (pintype "passive"))
    (pad "39" smd roundrect (at 0.399 5.788 180) (size 0.204 1.011199) (layers "F.Cu" "F.Paste" "F.Mask") (roundrect_rratio 0.25)
      (net 80 "/USB/USB3_RX_P") (pinfunction "USB3DN_RXDP3") (pintype "bidirectional"))
    (pad "40" smd roundrect (at 0.8 5.788 180) (size 0.204 1.011199) (layers "F.Cu" "F.Paste" "F.Mask") (roundrect_rratio 0.25)
      (net 79 "/USB/USB3_RX_N") (pinfunction "USB3DN_RXDM3") (pintype "bidirectional"))
    (pad "41" smd roundrect (at 1.199 5.788 180) (size 0.204 1.011199) (layers "F.Cu" "F.Paste" "F.Mask") (roundrect_rratio 0.25)
      (net 15 "PS_3V3") (pinfunction "USB2DN_DM6/PRT_DIS_M6") (pintype "bidirectional"))
    (pad "42" smd roundrect (at 1.598 5.788 180) (size 0.204 1.011199) (layers "F.Cu" "F.Paste" "F.Mask") (roundrect_rratio 0.25)
      (net 15 "PS_3V3") (pinfunction "USB2DN_DP6/PRT_DIS_P6") (pintype "bidirectional"))
    (pad "43" smd roundrect (at 1.999 5.788 180) (size 0.204 1.011199) (layers "F.Cu" "F.Paste" "F.Mask") (roundrect_rratio 0.25)
      (net 15 "PS_3V3") (pinfunction "VDD33") (pintype "passive"))
    (pad "44" smd roundrect (at 2.398 5.788 180) (size 0.204 1.011199) (layers "F.Cu" "F.Paste" "F.Mask") (roundrect_rratio 0.25)
      (net 656 "Net-(U17-PF3)") (pinfunction "PF3") (pintype "bidirectional"))
    (pad "45" smd roundrect (at 2.798 5.788 180) (size 0.204 1.011199) (layers "F.Cu" "F.Paste" "F.Mask") (roundrect_rratio 0.25)
      (net 657 "Net-(U17-PF4)") (pinfunction "PF4") (pintype "bidirectional"))
    (pad "46" smd roundrect (at 3.199 5.788 180) (size 0.204 1.011199) (layers "F.Cu" "F.Paste" "F.Mask") (roundrect_rratio 0.25)
      (net 658 "Net-(U17-PF5)") (pinfunction "PF5") (pintype "bidirectional"))
    (pad "47" smd roundrect (at 3.6 5.788 180) (size 0.204 1.011199) (layers "F.Cu" "F.Paste" "F.Mask") (roundrect_rratio 0.25)
      (net 659 "Net-(U17-PF6)") (pinfunction "PF6") (pintype "bidirectional"))
    (pad "48" smd roundrect (at 3.999 5.788 180) (size 0.204 1.011199) (layers "F.Cu" "F.Paste" "F.Mask") (roundrect_rratio 0.25)
      (net 660 "Net-(U17-PF7)") (pinfunction "PF7") (pintype "bidirectional"))
    (pad "49" smd roundrect (at 4.398 5.788 180) (size 0.204 1.011199) (layers "F.Cu" "F.Paste" "F.Mask") (roundrect_rratio 0.25)
      (net 661 "Net-(U17-PF8)") (pinfunction "PF8") (pintype "bidirectional"))
    (pad "50" smd roundrect (at 4.799 5.788 180) (size 0.204 1.011199) (layers "F.Cu" "F.Paste" "F.Mask") (roundrect_rratio 0.25)
      (net 662 "Net-(U17-PF9)") (pinfunction "PF9") (pintype "bidirectional"))
    (pad "51" smd roundrect (at 5.788 4.799 270) (size 0.204 1.011199) (layers "F.Cu" "F.Paste" "F.Mask") (roundrect_rratio 0.25)
      (net 714 "unconnected-(U17-PF10-Pad51)") (pinfunction "PF10") (pintype "bidirectional+no_connect"))
    (pad "52" smd roundrect (at 5.788 4.398 270) (size 0.204 1.011199) (layers "F.Cu" "F.Paste" "F.Mask") (roundrect_rratio 0.25)
      (net 715 "unconnected-(U17-PF11-Pad52)") (pinfunction "PF11") (pintype "bidirectional+no_connect"))
    (pad "53" smd roundrect (at 5.788 3.999 270) (size 0.204 1.011199) (layers "F.Cu" "F.Paste" "F.Mask") (roundrect_rratio 0.25)
      (net 15 "PS_3V3") (pinfunction "VDD33") (pintype "passive"))
    (pad "54" smd roundrect (at 5.788 3.6 270) (size 0.204 1.011199) (layers "F.Cu" "F.Paste" "F.Mask") (roundrect_rratio 0.25)
      (net 716 "unconnected-(U17-PF12-Pad54)") (pinfunction "PF12") (pintype "bidirectional+no_connect"))
    (pad "55" smd roundrect (at 5.788 3.199 270) (size 0.204 1.011199) (layers "F.Cu" "F.Paste" "F.Mask") (roundrect_rratio 0.25)
      (net 18 "PS_1V2") (pinfunction "VCORE") (pintype "passive"))
    (pad "56" smd roundrect (at 5.788 2.798 270) (size 0.204 1.011199) (layers "F.Cu" "F.Paste" "F.Mask") (roundrect_rratio 0.25)
      (net 305 "/USB/USB_PRT_CTL4") (pinfunction "PF13") (pintype "bidirectional"))
    (pad "57" smd roundrect (at 5.788 2.398 270) (size 0.204 1.011199) (layers "F.Cu" "F.Paste" "F.Mask") (roundrect_rratio 0.25)
      (net 304 "/USB/USB_PRT_CTL3") (pinfunction "PF14") (pintype "bidirectional"))
    (pad "58" smd roundrect (at 5.788 1.999 270) (size 0.204 1.011199) (layers "F.Cu" "F.Paste" "F.Mask") (roundrect_rratio 0.25)
      (net 303 "/USB/USB_PRT_CTL2") (pinfunction "PF15") (pintype "bidirectional"))
    (pad "59" smd roundrect (at 5.788 1.598 270) (size 0.204 1.011199) (layers "F.Cu" "F.Paste" "F.Mask") (roundrect_rratio 0.25)
      (net 717 "unconnected-(U17-PF16-Pad59)") (pinfunction "PF16") (pintype "bidirectional+no_connect"))
    (pad "60" smd roundrect (at 5.788 1.199 270) (size 0.204 1.011199) (layers "F.Cu" "F.Paste" "F.Mask") (roundrect_rratio 0.25)
      (net 302 "/USB/USB_PRT_CTL1") (pinfunction "PF17") (pintype "bidirectional"))
    (pad "61" smd roundrect (at 5.788 0.8 270) (size 0.204 1.011199) (layers "F.Cu" "F.Paste" "F.Mask") (roundrect_rratio 0.25)
      (net 718 "unconnected-(U17-PF18-Pad61)") (pinfunction "PF18") (pintype "bidirectional+no_connect"))
    (pad "62" smd roundrect (at 5.788 0.399 270) (size 0.204 1.011199) (layers "F.Cu" "F.Paste" "F.Mask") (roundrect_rratio 0.25)
      (net 15 "PS_3V3") (pinfunction "VDD33") (pintype "passive"))
    (pad "63" smd roundrect (at 5.788 0 270) (size 0.204 1.011199) (layers "F.Cu" "F.Paste" "F.Mask") (roundrect_rratio 0.25)
      (net 649 "Net-(U17-TEST1)") (pinfunction "TEST1") (pintype "passive"))
    (pad "64" smd roundrect (at 5.788 -0.401 270) (size 0.204 1.011199) (layers "F.Cu" "F.Paste" "F.Mask") (roundrect_rratio 0.25)
      (net 650 "Net-(U17-TEST2)") (pinfunction "TEST2") (pintype "passive"))
    (pad "65" smd roundrect (at 5.788 -0.802 270) (size 0.204 1.011199) (layers "F.Cu" "F.Paste" "F.Mask") (roundrect_rratio 0.25)
      (net 651 "Net-(U17-TEST3)") (pinfunction "TEST3") (pintype "passive"))
    (pad "66" smd roundrect (at 5.788 -1.2 270) (size 0.204 1.011199) (layers "F.Cu" "F.Paste" "F.Mask") (roundrect_rratio 0.25)
      (net 719 "unconnected-(U17-PF19-Pad66)") (pinfunction "PF19") (pintype "bidirectional+no_connect"))
    (pad "67" smd roundrect (at 5.788 -1.601 270) (size 0.204 1.011199) (layers "F.Cu" "F.Paste" "F.Mask") (roundrect_rratio 0.25)
      (net 15 "PS_3V3") (pinfunction "VDD33") (pintype "passive"))
    (pad "68" smd roundrect (at 5.788 -2 270) (size 0.204 1.011199) (layers "F.Cu" "F.Paste" "F.Mask") (roundrect_rratio 0.25)
      (net 643 "Net-(U17-SPI_CLK{slash}PF21)") (pinfunction "SPI_CLK/PF21") (pintype "bidirectional"))
    (pad "69" smd roundrect (at 5.788 -2.4 270) (size 0.204 1.011199) (layers "F.Cu" "F.Paste" "F.Mask") (roundrect_rratio 0.25)
      (net 644 "Net-(U17-SPI_CE_N{slash}CFG_NON_REM{slash}PF20)") (pinfunction "SPI_CE_N/CFG_NON_REM/PF20") (pintype "bidirectional"))
    (pad "70" smd roundrect (at 5.788 -2.801 270) (size 0.204 1.011199) (layers "F.Cu" "F.Paste" "F.Mask") (roundrect_rratio 0.25)
      (net 645 "Net-(U17-SPI_D0{slash}CFG_BC_EN{slash}PF22)") (pinfunction "SPI_D0/CFG_BC_EN/PF22") (pintype "bidirectional"))
    (pad "71" smd roundrect (at 5.788 -3.201 270) (size 0.204 1.011199) (layers "F.Cu" "F.Paste" "F.Mask") (roundrect_rratio 0.25)
      (net 646 "Net-(U17-SPI_D1{slash}PF23)") (pinfunction "SPI_D1/PF23") (pintype "bidirectional"))
    (pad "72" smd roundrect (at 5.788 -3.601 270) (size 0.204 1.011199) (layers "F.Cu" "F.Paste" "F.Mask") (roundrect_rratio 0.25)
      (net 647 "Net-(U17-SPI_D2{slash}PF24)") (pinfunction "SPI_D2/PF24") (pintype "bidirectional"))
    (pad "73" smd roundrect (at 5.788 -4 270) (size 0.204 1.011199) (layers "F.Cu" "F.Paste" "F.Mask") (roundrect_rratio 0.25)
      (net 648 "Net-(U17-SPI_D3{slash}PF25)") (pinfunction "SPI_D3/PF25") (pintype "bidirectional"))
    (pad "74" smd roundrect (at 5.788 -4.401 270) (size 0.204 1.011199) (layers "F.Cu" "F.Paste" "F.Mask") (roundrect_rratio 0.25)
      (net 720 "unconnected-(U17-PF29-Pad74)") (pinfunction "PF29") (pintype "bidirectional+no_connect"))
    (pad "75" smd roundrect (at 5.788 -4.8 270) (size 0.204 1.011199) (layers "F.Cu" "F.Paste" "F.Mask") (roundrect_rratio 0.25)
      (net 666 "Net-(U17-PF26)") (pinfunction "PF26") (pintype "bidirectional"))
    (pad "76" smd roundrect (at 4.799 -5.789 180) (size 0.204 1.011199) (layers "F.Cu" "F.Paste" "F.Mask") (roundrect_rratio 0.25)
      (net 667 "Net-(U17-PF27)") (pinfunction "PF27") (pintype "bidirectional"))
    (pad "77" smd roundrect (at 4.398 -5.789 180) (size 0.204 1.011199) (layers "F.Cu" "F.Paste" "F.Mask") (roundrect_rratio 0.25)
      (net 721 "unconnected-(U17-PF28-Pad77)") (pinfunction "PF28") (pintype "bidirectional+no_connect"))
    (pad "78" smd roundrect (at 3.999 -5.789 180) (size 0.204 1.011199) (layers "F.Cu" "F.Paste" "F.Mask") (roundrect_rratio 0.25)
      (net 18 "PS_1V2") (pinfunction "VCORE") (pintype "passive"))
    (pad "79" smd roundrect (at 3.6 -5.789 180) (size 0.204 1.011199) (layers "F.Cu" "F.Paste" "F.Mask") (roundrect_rratio 0.25)
      (net 15 "PS_3V3") (pinfunction "VDD33") (pintype "passive"))
    (pad "80" smd roundrect (at 3.199 -5.789 180) (size 0.204 1.011199) (layers "F.Cu" "F.Paste" "F.Mask") (roundrect_rratio 0.25)
      (net 275 "/USB/VBUS") (pinfunction "VBUS_MON_UP") (pintype "bidirectional"))
    (pad "81" smd roundrect (at 2.798 -5.789 180) (size 0.204 1.011199) (layers "F.Cu" "F.Paste" "F.Mask") (roundrect_rratio 0.25)
      (net 78 "/USB/USB4_P") (pinfunction "USB2DN_DP4/PRT_DIS_P4") (pintype "bidirectional"))
    (pad "82" smd roundrect (at 2.398 -5.789 180) (size 0.204 1.011199) (layers "F.Cu" "F.Paste" "F.Mask") (roundrect_rratio 0.25)
      (net 77 "/USB/USB4_N") (pinfunction "USB2DN_DM4/PRT_DIS_M4") (pintype "bidirectional"))
    (pad "83" smd roundrect (at 1.999 -5.789 180) (size 0.204 1.011199) (layers "F.Cu" "F.Paste" "F.Mask") (roundrect_rratio 0.25)
      (net 76 "/USB/USB4_TX_P") (pinfunction "USB3DN_TXDP4") (pintype "bidirectional"))
    (pad "84" smd roundrect (at 1.598 -5.789 180) (size 0.204 1.011199) (layers "F.Cu" "F.Paste" "F.Mask") (roundrect_rratio 0.25)
      (net 75 "/USB/USB4_TX_N") (pinfunction "USB3DN_TXDM4") (pintype "bidirectional"))
    (pad "85" smd roundrect (at 1.199 -5.789 180) (size 0.204 1.011199) (layers "F.Cu" "F.Paste" "F.Mask") (roundrect_rratio 0.25)
      (net 18 "PS_1V2") (pinfunction "VCORE") (pintype "passive"))
    (pad "86" smd roundrect (at 0.8 -5.789 180) (size 0.204 1.011199) (layers "F.Cu" "F.Paste" "F.Mask") (roundrect_rratio 0.25)
      (net 74 "/USB/USB4_RX_P") (pinfunction "USB3DN_RXDP4") (pintype "bidirectional"))
    (pad "87" smd roundrect (at 0.399 -5.789 180) (size 0.204 1.011199) (layers "F.Cu" "F.Paste" "F.Mask") (roundrect_rratio 0.25)
      (net 73 "/USB/USB4_RX_N") (pinfunction "USB3DN_RXDM4") (pintype "bidirectional"))
    (pad "88" smd roundrect (at 0 -5.789 180) (size 0.204 1.011199) (layers "F.Cu" "F.Paste" "F.Mask") (roundrect_rratio 0.25)
      (net 15 "PS_3V3") (pinfunction "VDD33") (pintype "passive"))
    (pad "89" smd roundrect (at -0.401 -5.789 180) (size 0.204 1.011199) (layers "F.Cu" "F.Paste" "F.Mask") (roundrect_rratio 0.25)
      (net 55 "/USB/USB2_PHY_P") (pinfunction "USB2UP_DP") (pintype "bidirectional"))
    (pad "90" smd roundrect (at -0.802 -5.789 180) (size 0.204 1.011199) (layers "F.Cu" "F.Paste" "F.Mask") (roundrect_rratio 0.25)
      (net 54 "/USB/USB2_PHY_N") (pinfunction "USB2UP_DM") (pintype "bidirectional"))
    (pad "91" smd roundrect (at -1.2 -5.789 180) (size 0.204 1.011199) (layers "F.Cu" "F.Paste" "F.Mask") (roundrect_rratio 0.25)
      (net 52 "/USB/GTR_DP2_C2M_C_P") (pinfunction "USB3UP_TXDP") (pintype "bidirectional"))
    (pad "92" smd roundrect (at -1.601 -5.789 180) (size 0.204 1.011199) (layers "F.Cu" "F.Paste" "F.Mask") (roundrect_rratio 0.25)
      (net 53 "/USB/GTR_DP2_C2M_C_N") (pinfunction "USB3UP_TXDM") (pintype "bidirectional"))
    (pad "93" smd roundrect (at -2 -5.789 180) (size 0.204 1.011199) (layers "F.Cu" "F.Paste" "F.Mask") (roundrect_rratio 0.25)
      (net 18 "PS_1V2") (pinfunction "VCORE") (pintype "passive"))
    (pad "94" smd roundrect (at -2.4 -5.789 180) (size 0.204 1.011199) (layers "F.Cu" "F.Paste" "F.Mask") (roundrect_rratio 0.25)
      (net 320 "/USB/GTR_DP2_M2C_C_P") (pinfunction "USB3UP_RXDP") (pintype "bidirectional"))
    (pad "95" smd roundrect (at -2.801 -5.789 180) (size 0.204 1.011199) (layers "F.Cu" "F.Paste" "F.Mask") (roundrect_rratio 0.25)
      (net 321 "/USB/GTR_DP2_M2C_C_N") (pinfunction "USB3UP_RXDM") (pintype "bidirectional"))
    (pad "96" smd roundrect (at -3.201 -5.789 180) (size 0.204 1.011199) (layers "F.Cu" "F.Paste" "F.Mask") (roundrect_rratio 0.25)
      (net 722 "unconnected-(U17-ATEST-Pad96)") (pinfunction "ATEST") (pintype "no_connect"))
    (pad "97" smd roundrect (at -3.601 -5.789 180) (size 0.204 1.011199) (layers "F.Cu" "F.Paste" "F.Mask") (roundrect_rratio 0.25)
      (net 723 "unconnected-(U17-XTALO-Pad97)") (pinfunction "XTALO") (pintype "output+no_connect"))
    (pad "98" smd roundrect (at -4 -5.789 180) (size 0.204 1.011199) (layers "F.Cu" "F.Paste" "F.Mask") (roundrect_rratio 0.25)
      (net 294 "/USB/CLK_IN") (pinfunction "XTALI/CLK_IN") (pintype "input"))
    (pad "99" smd roundrect (at -4.401 -5.789 180) (size 0.204 1.011199) (layers "F.Cu" "F.Paste" "F.Mask") (roundrect_rratio 0.25)
      (net 15 "PS_3V3") (pinfunction "VDD33") (pintype "passive"))
    (pad "100" smd roundrect (at -4.8 -5.789 180) (size 0.204 1.011199) (layers "F.Cu" "F.Paste" "F.Mask") (roundrect_rratio 0.25)
      (net 655 "Net-(U17-RBIAS)") (pinfunction "RBIAS") (pintype "input"))
    (pad "101" smd roundrect (at 0 0 180) (size 8.1026 8.1026) (layers "F.Cu" "F.Mask") (roundrect_rratio 0.05)
      (net 1 "GND") (pinfunction "VSS") (pintype "power_in"))
  )

  (footprint "kria-k26-devboard-footprints:R_0402_1005Metric" (layer "F.Cu")
    (at 114.3 89.875)
    (descr "Resistor SMD 0402")
    (tags "resistor SMD 0402")
    (property "Author" "Antmicro")
    (property "DNP" "DNP")
    (property "License" "Apache-2.0")
    (property "MPN" "CR0402-FX-4701GLF")
    (property "Manufacturer" "Bourns")
    (property "Sheetfile" "usb.kicad_sch")
    (property "Sheetname" "USB")
    (property "Tolerance" "1%")
    (property "Val" "4k7")
    (property "dnp" "")
    (property "exclude_from_bom" "")
    (property "ki_description" "4k7 resistor in 0402 package with 1% tolerance")
    (attr exclude_from_pos_files exclude_from_bom)
    (fp_text reference "R63" (at -3.156942 0.655139) (layer "F.SilkS")
        (effects (font (size 0.7 0.7) (thickness 0.15)) (justify left bottom))
    )
    (fp_text value "R_4k7_0402" (at 0 1.4) (layer "F.Fab") hide
        (effects (font (size 0.7 0.7) (thickness 0.15)) (justify left bottom))
    )
    (fp_text user "${REFERENCE}" (at -0.95 3.168) (layer "F.Fab") hide
        (effects (font (size 0.7 0.7) (thickness 0.15)) (justify left bottom))
    )
    (fp_text user "Author: Antmicro" (at -0.95 4.169) (layer "F.Fab") hide
        (effects (font (size 0.7 0.7) (thickness 0.15)) (justify left bottom))
    )
    (fp_text user "License: Apache-2.0" (at -0.95 5.169) (layer "F.Fab") hide
        (effects (font (size 0.7 0.7) (thickness 0.15)) (justify left bottom))
    )
    (fp_rect (start -0.93 -0.47) (end 0.93 0.47)
      (stroke (width 0.05) (type solid)) (fill none) (layer "F.CrtYd"))
    (fp_rect (start -0.5 -0.25) (end 0.5 0.25)
      (stroke (width 0.15) (type solid)) (fill none) (layer "F.Fab"))
    (pad "1" smd roundrect (at -0.485 0) (size 0.59 0.64) (layers "F.Cu" "F.Paste" "F.Mask") (roundrect_rratio 0.25)
      (net 15 "PS_3V3") (pintype "passive"))
    (pad "2" smd roundrect (at 0.485 0) (size 0.59 0.64) (layers "F.Cu" "F.Paste" "F.Mask") (roundrect_rratio 0.25)
      (net 666 "Net-(U17-PF26)") (pintype "passive"))
  )

  (footprint "kria-k26-devboard-footprints:R_0402_1005Metric" (layer "F.Cu")
    (at 116.45 92.55 90)
    (descr "Resistor SMD 0402")
    (tags "resistor SMD 0402")
    (property "Author" "Antmicro")
    (property "DNP" "DNP")
    (property "License" "Apache-2.0")
    (property "MPN" "CR0402-FX-4701GLF")
    (property "Manufacturer" "Bourns")
    (property "Sheetfile" "usb.kicad_sch")
    (property "Sheetname" "USB")
    (property "Tolerance" "1%")
    (property "Val" "4k7")
    (property "dnp" "")
    (property "exclude_from_bom" "")
    (property "ki_description" "4k7 resistor in 0402 package with 1% tolerance")
    (attr exclude_from_pos_files exclude_from_bom)
    (fp_text reference "R64" (at -1 -0.58 90) (layer "F.SilkS")
        (effects (font (size 0.7 0.7) (thickness 0.15)) (justify left bottom))
    )
    (fp_text value "R_4k7_0402" (at 0 1.4 90) (layer "F.Fab") hide
        (effects (font (size 0.7 0.7) (thickness 0.15)) (justify left bottom))
    )
    (fp_text user "Author: Antmicro" (at -0.95 4.169 90) (layer "F.Fab") hide
        (effects (font (size 0.7 0.7) (thickness 0.15)) (justify left bottom))
    )
    (fp_text user "${REFERENCE}" (at -0.95 3.168 90) (layer "F.Fab") hide
        (effects (font (size 0.7 0.7) (thickness 0.15)) (justify left bottom))
    )
    (fp_text user "License: Apache-2.0" (at -0.95 5.169 90) (layer "F.Fab") hide
        (effects (font (size 0.7 0.7) (thickness 0.15)) (justify left bottom))
    )
    (fp_rect (start -0.93 -0.47) (end 0.93 0.47)
      (stroke (width 0.05) (type solid)) (fill none) (layer "F.CrtYd"))
    (fp_rect (start -0.5 -0.25) (end 0.5 0.25)
      (stroke (width 0.15) (type solid)) (fill none) (layer "F.Fab"))
    (pad "1" smd roundrect (at -0.485 0 90) (size 0.59 0.64) (layers "F.Cu" "F.Paste" "F.Mask") (roundrect_rratio 0.25)
      (net 15 "PS_3V3") (pintype "passive"))
    (pad "2" smd roundrect (at 0.485 0 90) (size 0.59 0.64) (layers "F.Cu" "F.Paste" "F.Mask") (roundrect_rratio 0.25)
      (net 667 "Net-(U17-PF27)") (pintype "passive"))
  )

  (footprint "kria-k26-devboard-footprints:R_0402_1005Metric" (layer "F.Cu")
    (at 84.046 94.249 180)
    (descr "Resistor SMD 0402")
    (tags "resistor SMD 0402")
    (property "Author" "Antmicro")
    (property "License" "Apache-2.0")
    (property "MPN" "CR0402-FX-2201GLF")
    (property "Manufacturer" "Bourns")
    (property "Sheetfile" "camera.kicad_sch")
    (property "Sheetname" "Camera interface")
    (property "Tolerance" "1%")
    (property "Val" "2k2")
    (property "ki_description" "2k2 resistor in 0402 package with 1% tolerance")
    (attr smd)
    (fp_text reference "R32" (at 1.07 3.64 180) (layer "F.SilkS")
        (effects (font (size 0.7 0.7) (thickness 0.15)) (justify left bottom))
    )
    (fp_text value "R_2k2_0402" (at 0 1.4 180) (layer "F.Fab") hide
        (effects (font (size 0.7 0.7) (thickness 0.15)) (justify left bottom))
    )
    (fp_text user "${REFERENCE}" (at -0.95 3.168 180) (layer "F.Fab") hide
        (effects (font (size 0.7 0.7) (thickness 0.15)) (justify left bottom))
    )
    (fp_text user "Author: Antmicro" (at -0.95 4.169 180) (layer "F.Fab") hide
        (effects (font (size 0.7 0.7) (thickness 0.15)) (justify left bottom))
    )
    (fp_text user "License: Apache-2.0" (at -0.95 5.169 180) (layer "F.Fab") hide
        (effects (font (size 0.7 0.7) (thickness 0.15)) (justify left bottom))
    )
    (fp_rect (start -0.93 -0.47) (end 0.93 0.47)
      (stroke (width 0.05) (type solid)) (fill none) (layer "F.CrtYd"))
    (fp_rect (start -0.5 -0.25) (end 0.5 0.25)
      (stroke (width 0.15) (type solid)) (fill none) (layer "F.Fab"))
    (pad "1" smd roundrect (at -0.485 0 180) (size 0.59 0.64) (layers "F.Cu" "F.Paste" "F.Mask") (roundrect_rratio 0.25)
      (net 20 "PL_3V3") (pintype "passive"))
    (pad "2" smd roundrect (at 0.485 0 180) (size 0.59 0.64) (layers "F.Cu" "F.Paste" "F.Mask") (roundrect_rratio 0.25)
      (net 194 "/Camera interface/CCI1_I2C_SDA_3V3") (pintype "passive"))
  )

  (footprint "kria-k26-devboard-footprints:R_0402_1005Metric" (layer "F.Cu")
    (at 84.05 96.25 180)
    (descr "Resistor SMD 0402")
    (tags "resistor SMD 0402")
    (property "Author" "Antmicro")
    (property "License" "Apache-2.0")
    (property "MPN" "CR0402-FX-2201GLF")
    (property "Manufacturer" "Bourns")
    (property "Sheetfile" "camera.kicad_sch")
    (property "Sheetname" "Camera interface")
    (property "Tolerance" "1%")
    (property "Val" "2k2")
    (property "ki_description" "2k2 resistor in 0402 package with 1% tolerance")
    (attr smd)
    (fp_text reference "R31" (at 1.07 3.64 180) (layer "F.SilkS")
        (effects (font (size 0.7 0.7) (thickness 0.15)) (justify left bottom))
    )
    (fp_text value "R_2k2_0402" (at 0 1.4 180) (layer "F.Fab") hide
        (effects (font (size 0.7 0.7) (thickness 0.15)) (justify left bottom))
    )
    (fp_text user "License: Apache-2.0" (at -0.95 5.169 180) (layer "F.Fab") hide
        (effects (font (size 0.7 0.7) (thickness 0.15)) (justify left bottom))
    )
    (fp_text user "${REFERENCE}" (at -0.95 3.168 180) (layer "F.Fab") hide
        (effects (font (size 0.7 0.7) (thickness 0.15)) (justify left bottom))
    )
    (fp_text user "Author: Antmicro" (at -0.95 4.169 180) (layer "F.Fab") hide
        (effects (font (size 0.7 0.7) (thickness 0.15)) (justify left bottom))
    )
    (fp_rect (start -0.93 -0.47) (end 0.93 0.47)
      (stroke (width 0.05) (type solid)) (fill none) (layer "F.CrtYd"))
    (fp_rect (start -0.5 -0.25) (end 0.5 0.25)
      (stroke (width 0.15) (type solid)) (fill none) (layer "F.Fab"))
    (pad "1" smd roundrect (at -0.485 0 180) (size 0.59 0.64) (layers "F.Cu" "F.Paste" "F.Mask") (roundrect_rratio 0.25)
      (net 20 "PL_3V3") (pintype "passive"))
    (pad "2" smd roundrect (at 0.485 0 180) (size 0.59 0.64) (layers "F.Cu" "F.Paste" "F.Mask") (roundrect_rratio 0.25)
      (net 196 "/Camera interface/CCI0_I2C_SDA_3V3") (pintype "passive"))
  )

  (footprint "kria-k26-devboard-footprints:R_0402_1005Metric" (layer "F.Cu")
    (at 84.05 93.25 180)
    (descr "Resistor SMD 0402")
    (tags "resistor SMD 0402")
    (property "Author" "Antmicro")
    (property "License" "Apache-2.0")
    (property "MPN" "CR0402-FX-2201GLF")
    (property "Manufacturer" "Bourns")
    (property "Sheetfile" "camera.kicad_sch")
    (property "Sheetname" "Camera interface")
    (property "Tolerance" "1%")
    (property "Val" "2k2")
    (property "ki_description" "2k2 resistor in 0402 package with 1% tolerance")
    (attr smd)
    (fp_text reference "R30" (at 1.07 3.64 180) (layer "F.SilkS")
        (effects (font (size 0.7 0.7) (thickness 0.15)) (justify left bottom))
    )
    (fp_text value "R_2k2_0402" (at 0 1.4 180) (layer "F.Fab") hide
        (effects (font (size 0.7 0.7) (thickness 0.15)) (justify left bottom))
    )
    (fp_text user "License: Apache-2.0" (at -0.95 5.169 180) (layer "F.Fab") hide
        (effects (font (size 0.7 0.7) (thickness 0.15)) (justify left bottom))
    )
    (fp_text user "Author: Antmicro" (at -0.95 4.169 180) (layer "F.Fab") hide
        (effects (font (size 0.7 0.7) (thickness 0.15)) (justify left bottom))
    )
    (fp_text user "${REFERENCE}" (at -0.95 3.168 180) (layer "F.Fab") hide
        (effects (font (size 0.7 0.7) (thickness 0.15)) (justify left bottom))
    )
    (fp_rect (start -0.93 -0.47) (end 0.93 0.47)
      (stroke (width 0.05) (type solid)) (fill none) (layer "F.CrtYd"))
    (fp_rect (start -0.5 -0.25) (end 0.5 0.25)
      (stroke (width 0.15) (type solid)) (fill none) (layer "F.Fab"))
    (pad "1" smd roundrect (at -0.485 0 180) (size 0.59 0.64) (layers "F.Cu" "F.Paste" "F.Mask") (roundrect_rratio 0.25)
      (net 20 "PL_3V3") (pintype "passive"))
    (pad "2" smd roundrect (at 0.485 0 180) (size 0.59 0.64) (layers "F.Cu" "F.Paste" "F.Mask") (roundrect_rratio 0.25)
      (net 193 "/Camera interface/CCI1_I2C_SCL_3V3") (pintype "passive"))
  )

  (footprint "kria-k26-devboard-footprints:R_0402_1005Metric" (layer "F.Cu")
    (at 84.046 95.25 180)
    (descr "Resistor SMD 0402")
    (tags "resistor SMD 0402")
    (property "Author" "Antmicro")
    (property "License" "Apache-2.0")
    (property "MPN" "CR0402-FX-2201GLF")
    (property "Manufacturer" "Bourns")
    (property "Sheetfile" "camera.kicad_sch")
    (property "Sheetname" "Camera interface")
    (property "Tolerance" "1%")
    (property "Val" "2k2")
    (property "ki_description" "2k2 resistor in 0402 package with 1% tolerance")
    (attr smd)
    (fp_text reference "R29" (at 1.07 3.64 180) (layer "F.SilkS")
        (effects (font (size 0.7 0.7) (thickness 0.15)) (justify left bottom))
    )
    (fp_text value "R_2k2_0402" (at 0 1.4 180) (layer "F.Fab") hide
        (effects (font (size 0.7 0.7) (thickness 0.15)) (justify left bottom))
    )
    (fp_text user "License: Apache-2.0" (at -0.95 5.169 180) (layer "F.Fab") hide
        (effects (font (size 0.7 0.7) (thickness 0.15)) (justify left bottom))
    )
    (fp_text user "${REFERENCE}" (at -0.95 3.168 180) (layer "F.Fab") hide
        (effects (font (size 0.7 0.7) (thickness 0.15)) (justify left bottom))
    )
    (fp_text user "Author: Antmicro" (at -0.95 4.169 180) (layer "F.Fab") hide
        (effects (font (size 0.7 0.7) (thickness 0.15)) (justify left bottom))
    )
    (fp_rect (start -0.93 -0.47) (end 0.93 0.47)
      (stroke (width 0.05) (type solid)) (fill none) (layer "F.CrtYd"))
    (fp_rect (start -0.5 -0.25) (end 0.5 0.25)
      (stroke (width 0.15) (type solid)) (fill none) (layer "F.Fab"))
    (pad "1" smd roundrect (at -0.485 0 180) (size 0.59 0.64) (layers "F.Cu" "F.Paste" "F.Mask") (roundrect_rratio 0.25)
      (net 20 "PL_3V3") (pintype "passive"))
    (pad "2" smd roundrect (at 0.485 0 180) (size 0.59 0.64) (layers "F.Cu" "F.Paste" "F.Mask") (roundrect_rratio 0.25)
      (net 195 "/Camera interface/CCI0_I2C_SCL_3V3") (pintype "passive"))
  )

  (footprint "kria-k26-devboard-footprints:TP_SMD_0.75mm" (layer "F.Cu")
    (at 81.6 95.2008)
    (property "Author" "Antmicro")
    (property "License" "Apache-2.0")
    (property "MPN" "")
    (property "Manufacturer" "")
    (property "Sheetfile" "camera.kicad_sch")
    (property "Sheetname" "Camera interface")
    (property "ki_description" "Test Point 0.75mm")
    (attr exclude_from_pos_files)
    (fp_text reference "TP4" (at -2.38 0.35) (layer "F.SilkS")
        (effects (font (size 0.7 0.7) (thickness 0.15)) (justify left bottom))
    )
    (fp_text value "TP_0.75mm_SMD" (at 0 1.2) (layer "F.Fab") hide
        (effects (font (size 0.7 0.7) (thickness 0.15)) (justify left bottom))
    )
    (fp_text user "${REFERENCE}" (at -0.4 2.7) (layer "F.Fab") hide
        (effects (font (size 0.7 0.7) (thickness 0.15)) (justify left bottom))
    )
    (fp_text user "License: Apache-2.0" (at -0.4 5.101) (layer "F.Fab") hide
        (effects (font (size 0.7 0.7) (thickness 0.15)) (justify left bottom))
    )
    (fp_text user "Author: Antmicro" (at -0.4 3.901) (layer "F.Fab") hide
        (effects (font (size 0.7 0.7) (thickness 0.15)) (justify left bottom))
    )
    (pad "1" smd circle (at 0 0) (size 0.75 0.75) (layers "F.Cu" "F.Mask")
      (net 195 "/Camera interface/CCI0_I2C_SCL_3V3") (pinfunction "1") (pintype "passive"))
  )

  (footprint "kria-k26-devboard-footprints:TP_SMD_0.75mm" (layer "F.Cu")
    (at 81.6 96.2)
    (property "Author" "Antmicro")
    (property "License" "Apache-2.0")
    (property "MPN" "")
    (property "Manufacturer" "")
    (property "Sheetfile" "camera.kicad_sch")
    (property "Sheetname" "Camera interface")
    (property "ki_description" "Test Point 0.75mm")
    (attr exclude_from_pos_files)
    (fp_text reference "TP5" (at -2.38 0.35) (layer "F.SilkS")
        (effects (font (size 0.7 0.7) (thickness 0.15)) (justify left bottom))
    )
    (fp_text value "TP_0.75mm_SMD" (at 0 1.2) (layer "F.Fab") hide
        (effects (font (size 0.7 0.7) (thickness 0.15)) (justify left bottom))
    )
    (fp_text user "Author: Antmicro" (at -0.4 3.901) (layer "F.Fab") hide
        (effects (font (size 0.7 0.7) (thickness 0.15)) (justify left bottom))
    )
    (fp_text user "License: Apache-2.0" (at -0.4 5.101) (layer "F.Fab") hide
        (effects (font (size 0.7 0.7) (thickness 0.15)) (justify left bottom))
    )
    (fp_text user "${REFERENCE}" (at -0.4 2.7) (layer "F.Fab") hide
        (effects (font (size 0.7 0.7) (thickness 0.15)) (justify left bottom))
    )
    (pad "1" smd circle (at 0 0) (size 0.75 0.75) (layers "F.Cu" "F.Mask")
      (net 196 "/Camera interface/CCI0_I2C_SDA_3V3") (pinfunction "1") (pintype "passive"))
  )

  (footprint "kria-k26-devboard-footprints:TP_SMD_0.75mm" (layer "F.Cu")
    (at 81.6 93.1)
    (property "Author" "Antmicro")
    (property "License" "Apache-2.0")
    (property "MPN" "")
    (property "Manufacturer" "")
    (property "Sheetfile" "camera.kicad_sch")
    (property "Sheetname" "Camera interface")
    (property "ki_description" "Test Point 0.75mm")
    (attr exclude_from_pos_files)
    (fp_text reference "TP6" (at -2.38 0.35) (layer "F.SilkS")
        (effects (font (size 0.7 0.7) (thickness 0.15)) (justify left bottom))
    )
    (fp_text value "TP_0.75mm_SMD" (at 0 1.2) (layer "F.Fab") hide
        (effects (font (size 0.7 0.7) (thickness 0.15)) (justify left bottom))
    )
    (fp_text user "Author: Antmicro" (at -0.4 3.901) (layer "F.Fab") hide
        (effects (font (size 0.7 0.7) (thickness 0.15)) (justify left bottom))
    )
    (fp_text user "${REFERENCE}" (at -0.4 2.7) (layer "F.Fab") hide
        (effects (font (size 0.7 0.7) (thickness 0.15)) (justify left bottom))
    )
    (fp_text user "License: Apache-2.0" (at -0.4 5.101) (layer "F.Fab") hide
        (effects (font (size 0.7 0.7) (thickness 0.15)) (justify left bottom))
    )
    (pad "1" smd circle (at 0 0) (size 0.75 0.75) (layers "F.Cu" "F.Mask")
      (net 193 "/Camera interface/CCI1_I2C_SCL_3V3") (pinfunction "1") (pintype "passive"))
  )

  (footprint "kria-k26-devboard-footprints:TP_SMD_0.75mm" (layer "F.Cu")
    (at 81.6 94.1)
    (property "Author" "Antmicro")
    (property "License" "Apache-2.0")
    (property "MPN" "")
    (property "Manufacturer" "")
    (property "Sheetfile" "camera.kicad_sch")
    (property "Sheetname" "Camera interface")
    (property "ki_description" "Test Point 0.75mm")
    (attr exclude_from_pos_files)
    (fp_text reference "TP7" (at -2.38 0.35) (layer "F.SilkS")
        (effects (font (size 0.7 0.7) (thickness 0.15)) (justify left bottom))
    )
    (fp_text value "TP_0.75mm_SMD" (at 0 1.2) (layer "F.Fab") hide
        (effects (font (size 0.7 0.7) (thickness 0.15)) (justify left bottom))
    )
    (fp_text user "${REFERENCE}" (at -0.4 2.7) (layer "F.Fab") hide
        (effects (font (size 0.7 0.7) (thickness 0.15)) (justify left bottom))
    )
    (fp_text user "Author: Antmicro" (at -0.4 3.901) (layer "F.Fab") hide
        (effects (font (size 0.7 0.7) (thickness 0.15)) (justify left bottom))
    )
    (fp_text user "License: Apache-2.0" (at -0.4 5.101) (layer "F.Fab") hide
        (effects (font (size 0.7 0.7) (thickness 0.15)) (justify left bottom))
    )
    (pad "1" smd circle (at 0 0) (size 0.75 0.75) (layers "F.Cu" "F.Mask")
      (net 194 "/Camera interface/CCI1_I2C_SDA_3V3") (pinfunction "1") (pintype "passive"))
  )

  (footprint "kria-k26-devboard-footprints:Conn_Plug_Samtec_ADM6_4x60_ADM6-60-01.5-L-4-2-A-TR" (layer "F.Cu")
    (at 91.5765 117.6215 -90)
    (property "Author" "Antmicro")
    (property "License" "Apache-2.0")
    (property "MPN" "ADM6-60-01.5-L-4-2-A-TR")
    (property "Manufacturer" "Samtec")
    (property "Sheetfile" "k26_som.kicad_sch")
    (property "Sheetname" "Xilinx K26 SOM")
    (property "ki_description" "Board to Board & Mezzanine Connectors 0.635 mm AcceleRate HD High-Density 4-Row Header 60P")
    (attr smd)
    (fp_text reference "J_SOM240_1" (at -13.8415 -3.7635 -90) (layer "F.SilkS")
        (effects (font (size 0.7 0.7) (thickness 0.15)) (justify left bottom))
    )
    (fp_text value "ADM6-60-01.5-L-4-2-A-TR" (at 0 3.7 -90) (layer "F.Fab") hide
        (effects (font (size 0.7 0.7) (thickness 0.15)) (justify left bottom))
    )
    (fp_text user "License: Apache-2.0" (at -21.66 7.5 -90) (layer "F.Fab") hide
        (effects (font (size 0.7 0.7) (thickness 0.15)) (justify left bottom))
    )
    (fp_text user "${REFERENCE}" (at -21.66 5.1 -90) (layer "F.Fab") hide
        (effects (font (size 0.7 0.7) (thickness 0.15)) (justify left bottom))
    )
    (fp_text user "Author: Antmicro" (at -21.66 6.3 -90) (layer "F.Fab") hide
        (effects (font (size 0.7 0.7) (thickness 0.15)) (justify left bottom))
    )
    (fp_line (start -21.5 -1.7) (end -20.6 -2.6)
      (stroke (width 0.15) (type solid)) (layer "F.SilkS"))
    (fp_line (start -21.5 2.592) (end -21.5 -1.7)
      (stroke (width 0.15) (type solid)) (layer "F.SilkS"))
    (fp_line (start -20.6 -2.6) (end 20.6 -2.6)
      (stroke (width 0.15) (type solid)) (layer "F.SilkS"))
    (fp_line (start 20.6 -2.6) (end 21.5 -1.7)
      (stroke (width 0.15) (type solid)) (layer "F.SilkS"))
    (fp_line (start 21.5 -1.7) (end 21.5 2.592)
      (stroke (width 0.15) (type solid)) (layer "F.SilkS"))
    (fp_line (start 21.5 2.592) (end -21.5 2.592)
      (stroke (width 0.15) (type solid)) (layer "F.SilkS"))
    (fp_circle (center 18.75 -2.9) (end 18.8 -2.9)
      (stroke (width 0.15) (type solid)) (fill solid) (layer "F.SilkS"))
    (fp_line (start -21.66 -1.92) (end -20.83 -2.75)
      (stroke (width 0.05) (type solid)) (layer "F.CrtYd"))
    (fp_line (start -21.66 2.74) (end -21.66 -1.92)
      (stroke (width 0.05) (type solid)) (layer "F.CrtYd"))
    (fp_line (start -20.83 -2.75) (end 20.82 -2.75)
      (stroke (width 0.05) (type solid)) (layer "F.CrtYd"))
    (fp_line (start 20.82 -2.75) (end 21.65 -1.92)
      (stroke (width 0.05) (type solid)) (layer "F.CrtYd"))
    (fp_line (start 21.65 -1.92) (end 21.65 2.74)
      (stroke (width 0.05) (type solid)) (layer "F.CrtYd"))
    (fp_line (start 21.65 2.74) (end -21.66 2.74)
      (stroke (width 0.05) (type solid)) (layer "F.CrtYd"))
    (fp_line (start -21.41 2.499) (end -21.4 -1.7)
      (stroke (width 0.15) (type solid)) (layer "F.Fab"))
    (fp_line (start -21.4 -1.7) (end -20.6 -2.5)
      (stroke (width 0.15) (type solid)) (layer "F.Fab"))
    (fp_line (start -20.6 -2.5) (end 20.6 -2.5)
      (stroke (width 0.15) (type solid)) (layer "F.Fab"))
    (fp_line (start 20.6 -2.5) (end 21.409 -1.7)
      (stroke (width 0.15) (type solid)) (layer "F.Fab"))
    (fp_line (start 21.409 -1.7) (end 21.409 2.499)
      (stroke (width 0.15) (type solid)) (layer "F.Fab"))
    (fp_line (start 21.409 2.499) (end -21.41 2.499)
      (stroke (width 0.15) (type solid)) (layer "F.Fab"))
    (pad "" np_thru_hole circle (at -20.136 -1.27 270) (size 0.95 0.95) (drill 0.95) (layers "*.Cu" "*.Mask"))
    (pad "" np_thru_hole circle (at 20.135 0 270) (size 0.95 0.95) (drill 0.95) (layers "*.Cu" "*.Mask"))
    (pad "A01" smd circle (at 18.732 -1.75 270) (size 0.356 0.356) (layers "F.Cu" "F.Paste" "F.Mask")
      (net 438 "/Xilinx K26 SOM/VCC_BATT") (pinfunction "A01") (pintype "passive"))
    (pad "A02" smd circle (at 18.097 -1.75 270) (size 0.356 0.356) (layers "F.Cu" "F.Paste" "F.Mask")
      (net 1 "GND") (pinfunction "A02") (pintype "passive"))
    (pad "A03" smd circle (at 17.462 -1.75 270) (size 0.356 0.356) (layers "F.Cu" "F.Paste" "F.Mask")
      (net 202 "/Camera interface/HPA06_P") (pinfunction "A03") (pintype "passive"))
    (pad "A04" smd circle (at 16.827 -1.75 270) (size 0.356 0.356) (layers "F.Cu" "F.Paste" "F.Mask")
      (net 203 "/Camera interface/HPA06_N") (pinfunction "A04") (pintype "passive"))
    (pad "A05" smd circle (at 16.192 -1.75 270) (size 0.356 0.356) (layers "F.Cu" "F.Paste" "F.Mask")
      (net 1 "GND") (pinfunction "A05") (pintype "passive"))
    (pad "A06" smd circle (at 15.557 -1.75 270) (size 0.356 0.356) (layers "F.Cu" "F.Paste" "F.Mask")
      (net 439 "/Xilinx K26 SOM/HPA06_CLK0_P") (pinfunction "A06") (pintype "passive"))
    (pad "A07" smd circle (at 14.922 -1.75 270) (size 0.356 0.356) (layers "F.Cu" "F.Paste" "F.Mask")
      (net 440 "/Xilinx K26 SOM/HPA06_CLK0_N") (pinfunction "A07") (pintype "passive"))
    (pad "A08" smd circle (at 14.287 -1.75 270) (size 0.356 0.356) (layers "F.Cu" "F.Paste" "F.Mask")
      (net 1 "GND") (pinfunction "A08") (pintype "passive"))
    (pad "A09" smd circle (at 13.652 -1.75 270) (size 0.356 0.356) (layers "F.Cu" "F.Paste" "F.Mask")
      (net 441 "/Xilinx K26 SOM/HPA12_P") (pinfunction "A09") (pintype "passive"))
    (pad "A10" smd circle (at 13.017 -1.75 270) (size 0.356 0.356) (layers "F.Cu" "F.Paste" "F.Mask")
      (net 442 "/Xilinx K26 SOM/HPA12_N") (pinfunction "A10") (pintype "passive"))
    (pad "A11" smd circle (at 12.382 -1.75 270) (size 0.356 0.356) (layers "F.Cu" "F.Paste" "F.Mask")
      (net 1 "GND") (pinfunction "A11") (pintype "passive"))
    (pad "A12" smd circle (at 11.747 -1.75 270) (size 0.356 0.356) (layers "F.Cu" "F.Paste" "F.Mask")
      (net 443 "/Xilinx K26 SOM/HPA13_P") (pinfunction "A12") (pintype "passive"))
    (pad "A13" smd circle (at 11.112 -1.75 270) (size 0.356 0.356) (layers "F.Cu" "F.Paste" "F.Mask")
      (net 444 "/Xilinx K26 SOM/HPA13_N") (pinfunction "A13") (pintype "passive"))
    (pad "A14" smd circle (at 10.477 -1.75 270) (size 0.356 0.356) (layers "F.Cu" "F.Paste" "F.Mask")
      (net 1 "GND") (pinfunction "A14") (pintype "passive"))
    (pad "A15" smd circle (at 9.842 -1.75 270) (size 0.356 0.356) (layers "F.Cu" "F.Paste" "F.Mask")
      (net 197 "/Camera interface/CAM1_VSYNC") (pinfunction "A15") (pintype "passive"))
    (pad "A16" smd circle (at 9.207 -1.75 270) (size 0.356 0.356) (layers "F.Cu" "F.Paste" "F.Mask")
      (net 445 "/Xilinx K26 SOM/HDA10") (pinfunction "A16") (pintype "passive"))
    (pad "A17" smd circle (at 8.572 -1.75 270) (size 0.356 0.356) (layers "F.Cu" "F.Paste" "F.Mask")
      (net 144 "/PMOD/HDA11") (pinfunction "A17") (pintype "passive"))
    (pad "A18" smd circle (at 7.937 -1.75 270) (size 0.356 0.356) (layers "F.Cu" "F.Paste" "F.Mask")
      (net 1 "GND") (pinfunction "A18") (pintype "passive"))
    (pad "A19" smd circle (at 7.302 -1.75 270) (size 0.356 0.356) (layers "F.Cu" "F.Paste" "F.Mask")
      (net 23 "/Power Supply/VCCOEN_PS_M2C") (pinfunction "A19") (pintype "passive"))
    (pad "A20" smd circle (at 6.667 -1.75 270) (size 0.356 0.356) (layers "F.Cu" "F.Paste" "F.Mask")
      (net 24 "/Power Supply/VCCOEN_PL_M2C") (pinfunction "A20") (pintype "passive"))
    (pad "A21" smd circle (at 6.032 -1.75 270) (size 0.356 0.356) (layers "F.Cu" "F.Paste" "F.Mask")
      (net 1 "GND") (pinfunction "A21") (pintype "passive"))
    (pad "A22" smd circle (at 5.397 -1.75 270) (size 0.356 0.356) (layers "F.Cu" "F.Paste" "F.Mask")
      (net 145 "/Debug and JTAG/JTAG_TMS_C2M") (pinfunction "A22") (pintype "passive"))
    (pad "A23" smd circle (at 4.762 -1.75 270) (size 0.356 0.356) (layers "F.Cu" "F.Paste" "F.Mask")
      (net 142 "/Debug and JTAG/JTAG_TDO_M2C") (pinfunction "A23") (pintype "passive"))
    (pad "A24" smd circle (at 4.127 -1.75 270) (size 0.356 0.356) (layers "F.Cu" "F.Paste" "F.Mask")
      (net 141 "/Debug and JTAG/JTAG_TDI_C2M") (pinfunction "A24") (pintype "passive"))
    (pad "A25" smd circle (at 3.492 -1.75 270) (size 0.356 0.356) (layers "F.Cu" "F.Paste" "F.Mask")
      (net 143 "/Debug and JTAG/JTAG_TCK_C2M") (pinfunction "A25") (pintype "passive"))
    (pad "A26" smd circle (at 2.857 -1.75 270) (size 0.356 0.356) (layers "F.Cu" "F.Paste" "F.Mask")
      (net 1 "GND") (pinfunction "A26") (pintype "passive"))
    (pad "A27" smd circle (at 2.222 -1.75 270) (size 0.356 0.356) (layers "F.Cu" "F.Paste" "F.Mask")
      (net 2 "/Xilinx K26 SOM/MODE0_C2M") (pinfunction "A27") (pintype "passive"))
    (pad "A28" smd circle (at 1.587 -1.75 270) (size 0.356 0.356) (layers "F.Cu" "F.Paste" "F.Mask")
      (net 3 "/Xilinx K26 SOM/MODE1_C2M") (pinfunction "A28") (pintype "passive"))
    (pad "A29" smd circle (at 0.952 -1.75 270) (size 0.356 0.356) (layers "F.Cu" "F.Paste" "F.Mask")
      (net 4 "/Xilinx K26 SOM/MODE2_C2M") (pinfunction "A29") (pintype "passive"))
    (pad "A30" smd circle (at 0.317 -1.75 270) (size 0.356 0.356) (layers "F.Cu" "F.Paste" "F.Mask")
      (net 5 "/Xilinx K26 SOM/MODE3_C2M") (pinfunction "A30") (pintype "passive"))
    (pad "A31" smd circle (at -0.318 -1.75 270) (size 0.356 0.356) (layers "F.Cu" "F.Paste" "F.Mask")
      (net 446 "unconnected-(J_SOM240_1-PadA31)") (pinfunction "A31") (pintype "passive+no_connect"))
    (pad "A32" smd circle (at -0.953 -1.75 270) (size 0.356 0.356) (layers "F.Cu" "F.Paste" "F.Mask")
      (net 447 "unconnected-(J_SOM240_1-PadA32)") (pinfunction "A32") (pintype "passive+no_connect"))
    (pad "A33" smd circle (at -1.588 -1.75 270) (size 0.356 0.356) (layers "F.Cu" "F.Paste" "F.Mask")
      (net 1 "GND") (pinfunction "A33") (pintype "passive"))
    (pad "A34" smd circle (at -2.223 -1.75 270) (size 0.356 0.356) (layers "F.Cu" "F.Paste" "F.Mask")
      (net 224 "/Reset logic/MIO41") (pinfunction "A34") (pintype "passive"))
    (pad "A35" smd circle (at -2.858 -1.75 270) (size 0.356 0.356) (layers "F.Cu" "F.Paste" "F.Mask")
      (net 448 "/Xilinx K26 SOM/MIO42") (pinfunction "A35") (pintype "passive"))
    (pad "A36" smd circle (at -3.493 -1.75 270) (size 0.356 0.356) (layers "F.Cu" "F.Paste" "F.Mask")
      (net 127 "/Reset logic/MIO43") (pinfunction "A36") (pintype "passive"))
    (pad "A37" smd circle (at -4.128 -1.75 270) (size 0.356 0.356) (layers "F.Cu" "F.Paste" "F.Mask")
      (net 1 "GND") (pinfunction "A37") (pintype "passive"))
    (pad "A38" smd circle (at -4.763 -1.75 270) (size 0.356 0.356) (layers "F.Cu" "F.Paste" "F.Mask")
      (net 37 "/USB/MIO61") (pinfunction "A38") (pintype "passive"))
    (pad "A39" smd circle (at -5.398 -1.75 270) (size 0.356 0.356) (layers "F.Cu" "F.Paste" "F.Mask")
      (net 38 "/USB/MIO62") (pinfunction "A39") (pintype "passive"))
    (pad "A40" smd circle (at -6.033 -1.75 270) (size 0.356 0.356) (layers "F.Cu" "F.Paste" "F.Mask")
      (net 39 "/USB/MIO63") (pinfunction "A40") (pintype "passive"))
    (pad "A41" smd circle (at -6.668 -1.75 270) (size 0.356 0.356) (layers "F.Cu" "F.Paste" "F.Mask")
      (net 1 "GND") (pinfunction "A41") (pintype "passive"))
    (pad "A42" smd circle (at -7.303 -1.75 270) (size 0.356 0.356) (layers "F.Cu" "F.Paste" "F.Mask")
      (net 26 "/Ethernet/MIO73") (pinfunction "A42") (pintype "passive"))
    (pad "A43" smd circle (at -7.938 -1.75 270) (size 0.356 0.356) (layers "F.Cu" "F.Paste" "F.Mask")
      (net 27 "/Ethernet/MIO74") (pinfunction "A43") (pintype "passive"))
    (pad "A44" smd circle (at -8.573 -1.75 270) (size 0.356 0.356) (layers "F.Cu" "F.Paste" "F.Mask")
      (net 28 "/Ethernet/MIO75") (pinfunction "A44") (pintype "passive"))
    (pad "A45" smd circle (at -9.208 -1.75 270) (size 0.356 0.356) (layers "F.Cu" "F.Paste" "F.Mask")
      (net 1 "GND") (pinfunction "A45") (pintype "passive"))
    (pad "A46" smd circle (at -9.843 -1.75 270) (size 0.356 0.356) (layers "F.Cu" "F.Paste" "F.Mask")
      (net 1 "GND") (pinfunction "A46") (pintype "passive"))
    (pad "A47" smd circle (at -10.478 -1.75 270) (size 0.356 0.356) (layers "F.Cu" "F.Paste" "F.Mask")
      (net 92 "/Display Port/GTR_DP1_M2C_P") (pinfunction "A47") (pintype "passive"))
    (pad "A48" smd circle (at -11.113 -1.75 270) (size 0.356 0.356) (layers "F.Cu" "F.Paste" "F.Mask")
      (net 94 "/Display Port/GTR_DP1_M2C_N") (pinfunction "A48") (pintype "passive"))
    (pad "A49" smd circle (at -11.748 -1.75 270) (size 0.356 0.356) (layers "F.Cu" "F.Paste" "F.Mask")
      (net 1 "GND") (pinfunction "A49") (pintype "passive"))
    (pad "A50" smd circle (at -12.383 -1.75 270) (size 0.356 0.356) (layers "F.Cu" "F.Paste" "F.Mask")
      (net 1 "GND") (pinfunction "A50") (pintype "passive"))
    (pad "A51" smd circle (at -13.018 -1.75 270) (size 0.356 0.356) (layers "F.Cu" "F.Paste" "F.Mask")
      (net 107 "/Clock distribution/GTR_REFCLK3_C2M_P") (pinfunction "A51") (pintype "passive"))
    (pad "A52" smd circle (at -13.653 -1.75 270) (size 0.356 0.356) (layers "F.Cu" "F.Paste" "F.Mask")
      (net 108 "/Clock distribution/GTR_REFCLK3_C2M_N") (pinfunction "A52") (pintype "passive"))
    (pad "A53" smd circle (at -14.288 -1.75 270) (size 0.356 0.356) (layers "F.Cu" "F.Paste" "F.Mask")
      (net 1 "GND") (pinfunction "A53") (pintype "passive"))
    (pad "A54" smd circle (at -14.923 -1.75 270) (size 0.356 0.356) (layers "F.Cu" "F.Paste" "F.Mask")
      (net 1 "GND") (pinfunction "A54") (pintype "passive"))
    (pad "A55" smd circle (at -15.558 -1.75 270) (size 0.356 0.356) (layers "F.Cu" "F.Paste" "F.Mask")
      (net 449 "/Xilinx K26 SOM/GTR_DP0_C2M_P") (pinfunction "A55") (pintype "passive"))
    (pad "A56" smd circle (at -16.193 -1.75 270) (size 0.356 0.356) (layers "F.Cu" "F.Paste" "F.Mask")
      (net 450 "/Xilinx K26 SOM/GTR_DP0_C2M_N") (pinfunction "A56") (pintype "passive"))
    (pad "A57" smd circle (at -16.828 -1.75 270) (size 0.356 0.356) (layers "F.Cu" "F.Paste" "F.Mask")
      (net 1 "GND") (pinfunction "A57") (pintype "passive"))
    (pad "A58" smd circle (at -17.463 -1.75 270) (size 0.356 0.356) (layers "F.Cu" "F.Paste" "F.Mask")
      (net 1 "GND") (pinfunction "A58") (pintype "passive"))
    (pad "A59" smd circle (at -18.098 -1.75 270) (size 0.356 0.356) (layers "F.Cu" "F.Paste" "F.Mask")
      (net 8 "SOM_5V0") (pinfunction "A59") (pintype "passive"))
    (pad "A60" smd circle (at -18.733 -1.75 270) (size 0.356 0.356) (layers "F.Cu" "F.Paste" "F.Mask")
      (net 8 "SOM_5V0") (pinfunction "A60") (pintype "passive"))
    (pad "B01" smd circle (at 18.732 -0.791 270) (size 0.356 0.356) (layers "F.Cu" "F.Paste" "F.Mask")
      (net 200 "/Camera interface/HPA05_CC_P") (pinfunction "B01") (pintype "passive"))
    (pad "B02" smd circle (at 18.097 -0.791 270) (size 0.356 0.356) (layers "F.Cu" "F.Paste" "F.Mask")
      (net 201 "/Camera interface/HPA05_CC_N") (pinfunction "B02") (pintype "passive"))
    (pad "B03" smd circle (at 17.462 -0.791 270) (size 0.356 0.356) (layers "F.Cu" "F.Paste" "F.Mask")
      (net 1 "GND") (pinfunction "B03") (pintype "passive"))
    (pad "B04" smd circle (at 16.827 -0.791 270) (size 0.356 0.356) (layers "F.Cu" "F.Paste" "F.Mask")
      (net 218 "/Camera interface/HPA04_P") (pinfunction "B04") (pintype "passive"))
    (pad "B05" smd circle (at 16.192 -0.791 270) (size 0.356 0.356) (layers "F.Cu" "F.Paste" "F.Mask")
      (net 219 "/Camera interface/HPA04_N") (pinfunction "B05") (pintype "passive"))
    (pad "B06" smd circle (at 15.557 -0.791 270) (size 0.356 0.356) (layers "F.Cu" "F.Paste" "F.Mask")
      (net 1 "GND") (pinfunction "B06") (pintype "passive"))
    (pad "B07" smd circle (at 14.922 -0.791 270) (size 0.356 0.356) (layers "F.Cu" "F.Paste" "F.Mask")
      (net 204 "/Camera interface/HPA07_P") (pinfunction "B07") (pintype "passive"))
    (pad "B08" smd circle (at 14.287 -0.791 270) (size 0.356 0.356) (layers "F.Cu" "F.Paste" "F.Mask")
      (net 205 "/Camera interface/HPA07_N") (pinfunction "B08") (pintype "passive"))
    (pad "B09" smd circle (at 13.652 -0.791 270) (size 0.356 0.356) (layers "F.Cu" "F.Paste" "F.Mask")
      (net 1 "GND") (pinfunction "B09") (pintype "passive"))
    (pad "B10" smd circle (at 13.017 -0.791 270) (size 0.356 0.356) (layers "F.Cu" "F.Paste" "F.Mask")
      (net 451 "/Xilinx K26 SOM/HPA11_P") (pinfunction "B10") (pintype "passive"))
    (pad "B11" smd circle (at 12.382 -0.791 270) (size 0.356 0.356) (layers "F.Cu" "F.Paste" "F.Mask")
      (net 452 "/Xilinx K26 SOM/HPA11_N") (pinfunction "B11") (pintype "passive"))
    (pad "B12" smd circle (at 11.747 -0.791 270) (size 0.356 0.356) (layers "F.Cu" "F.Paste" "F.Mask")
      (net 1 "GND") (pinfunction "B12") (pintype "passive"))
    (pad "B13" smd circle (at 11.112 -0.791 270) (size 0.356 0.356) (layers "F.Cu" "F.Paste" "F.Mask")
      (net 20 "PL_3V3") (pinfunction "B13") (pintype "passive"))
    (pad "B14" smd circle (at 10.477 -0.791 270) (size 0.356 0.356) (layers "F.Cu" "F.Paste" "F.Mask")
      (net 20 "PL_3V3") (pinfunction "B14") (pintype "passive"))
    (pad "B15" smd circle (at 9.842 -0.791 270) (size 0.356 0.356) (layers "F.Cu" "F.Paste" "F.Mask")
      (net 1 "GND") (pinfunction "B15") (pintype "passive"))
    (pad "B16" smd circle (at 9.207 -0.791 270) (size 0.356 0.356) (layers "F.Cu" "F.Paste" "F.Mask")
      (net 453 "/Xilinx K26 SOM/HDA03") (pinfunction "B16") (pintype "passive"))
    (pad "B17" smd circle (at 8.572 -0.791 270) (size 0.356 0.356) (layers "F.Cu" "F.Paste" "F.Mask")
      (net 199 "/Camera interface/CAM0_VSYNC") (pinfunction "B17") (pintype "passive"))
    (pad "B18" smd circle (at 7.937 -0.791 270) (size 0.356 0.356) (layers "F.Cu" "F.Paste" "F.Mask")
      (net 454 "/Xilinx K26 SOM/HDA05") (pinfunction "B18") (pintype "passive"))
    (pad "B19" smd circle (at 7.302 -0.791 270) (size 0.356 0.356) (layers "F.Cu" "F.Paste" "F.Mask")
      (net 1 "GND") (pinfunction "B19") (pintype "passive"))
    (pad "B20" smd circle (at 6.667 -0.791 270) (size 0.356 0.356) (layers "F.Cu" "F.Paste" "F.Mask")
      (net 146 "/PMOD/HDA15") (pinfunction "B20") (pintype "passive"))
    (pad "B21" smd circle (at 6.032 -0.791 270) (size 0.356 0.356) (layers "F.Cu" "F.Paste" "F.Mask")
      (net 147 "/PMOD/HDA16_CC") (pinfunction "B21") (pintype "passive"))
    (pad "B22" smd circle (at 5.397 -0.791 270) (size 0.356 0.356) (layers "F.Cu" "F.Paste" "F.Mask")
      (net 148 "/PMOD/HDA17") (pinfunction "B22") (pintype "passive"))
    (pad "B23" smd circle (at 4.762 -0.791 270) (size 0.356 0.356) (layers "F.Cu" "F.Paste" "F.Mask")
      (net 1 "GND") (pinfunction "B23") (pintype "passive"))
    (pad "B24" smd circle (at 4.127 -0.791 270) (size 0.356 0.356) (layers "F.Cu" "F.Paste" "F.Mask")
      (net 455 "/Xilinx K26 SOM/PS_ERROR_OUT_M2C") (pinfunction "B24") (pintype "passive"))
    (pad "B25" smd circle (at 3.492 -0.791 270) (size 0.356 0.356) (layers "F.Cu" "F.Paste" "F.Mask")
      (net 456 "/Xilinx K26 SOM/PS_ERROR_STATUS_M2C") (pinfunction "B25") (pintype "passive"))
    (pad "B26" smd circle (at 2.857 -0.791 270) (size 0.356 0.356) (layers "F.Cu" "F.Paste" "F.Mask")
      (net 457 "/Xilinx K26 SOM/PWROFF_C2M_L") (pinfunction "B26") (pintype "passive"))
    (pad "B27" smd circle (at 2.222 -0.791 270) (size 0.356 0.356) (layers "F.Cu" "F.Paste" "F.Mask")
      (net 1 "GND") (pinfunction "B27") (pintype "passive"))
    (pad "B28" smd circle (at 1.587 -0.791 270) (size 0.356 0.356) (layers "F.Cu" "F.Paste" "F.Mask")
      (net 458 "/Xilinx K26 SOM/MIO35_WD_OUT") (pinfunction "B28") (pintype "passive"))
    (pad "B29" smd circle (at 0.952 -0.791 270) (size 0.356 0.356) (layers "F.Cu" "F.Paste" "F.Mask")
      (net 149 "/Debug and JTAG/MIO36") (pinfunction "B29") (pintype "passive"))
    (pad "B30" smd circle (at 0.317 -0.791 270) (size 0.356 0.356) (layers "F.Cu" "F.Paste" "F.Mask")
      (net 150 "/Debug and JTAG/MIO37") (pinfunction "B30") (pintype "passive"))
    (pad "B31" smd circle (at -0.318 -0.791 270) (size 0.356 0.356) (layers "F.Cu" "F.Paste" "F.Mask")
      (net 1 "GND") (pinfunction "B31") (pintype "passive"))
    (pad "B32" smd circle (at -0.953 -0.791 270) (size 0.356 0.356) (layers "F.Cu" "F.Paste" "F.Mask")
      (net 128 "/Reset logic/MIO38") (pinfunction "B32") (pintype "passive"))
    (pad "B33" smd circle (at -1.588 -0.791 270) (size 0.356 0.356) (layers "F.Cu" "F.Paste" "F.Mask")
      (net 109 "/SD 3.0 card/MIO39") (pinfunction "B33") (pintype "passive"))
    (pad "B34" smd circle (at -2.223 -0.791 270) (size 0.356 0.356) (layers "F.Cu" "F.Paste" "F.Mask")
      (net 459 "/Xilinx K26 SOM/MIO40") (pinfunction "B34") (pintype "passive"))
    (pad "B35" smd circle (at -2.858 -0.791 270) (size 0.356 0.356) (layers "F.Cu" "F.Paste" "F.Mask")
      (net 1 "GND") (pinfunction "B35") (pintype "passive"))
    (pad "B36" smd circle (at -3.493 -0.791 270) (size 0.356 0.356) (layers "F.Cu" "F.Paste" "F.Mask")
      (net 110 "/SD 3.0 card/MIO50") (pinfunction "B36") (pintype "passive"))
    (pad "B37" smd circle (at -4.128 -0.791 270) (size 0.356 0.356) (layers "F.Cu" "F.Paste" "F.Mask")
      (net 123 "/SD 3.0 card/MIO51") (pinfunction "B37") (pintype "passive"))
    (pad "B38" smd circle (at -4.763 -0.791 270) (size 0.356 0.356) (layers "F.Cu" "F.Paste" "F.Mask")
      (net 460 "unconnected-(J_SOM240_1-PadB38)") (pinfunction "B38") (pintype "passive+no_connect"))
    (pad "B39" smd circle (at -5.398 -0.791 270) (size 0.356 0.356) (layers "F.Cu" "F.Paste" "F.Mask")
      (net 1 "GND") (pinfunction "B39") (pintype "passive"))
    (pad "B40" smd circle (at -6.033 -0.791 270) (size 0.356 0.356) (layers "F.Cu" "F.Paste" "F.Mask")
      (net 40 "/USB/MIO58") (pinfunction "B40") (pintype "passive"))
    (pad "B41" smd circle (at -6.668 -0.791 270) (size 0.356 0.356) (layers "F.Cu" "F.Paste" "F.Mask")
      (net 41 "/USB/MIO59") (pinfunction "B41") (pintype "passive"))
    (pad "B42" smd circle (at -7.303 -0.791 270) (size 0.356 0.356) (layers "F.Cu" "F.Paste" "F.Mask")
      (net 42 "/USB/MIO60") (pinfunction "B42") (pintype "passive"))
    (pad "B43" smd circle (at -7.938 -0.791 270) (size 0.356 0.356) (layers "F.Cu" "F.Paste" "F.Mask")
      (net 1 "GND") (pinfunction "B43") (pintype "passive"))
    (pad "B44" smd circle (at -8.573 -0.791 270) (size 0.356 0.356) (layers "F.Cu" "F.Paste" "F.Mask")
      (net 29 "/Ethernet/MIO70") (pinfunction "B44") (pintype "passive"))
    (pad "B45" smd circle (at -9.208 -0.791 270) (size 0.356 0.356) (layers "F.Cu" "F.Paste" "F.Mask")
      (net 30 "/Ethernet/MIO71") (pinfunction "B45") (pintype "passive"))
    (pad "B46" smd circle (at -9.843 -0.791 270) (size 0.356 0.356) (layers "F.Cu" "F.Paste" "F.Mask")
      (net 31 "/Ethernet/MIO72") (pinfunction "B46") (pintype "passive"))
    (pad "B47" smd circle (at -10.478 -0.791 270) (size 0.356 0.356) (layers "F.Cu" "F.Paste" "F.Mask")
      (net 1 "GND") (pinfunction "B47") (pintype "passive"))
    (pad "B48" smd circle (at -11.113 -0.791 270) (size 0.356 0.356) (layers "F.Cu" "F.Paste" "F.Mask")
      (net 1 "GND") (pinfunction "B48") (pintype "passive"))
    (pad "B49" smd circle (at -11.748 -0.791 270) (size 0.356 0.356) (layers "F.Cu" "F.Paste" "F.Mask")
      (net 179 "/Clock distribution/GTR_REFCLK1_C2M_P") (pinfunction "B49") (pintype "passive"))
    (pad "B50" smd circle (at -12.383 -0.791 270) (size 0.356 0.356) (layers "F.Cu" "F.Paste" "F.Mask")
      (net 180 "/Clock distribution/GTR_REFCLK1_C2M_N") (pinfunction "B50") (pintype "passive"))
    (pad "B51" smd circle (at -13.018 -0.791 270) (size 0.356 0.356) (layers "F.Cu" "F.Paste" "F.Mask")
      (net 1 "GND") (pinfunction "B51") (pintype "passive"))
    (pad "B52" smd circle (at -13.653 -0.791 270) (size 0.356 0.356) (layers "F.Cu" "F.Paste" "F.Mask")
      (net 1 "GND") (pinfunction "B52") (pintype "passive"))
    (pad "B53" smd circle (at -14.288 -0.791 270) (size 0.356 0.356) (layers "F.Cu" "F.Paste" "F.Mask")
      (net 56 "/USB/GTR_DP2_C2M_P") (pinfunction "B53") (pintype "passive"))
    (pad "B54" smd circle (at -14.923 -0.791 270) (size 0.356 0.356) (layers "F.Cu" "F.Paste" "F.Mask")
      (net 57 "/USB/GTR_DP2_C2M_N") (pinfunction "B54") (pintype "passive"))
    (pad "B55" smd circle (at -15.558 -0.791 270) (size 0.356 0.356) (layers "F.Cu" "F.Paste" "F.Mask")
      (net 1 "GND") (pinfunction "B55") (pintype "passive"))
    (pad "B56" smd circle (at -16.193 -0.791 270) (size 0.356 0.356) (layers "F.Cu" "F.Paste" "F.Mask")
      (net 1 "GND") (pinfunction "B56") (pintype "passive"))
    (pad "B57" smd circle (at -16.828 -0.791 270) (size 0.356 0.356) (layers "F.Cu" "F.Paste" "F.Mask")
      (net 100 "/Display Port/GTR_DP0_M2C_P") (pinfunction "B57") (pintype "passive"))
    (pad "B58" smd circle (at -17.463 -0.791 270) (size 0.356 0.356) (layers "F.Cu" "F.Paste" "F.Mask")
      (net 102 "/Display Port/GTR_DP0_M2C_N") (pinfunction "B58") (pintype "passive"))
    (pad "B59" smd circle (at -18.098 -0.791 270) (size 0.356 0.356) (layers "F.Cu" "F.Paste" "F.Mask")
      (net 1 "GND") (pinfunction "B59") (pintype "passive"))
    (pad "B60" smd circle (at -18.733 -0.791 270) (size 0.356 0.356) (layers "F.Cu" "F.Paste" "F.Mask")
      (net 8 "SOM_5V0") (pinfunction "B60") (pintype "passive"))
    (pad "C01" smd circle (at 18.732 0.79 270) (size 0.356 0.356) (layers "F.Cu" "F.Paste" "F.Mask")
      (net 1 "GND") (pinfunction "C01") (pintype "passive"))
    (pad "C02" smd circle (at 18.097 0.79 270) (size 0.356 0.356) (layers "F.Cu" "F.Paste" "F.Mask")
      (net 1 "GND") (pinfunction "C02") (pintype "passive"))
    (pad "C03" smd circle (at 17.462 0.79 270) (size 0.356 0.356) (layers "F.Cu" "F.Paste" "F.Mask")
      (net 210 "/Camera interface/HPA00_CC_P") (pinfunction "C03") (pintype "passive"))
    (pad "C04" smd circle (at 16.827 0.79 270) (size 0.356 0.356) (layers "F.Cu" "F.Paste" "F.Mask")
      (net 211 "/Camera interface/HPA00_CC_N") (pinfunction "C04") (pintype "passive"))
    (pad "C05" smd circle (at 16.192 0.79 270) (size 0.356 0.356) (layers "F.Cu" "F.Paste" "F.Mask")
      (net 1 "GND") (pinfunction "C05") (pintype "passive"))
    (pad "C06" smd circle (at 15.557 0.79 270) (size 0.356 0.356) (layers "F.Cu" "F.Paste" "F.Mask")
      (net 216 "/Camera interface/HPA03_P") (pinfunction "C06") (pintype "passive"))
    (pad "C07" smd circle (at 14.922 0.79 270) (size 0.356 0.356) (layers "F.Cu" "F.Paste" "F.Mask")
      (net 217 "/Camera interface/HPA03_N") (pinfunction "C07") (pintype "passive"))
    (pad "C08" smd circle (at 14.287 0.79 270) (size 0.356 0.356) (layers "F.Cu" "F.Paste" "F.Mask")
      (net 1 "GND") (pinfunction "C08") (pintype "passive"))
    (pad "C09" smd circle (at 13.652 0.79 270) (size 0.356 0.356) (layers "F.Cu" "F.Paste" "F.Mask")
      (net 206 "/Camera interface/HPA08_P") (pinfunction "C09") (pintype "passive"))
    (pad "C10" smd circle (at 13.017 0.79 270) (size 0.356 0.356) (layers "F.Cu" "F.Paste" "F.Mask")
      (net 207 "/Camera interface/HPA08_N") (pinfunction "C10") (pintype "passive"))
    (pad "C11" smd circle (at 12.382 0.79 270) (size 0.356 0.356) (layers "F.Cu" "F.Paste" "F.Mask")
      (net 1 "GND") (pinfunction "C11") (pintype "passive"))
    (pad "C12" smd circle (at 11.747 0.79 270) (size 0.356 0.356) (layers "F.Cu" "F.Paste" "F.Mask")
      (net 461 "/Xilinx K26 SOM/HPA10_CC_P") (pinfunction "C12") (pintype "passive"))
    (pad "C13" smd circle (at 11.112 0.79 270) (size 0.356 0.356) (layers "F.Cu" "F.Paste" "F.Mask")
      (net 462 "/Xilinx K26 SOM/HPA10_CC_N") (pinfunction "C13") (pintype "passive"))
    (pad "C14" smd circle (at 10.477 0.79 270) (size 0.356 0.356) (layers "F.Cu" "F.Paste" "F.Mask")
      (net 1 "GND") (pinfunction "C14") (pintype "passive"))
    (pad "C15" smd circle (at 9.842 0.79 270) (size 0.356 0.356) (layers "F.Cu" "F.Paste" "F.Mask")
      (net 151 "/Debug and JTAG/~{PS_POR}") (pinfunction "C15") (pintype "passive"))
    (pad "C16" smd circle (at 9.207 0.79 270) (size 0.356 0.356) (layers "F.Cu" "F.Paste" "F.Mask")
      (net 140 "/Debug and JTAG/~{PS_SRST_C2M}") (pinfunction "C16") (pintype "passive"))
    (pad "C17" smd circle (at 8.572 0.79 270) (size 0.356 0.356) (layers "F.Cu" "F.Paste" "F.Mask")
      (net 1 "GND") (pinfunction "C17") (pintype "passive"))
    (pad "C18" smd circle (at 7.937 0.79 270) (size 0.356 0.356) (layers "F.Cu" "F.Paste" "F.Mask")
      (net 463 "/Xilinx K26 SOM/HDA06") (pinfunction "C18") (pintype "passive"))
    (pad "C19" smd circle (at 7.302 0.79 270) (size 0.356 0.356) (layers "F.Cu" "F.Paste" "F.Mask")
      (net 464 "/Xilinx K26 SOM/HDA07") (pinfunction "C19") (pintype "passive"))
    (pad "C20" smd circle (at 6.667 0.79 270) (size 0.356 0.356) (layers "F.Cu" "F.Paste" "F.Mask")
      (net 465 "/Xilinx K26 SOM/HDA08_CC") (pinfunction "C20") (pintype "passive"))
    (pad "C21" smd circle (at 6.032 0.79 270) (size 0.356 0.356) (layers "F.Cu" "F.Paste" "F.Mask")
      (net 1 "GND") (pinfunction "C21") (pintype "passive"))
    (pad "C22" smd circle (at 5.397 0.79 270) (size 0.356 0.356) (layers "F.Cu" "F.Paste" "F.Mask")
      (net 152 "/PMOD/HDA18") (pinfunction "C22") (pintype "passive"))
    (pad "C23" smd circle (at 4.762 0.79 270) (size 0.356 0.356) (layers "F.Cu" "F.Paste" "F.Mask")
      (net 466 "/Xilinx K26 SOM/HDA19") (pinfunction "C23") (pintype "passive"))
    (pad "C24" smd circle (at 4.127 0.79 270) (size 0.356 0.356) (layers "F.Cu" "F.Paste" "F.Mask")
      (net 6 "/Xilinx K26 SOM/HDA20") (pinfunction "C24") (pintype "passive"))
    (pad "C25" smd circle (at 3.492 0.79 270) (size 0.356 0.356) (layers "F.Cu" "F.Paste" "F.Mask")
      (net 1 "GND") (pinfunction "C25") (pintype "passive"))
    (pad "C26" smd circle (at 2.857 0.79 270) (size 0.356 0.356) (layers "F.Cu" "F.Paste" "F.Mask")
      (net 153 "/I2C /MIO24_I2C_SCK") (pinfunction "C26") (pintype "passive"))
    (pad "C27" smd circle (at 2.222 0.79 270) (size 0.356 0.356) (layers "F.Cu" "F.Paste" "F.Mask")
      (net 432 "/I2C /MIO25_I2C_SDA") (pinfunction "C27") (pintype "passive"))
    (pad "C28" smd circle (at 1.587 0.79 270) (size 0.356 0.356) (layers "F.Cu" "F.Paste" "F.Mask")
      (net 467 "/Xilinx K26 SOM/MIO12_FWUEN_C2M_L") (pinfunction "C28") (pintype "passive"))
    (pad "C29" smd circle (at 0.952 0.79 270) (size 0.356 0.356) (layers "F.Cu" "F.Paste" "F.Mask")
      (net 1 "GND") (pinfunction "C29") (pintype "passive"))
    (pad "C30" smd circle (at 0.317 0.79 270) (size 0.356 0.356) (layers "F.Cu" "F.Paste" "F.Mask")
      (net 111 "/Display Port/MIO29") (pinfunction "C30") (pintype "passive"))
    (pad "C31" smd circle (at -0.318 0.79 270) (size 0.356 0.356) (layers "F.Cu" "F.Paste" "F.Mask")
      (net 112 "/Display Port/MIO30") (pinfunction "C31") (pintype "passive"))
    (pad "C32" smd circle (at -0.953 0.79 270) (size 0.356 0.356) (layers "F.Cu" "F.Paste" "F.Mask")
      (net 409 "/Xilinx K26 SOM/MIO31_SHUTDOWN") (pinfunction "C32") (pintype "passive"))
    (pad "C33" smd circle (at -1.588 0.79 270) (size 0.356 0.356) (layers "F.Cu" "F.Paste" "F.Mask")
      (net 1 "GND") (pinfunction "C33") (pintype "passive"))
    (pad "C34" smd circle (at -2.223 0.79 270) (size 0.356 0.356) (layers "F.Cu" "F.Paste" "F.Mask")
      (net 113 "/SD 3.0 card/MIO47") (pinfunction "C34") (pintype "passive"))
    (pad "C35" smd circle (at -2.858 0.79 270) (size 0.356 0.356) (layers "F.Cu" "F.Paste" "F.Mask")
      (net 114 "/SD 3.0 card/MIO48") (pinfunction "C35") (pintype "passive"))
    (pad "C36" smd circle (at -3.493 0.79 270) (size 0.356 0.356) (layers "F.Cu" "F.Paste" "F.Mask")
      (net 115 "/SD 3.0 card/MIO49") (pinfunction "C36") (pintype "passive"))
    (pad "C37" smd circle (at -4.128 0.79 270) (size 0.356 0.356) (layers "F.Cu" "F.Paste" "F.Mask")
      (net 1 "GND") (pinfunction "C37") (pintype "passive"))
    (pad "C38" smd circle (at -4.763 0.79 270) (size 0.356 0.356) (layers "F.Cu" "F.Paste" "F.Mask")
      (net 43 "/USB/MIO55") (pinfunction "C38") (pintype "passive"))
    (pad "C39" smd circle (at -5.398 0.79 270) (size 0.356 0.356) (layers "F.Cu" "F.Paste" "F.Mask")
      (net 44 "/USB/MIO56") (pinfunction "C39") (pintype "passive"))
    (pad "C40" smd circle (at -6.033 0.79 270) (size 0.356 0.356) (layers "F.Cu" "F.Paste" "F.Mask")
      (net 45 "/USB/MIO57") (pinfunction "C40") (pintype "passive"))
    (pad "C41" smd circle (at -6.668 0.79 270) (size 0.356 0.356) (layers "F.Cu" "F.Paste" "F.Mask")
      (net 1 "GND") (pinfunction "C41") (pintype "passive"))
    (pad "C42" smd circle (at -7.303 0.79 270) (size 0.356 0.356) (layers "F.Cu" "F.Paste" "F.Mask")
      (net 32 "/Ethernet/MIO67") (pinfunction "C42") (pintype "passive"))
    (pad "C43" smd circle (at -7.938 0.79 270) (size 0.356 0.356) (layers "F.Cu" "F.Paste" "F.Mask")
      (net 33 "/Ethernet/MIO68") (pinfunction "C43") (pintype "passive"))
    (pad "C44" smd circle (at -8.573 0.79 270) (size 0.356 0.356) (layers "F.Cu" "F.Paste" "F.Mask")
      (net 34 "/Ethernet/MIO69") (pinfunction "C44") (pintype "passive"))
    (pad "C45" smd circle (at -9.208 0.79 270) (size 0.356 0.356) (layers "F.Cu" "F.Paste" "F.Mask")
      (net 468 "unconnected-(J_SOM240_1-PadC45)") (pinfunction "C45") (pintype "passive+no_connect"))
    (pad "C46" smd circle (at -9.843 0.79 270) (size 0.356 0.356) (layers "F.Cu" "F.Paste" "F.Mask")
      (net 1 "GND") (pinfunction "C46") (pintype "passive"))
    (pad "C47" smd circle (at -10.478 0.79 270) (size 0.356 0.356) (layers "F.Cu" "F.Paste" "F.Mask")
      (net 181 "/Clock distribution/GTR_REFCLK0_C2M_P") (pinfunction "C47") (pintype "passive"))
    (pad "C48" smd circle (at -11.113 0.79 270) (size 0.356 0.356) (layers "F.Cu" "F.Paste" "F.Mask")
      (net 182 "/Clock distribution/GTR_REFCLK0_C2M_N") (pinfunction "C48") (pintype "passive"))
    (pad "C49" smd circle (at -11.748 0.79 270) (size 0.356 0.356) (layers "F.Cu" "F.Paste" "F.Mask")
      (net 1 "GND") (pinfunction "C49") (pintype "passive"))
    (pad "C50" smd circle (at -12.383 0.79 270) (size 0.356 0.356) (layers "F.Cu" "F.Paste" "F.Mask")
      (net 1 "GND") (pinfunction "C50") (pintype "passive"))
    (pad "C51" smd circle (at -13.018 0.79 270) (size 0.356 0.356) (layers "F.Cu" "F.Paste" "F.Mask")
      (net 88 "/PCIE M2 key E /GTR_DP3_M2C_P") (pinfunction "C51") (pintype "passive"))
    (pad "C52" smd circle (at -13.653 0.79 270) (size 0.356 0.356) (layers "F.Cu" "F.Paste" "F.Mask")
      (net 90 "/PCIE M2 key E /GTR_DP3_M2C_N") (pinfunction "C52") (pintype "passive"))
    (pad "C53" smd circle (at -14.288 0.79 270) (size 0.356 0.356) (layers "F.Cu" "F.Paste" "F.Mask")
      (net 1 "GND") (pinfunction "C53") (pintype "passive"))
    (pad "C54" smd circle (at -14.923 0.79 270) (size 0.356 0.356) (layers "F.Cu" "F.Paste" "F.Mask")
      (net 1 "GND") (pinfunction "C54") (pintype "passive"))
    (pad "C55" smd circle (at -15.558 0.79 270) (size 0.356 0.356) (layers "F.Cu" "F.Paste" "F.Mask")
      (net 469 "/Xilinx K26 SOM/GTR_DP1_C2M_P") (pinfunction "C55") (pintype "passive"))
    (pad "C56" smd circle (at -16.193 0.79 270) (size 0.356 0.356) (layers "F.Cu" "F.Paste" "F.Mask")
      (net 470 "/Xilinx K26 SOM/GTR_DP1_C2M_N") (pinfunction "C56") (pintype "passive"))
    (pad "C57" smd circle (at -16.828 0.79 270) (size 0.356 0.356) (layers "F.Cu" "F.Paste" "F.Mask")
      (net 1 "GND") (pinfunction "C57") (pintype "passive"))
    (pad "C58" smd circle (at -17.463 0.79 270) (size 0.356 0.356) (layers "F.Cu" "F.Paste" "F.Mask")
      (net 1 "GND") (pinfunction "C58") (pintype "passive"))
    (pad "C59" smd circle (at -18.098 0.79 270) (size 0.356 0.356) (layers "F.Cu" "F.Paste" "F.Mask")
      (net 8 "SOM_5V0") (pinfunction "C59") (pintype "passive"))
    (pad "C60" smd circle (at -18.733 0.79 270) (size 0.356 0.356) (layers "F.Cu" "F.Paste" "F.Mask")
      (net 8 "SOM_5V0") (pinfunction "C60") (pintype "passive"))
    (pad "D01" smd circle (at 18.732 1.749 270) (size 0.356 0.356) (layers "F.Cu" "F.Paste" "F.Mask")
      (net 21 "PL_1V2") (pinfunction "D01") (pintype "passive"))
    (pad "D02" smd circle (at 18.097 1.749 270) (size 0.356 0.356) (layers "F.Cu" "F.Paste" "F.Mask")
      (net 21 "PL_1V2") (pinfunction "D02") (pintype "passive"))
    (pad "D03" smd circle (at 17.462 1.749 270) (size 0.356 0.356) (layers "F.Cu" "F.Paste" "F.Mask")
      (net 1 "GND") (pinfunction "D03") (pintype "passive"))
    (pad "D04" smd circle (at 16.827 1.749 270) (size 0.356 0.356) (layers "F.Cu" "F.Paste" "F.Mask")
      (net 214 "/Camera interface/HPA02_P") (pinfunction "D04") (pintype "passive"))
    (pad "D05" smd circle (at 16.192 1.749 270) (size 0.356 0.356) (layers "F.Cu" "F.Paste" "F.Mask")
      (net 215 "/Camera interface/HPA02_N") (pinfunction "D05") (pintype "passive"))
    (pad "D06" smd circle (at 15.557 1.749 270) (size 0.356 0.356) (layers "F.Cu" "F.Paste" "F.Mask")
      (net 1 "GND") (pinfunction "D06") (pintype "passive"))
    (pad "D07" smd circle (at 14.922 1.749 270) (size 0.356 0.356) (layers "F.Cu" "F.Paste" "F.Mask")
      (net 212 "/Camera interface/HPA01_P") (pinfunction "D07") (pintype "passive"))
    (pad "D08" smd circle (at 14.287 1.749 270) (size 0.356 0.356) (layers "F.Cu" "F.Paste" "F.Mask")
      (net 213 "/Camera interface/HPA01_N") (pinfunction "D08") (pintype "passive"))
    (pad "D09" smd circle (at 13.652 1.749 270) (size 0.356 0.356) (layers "F.Cu" "F.Paste" "F.Mask")
      (net 1 "GND") (pinfunction "D09") (pintype "passive"))
    (pad "D10" smd circle (at 13.017 1.749 270) (size 0.356 0.356) (layers "F.Cu" "F.Paste" "F.Mask")
      (net 208 "/Camera interface/HPA09_P") (pinfunction "D10") (pintype "passive"))
    (pad "D11" smd circle (at 12.382 1.749 270) (size 0.356 0.356) (layers "F.Cu" "F.Paste" "F.Mask")
      (net 209 "/Camera interface/HPA09_N") (pinfunction "D11") (pintype "passive"))
    (pad "D12" smd circle (at 11.747 1.749 270) (size 0.356 0.356) (layers "F.Cu" "F.Paste" "F.Mask")
      (net 1 "GND") (pinfunction "D12") (pintype "passive"))
    (pad "D13" smd circle (at 11.112 1.749 270) (size 0.356 0.356) (layers "F.Cu" "F.Paste" "F.Mask")
      (net 471 "/Xilinx K26 SOM/HPA14_P") (pinfunction "D13") (pintype "passive"))
    (pad "D14" smd circle (at 10.477 1.749 270) (size 0.356 0.356) (layers "F.Cu" "F.Paste" "F.Mask")
      (net 472 "/Xilinx K26 SOM/HPA14_N") (pinfunction "D14") (pintype "passive"))
    (pad "D15" smd circle (at 9.842 1.749 270) (size 0.356 0.356) (layers "F.Cu" "F.Paste" "F.Mask")
      (net 1 "GND") (pinfunction "D15") (pintype "passive"))
    (pad "D16" smd circle (at 9.207 1.749 270) (size 0.356 0.356) (layers "F.Cu" "F.Paste" "F.Mask")
      (net 410 "/Camera interface/HDA00_CC") (pinfunction "D16") (pintype "passive"))
    (pad "D17" smd circle (at 8.572 1.749 270) (size 0.356 0.356) (layers "F.Cu" "F.Paste" "F.Mask")
      (net 225 "/Camera interface/HDA01") (pinfunction "D17") (pintype "passive"))
    (pad "D18" smd circle (at 7.937 1.749 270) (size 0.356 0.356) (layers "F.Cu" "F.Paste" "F.Mask")
      (net 129 "/Reset logic/HDA02") (pinfunction "D18") (pintype "passive"))
    (pad "D19" smd circle (at 7.302 1.749 270) (size 0.356 0.356) (layers "F.Cu" "F.Paste" "F.Mask")
      (net 1 "GND") (pinfunction "D19") (pintype "passive"))
    (pad "D20" smd circle (at 6.667 1.749 270) (size 0.356 0.356) (layers "F.Cu" "F.Paste" "F.Mask")
      (net 155 "/PMOD/HDA12") (pinfunction "D20") (pintype "passive"))
    (pad "D21" smd circle (at 6.032 1.749 270) (size 0.356 0.356) (layers "F.Cu" "F.Paste" "F.Mask")
      (net 156 "/PMOD/HDA13") (pinfunction "D21") (pintype "passive"))
    (pad "D22" smd circle (at 5.397 1.749 270) (size 0.356 0.356) (layers "F.Cu" "F.Paste" "F.Mask")
      (net 157 "/PMOD/HDA14") (pinfunction "D22") (pintype "passive"))
    (pad "D23" smd circle (at 4.762 1.749 270) (size 0.356 0.356) (layers "F.Cu" "F.Paste" "F.Mask")
      (net 1 "GND") (pinfunction "D23") (pintype "passive"))
    (pad "D24" smd circle (at 4.127 1.749 270) (size 0.356 0.356) (layers "F.Cu" "F.Paste" "F.Mask")
      (net 473 "/Xilinx K26 SOM/PWRGD_FPD_M2C") (pinfunction "D24") (pintype "passive"))
    (pad "D25" smd circle (at 3.492 1.749 270) (size 0.356 0.356) (layers "F.Cu" "F.Paste" "F.Mask")
      (net 474 "/Xilinx K26 SOM/PWRGD_LPD_M2C") (pinfunction "D25") (pintype "passive"))
    (pad "D26" smd circle (at 2.857 1.749 270) (size 0.356 0.356) (layers "F.Cu" "F.Paste" "F.Mask")
      (net 475 "/Xilinx K26 SOM/PWR_GD_PL_M2C") (pinfunction "D26") (pintype "passive"))
    (pad "D27" smd circle (at 2.222 1.749 270) (size 0.356 0.356) (layers "F.Cu" "F.Paste" "F.Mask")
      (net 1 "GND") (pinfunction "D27") (pintype "passive"))
    (pad "D28" smd circle (at 1.587 1.749 270) (size 0.356 0.356) (layers "F.Cu" "F.Paste" "F.Mask")
      (net 476 "/Xilinx K26 SOM/MIO26") (pinfunction "D28") (pintype "passive"))
    (pad "D29" smd circle (at 0.952 1.749 270) (size 0.356 0.356) (layers "F.Cu" "F.Paste" "F.Mask")
      (net 116 "/Display Port/MIO27") (pinfunction "D29") (pintype "passive"))
    (pad "D30" smd circle (at 0.317 1.749 270) (size 0.356 0.356) (layers "F.Cu" "F.Paste" "F.Mask")
      (net 117 "/Display Port/MIO28") (pinfunction "D30") (pintype "passive"))
    (pad "D31" smd circle (at -0.318 1.749 270) (size 0.356 0.356) (layers "F.Cu" "F.Paste" "F.Mask")
      (net 1 "GND") (pinfunction "D31") (pintype "passive"))
    (pad "D32" smd circle (at -0.953 1.749 270) (size 0.356 0.356) (layers "F.Cu" "F.Paste" "F.Mask")
      (net 130 "/Reset logic/MIO44") (pinfunction "D32") (pintype "passive"))
    (pad "D33" smd circle (at -1.588 1.749 270) (size 0.356 0.356) (layers "F.Cu" "F.Paste" "F.Mask")
      (net 106 "/SD 3.0 card/MIO45") (pinfunction "D33") (pintype "passive"))
    (pad "D34" smd circle (at -2.223 1.749 270) (size 0.356 0.356) (layers "F.Cu" "F.Paste" "F.Mask")
      (net 118 "/SD 3.0 card/MIO46") (pinfunction "D34") (pintype "passive"))
    (pad "D35" smd circle (at -2.858 1.749 270) (size 0.356 0.356) (layers "F.Cu" "F.Paste" "F.Mask")
      (net 1 "GND") (pinfunction "D35") (pintype "passive"))
    (pad "D36" smd circle (at -3.493 1.749 270) (size 0.356 0.356) (layers "F.Cu" "F.Paste" "F.Mask")
      (net 46 "/USB/MIO52") (pinfunction "D36") (pintype "passive"))
    (pad "D37" smd circle (at -4.128 1.749 270) (size 0.356 0.356) (layers "F.Cu" "F.Paste" "F.Mask")
      (net 47 "/USB/MIO53") (pinfunction "D37") (pintype "passive"))
    (pad "D38" smd circle (at -4.763 1.749 270) (size 0.356 0.356) (layers "F.Cu" "F.Paste" "F.Mask")
      (net 48 "/USB/MIO54") (pinfunction "D38") (pintype "passive"))
    (pad "D39" smd circle (at -5.398 1.749 270) (size 0.356 0.356) (layers "F.Cu" "F.Paste" "F.Mask")
      (net 1 "GND") (pinfunction "D39") (pintype "passive"))
    (pad "D40" smd circle (at -6.033 1.749 270) (size 0.356 0.356) (layers "F.Cu" "F.Paste" "F.Mask")
      (net 25 "/Ethernet/MIO64") (pinfunction "D40") (pintype "passive"))
    (pad "D41" smd circle (at -6.668 1.749 270) (size 0.356 0.356) (layers "F.Cu" "F.Paste" "F.Mask")
      (net 35 "/Ethernet/MIO65") (pinfunction "D41") (pintype "passive"))
    (pad "D42" smd circle (at -7.303 1.749 270) (size 0.356 0.356) (layers "F.Cu" "F.Paste" "F.Mask")
      (net 36 "/Ethernet/MIO66") (pinfunction "D42") (pintype "passive"))
    (pad "D43" smd circle (at -7.938 1.749 270) (size 0.356 0.356) (layers "F.Cu" "F.Paste" "F.Mask")
      (net 1 "GND") (pinfunction "D43") (pintype "passive"))
    (pad "D44" smd circle (at -8.573 1.749 270) (size 0.356 0.356) (layers "F.Cu" "F.Paste" "F.Mask")
      (net 49 "/Ethernet/MIO76") (pinfunction "D44") (pintype "passive"))
    (pad "D45" smd circle (at -9.208 1.749 270) (size 0.356 0.356) (layers "F.Cu" "F.Paste" "F.Mask")
      (net 50 "/Ethernet/MIO77") (pinfunction "D45") (pintype "passive"))
    (pad "D46" smd circle (at -9.843 1.749 270) (size 0.356 0.356) (layers "F.Cu" "F.Paste" "F.Mask")
      (net 477 "unconnected-(J_SOM240_1-PadD46)") (pinfunction "D46") (pintype "passive+no_connect"))
    (pad "D47" smd circle (at -10.478 1.749 270) (size 0.356 0.356) (layers "F.Cu" "F.Paste" "F.Mask")
      (net 1 "GND") (pinfunction "D47") (pintype "passive"))
    (pad "D48" smd circle (at -11.113 1.749 270) (size 0.356 0.356) (layers "F.Cu" "F.Paste" "F.Mask")
      (net 1 "GND") (pinfunction "D48") (pintype "passive"))
    (pad "D49" smd circle (at -11.748 1.749 270) (size 0.356 0.356) (layers "F.Cu" "F.Paste" "F.Mask")
      (net 119 "/PCIE M2 key E /GTR_DP3_C2M_P") (pinfunction "D49") (pintype "passive"))
    (pad "D50" smd circle (at -12.383 1.749 270) (size 0.356 0.356) (layers "F.Cu" "F.Paste" "F.Mask")
      (net 120 "/PCIE M2 key E /GTR_DP3_C2M_N") (pinfunction "D50") (pintype "passive"))
    (pad "D51" smd circle (at -13.018 1.749 270) (size 0.356 0.356) (layers "F.Cu" "F.Paste" "F.Mask")
      (net 1 "GND") (pinfunction "D51") (pintype "passive"))
    (pad "D52" smd circle (at -13.653 1.749 270) (size 0.356 0.356) (layers "F.Cu" "F.Paste" "F.Mask")
      (net 1 "GND") (pinfunction "D52") (pintype "passive"))
    (pad "D53" smd circle (at -14.288 1.749 270) (size 0.356 0.356) (layers "F.Cu" "F.Paste" "F.Mask")
      (net 183 "/Clock distribution/GTR_REFCLK2_C2M_P") (pinfunction "D53") (pintype "passive"))
    (pad "D54" smd circle (at -14.923 1.749 270) (size 0.356 0.356) (layers "F.Cu" "F.Paste" "F.Mask")
      (net 184 "/Clock distribution/GTR_REFCLK2_C2M_N") (pinfunction "D54") (pintype "passive"))
    (pad "D55" smd circle (at -15.558 1.749 270) (size 0.356 0.356) (layers "F.Cu" "F.Paste" "F.Mask")
      (net 1 "GND") (pinfunction "D55") (pintype "passive"))
    (pad "D56" smd circle (at -16.193 1.749 270) (size 0.356 0.356) (layers "F.Cu" "F.Paste" "F.Mask")
      (net 1 "GND") (pinfunction "D56") (pintype "passive"))
    (pad "D57" smd circle (at -16.828 1.749 270) (size 0.356 0.356) (layers "F.Cu" "F.Paste" "F.Mask")
      (net 58 "/USB/GTR_DP2_M2C_P") (pinfunction "D57") (pintype "passive"))
    (pad "D58" smd circle (at -17.463 1.749 270) (size 0.356 0.356) (layers "F.Cu" "F.Paste" "F.Mask")
      (net 59 "/USB/GTR_DP2_M2C_N") (pinfunction "D58") (pintype "passive"))
    (pad "D59" smd circle (at -18.098 1.749 270) (size 0.356 0.356) (layers "F.Cu" "F.Paste" "F.Mask")
      (net 1 "GND") (pinfunction "D59") (pintype "passive"))
    (pad "D60" smd circle (at -18.733 1.749 270) (size 0.356 0.356) (layers "F.Cu" "F.Paste" "F.Mask")
      (net 8 "SOM_5V0") (pinfunction "D60") (pintype "passive"))
  )

  (footprint "kria-k26-devboard-footprints:USON-10_2.5x1mm_P0.5mm" (layer "F.Cu")
    (at 81.96 136)
    (descr "USON-10 2.5x1mm_ Pitch 0.5mm")
    (tags "USON-10 2.5x1mm Pitch 0.5mm")
    (property "Author" "Antmicro")
    (property "License" "Apache-2.0")
    (property "MPN" "TPD4E05U06QDQARQ1")
    (property "Manufacturer" "Texas Instruments")
    (property "Sheetfile" "debug.kicad_sch")
    (property "Sheetname" "Debug and JTAG")
    (property "ki_description" "ESD protection")
    (property "ki_keywords" "SMT, DIODE, IC, TVS, ESD")
    (attr smd)
    (fp_text reference "U41" (at -0.8 -1.65) (layer "F.SilkS")
        (effects (font (size 0.7 0.7) (thickness 0.15)) (justify left bottom))
    )
    (fp_text value "TPD4E05U06QDQARQ1" (at 0.018 2.499) (layer "F.Fab") hide
        (effects (font (size 0.7 0.7) (thickness 0.15)) (justify left bottom))
    )
    (fp_text user "${REFERENCE}" (at -0.802 4.498) (layer "F.Fab") hide
        (effects (font (size 0.7 0.7) (thickness 0.15)) (justify left bottom))
    )
    (fp_text user "Author: Antmicro" (at -0.802 5.7) (layer "F.Fab") hide
        (effects (font (size 0.7 0.7) (thickness 0.15)) (justify left bottom))
    )
    (fp_text user "License: Apache-2.0" (at -0.802 6.9) (layer "F.Fab") hide
        (effects (font (size 0.7 0.7) (thickness 0.15)) (justify left bottom))
    )
    (fp_line (start 0.498 -1.401) (end -0.5 -1.401)
      (stroke (width 0.15) (type solid)) (layer "F.SilkS"))
    (fp_line (start 0.498 1.398) (end -0.5 1.398)
      (stroke (width 0.15) (type solid)) (layer "F.SilkS"))
    (fp_circle (center -0.68 -1.27) (end -0.63 -1.27)
      (stroke (width 0.15) (type solid)) (fill solid) (layer "F.SilkS"))
    (fp_rect (start -0.8 -1.5) (end 0.8 1.499)
      (stroke (width 0.05) (type solid)) (fill none) (layer "F.CrtYd"))
    (fp_line (start -0.5 -1) (end -0.5 1.249)
      (stroke (width 0.15) (type solid)) (layer "F.Fab"))
    (fp_line (start -0.5 1.249) (end 0.498 1.249)
      (stroke (width 0.15) (type solid)) (layer "F.Fab"))
    (fp_line (start -0.25 -1.25) (end -0.5 -1)
      (stroke (width 0.15) (type solid)) (layer "F.Fab"))
    (fp_line (start 0.498 -1.25) (end -0.25 -1.25)
      (stroke (width 0.15) (type solid)) (layer "F.Fab"))
    (fp_line (start 0.498 -1.25) (end 0.498 1.249)
      (stroke (width 0.15) (type solid)) (layer "F.Fab"))
    (pad "1" smd roundrect (at -0.387 -1 270) (size 0.25 0.55) (layers "F.Cu" "F.Paste" "F.Mask") (roundrect_rratio 0.25)
      (net 145 "/Debug and JTAG/JTAG_TMS_C2M") (pintype "passive"))
    (pad "2" smd roundrect (at -0.387 -0.5 270) (size 0.25 0.55) (layers "F.Cu" "F.Paste" "F.Mask") (roundrect_rratio 0.25)
      (net 143 "/Debug and JTAG/JTAG_TCK_C2M") (pintype "passive"))
    (pad "3" smd roundrect (at -0.387 0 270) (size 0.4 0.55) (layers "F.Cu" "F.Paste" "F.Mask") (roundrect_rratio 0.25)
      (net 1 "GND") (pintype "power_in"))
    (pad "4" smd roundrect (at -0.387 0.498 270) (size 0.25 0.55) (layers "F.Cu" "F.Paste" "F.Mask") (roundrect_rratio 0.25)
      (net 142 "/Debug and JTAG/JTAG_TDO_M2C") (pintype "passive"))
    (pad "5" smd roundrect (at -0.387 0.998 270) (size 0.25 0.55) (layers "F.Cu" "F.Paste" "F.Mask") (roundrect_rratio 0.25)
      (net 141 "/Debug and JTAG/JTAG_TDI_C2M") (pintype "passive"))
    (pad "6" smd roundrect (at 0.385 0.998 270) (size 0.25 0.55) (layers "F.Cu" "F.Paste" "F.Mask") (roundrect_rratio 0.25)
      (net 141 "/Debug and JTAG/JTAG_TDI_C2M") (pintype "passive"))
    (pad "7" smd roundrect (at 0.385 0.498 270) (size 0.25 0.55) (layers "F.Cu" "F.Paste" "F.Mask") (roundrect_rratio 0.25)
      (net 142 "/Debug and JTAG/JTAG_TDO_M2C") (pintype "passive"))
    (pad "8" smd roundrect (at 0.385 0 270) (size 0.4 0.55) (layers "F.Cu" "F.Paste" "F.Mask") (roundrect_rratio 0.25)
      (net 1 "GND") (pintype "passive"))
    (pad "9" smd roundrect (at 0.385 -0.5 270) (size 0.25 0.55) (layers "F.Cu" "F.Paste" "F.Mask") (roundrect_rratio 0.25)
      (net 143 "/Debug and JTAG/JTAG_TCK_C2M") (pintype "passive"))
    (pad "10" smd roundrect (at 0.385 -1 270) (size 0.25 0.55) (layers "F.Cu" "F.Paste" "F.Mask") (roundrect_rratio 0.25)
      (net 145 "/Debug and JTAG/JTAG_TMS_C2M") (pintype "passive"))
  )

  (footprint "kria-k26-devboard-footprints:WSON-6-1EP_2x2mm_P0.65mm" (layer "F.Cu")
    (at 151.9 111 90)
    (property "Author" "Antmicro")
    (property "License" "Apache-2.0")
    (property "MPN" "NCP730BMT330TBG")
    (property "Manufacturer" "ON Semiconductor")
    (property "Sheetfile" "debug.kicad_sch")
    (property "Sheetname" "Debug and JTAG")
    (property "ki_description" "Linear Voltage Regulator IC Positive Fixed 1 Output 150mA 6-WDFN (2x2)")
    (property "ki_keywords" "SMT, PMIC, IC, LDO, VOLTAGE, REGULATOR")
    (attr smd)
    (fp_text reference "U38" (at -0.43 -1.13 90) (layer "F.SilkS")
        (effects (font (size 0.7 0.7) (thickness 0.15)) (justify left bottom))
    )
    (fp_text value "NCP730BMT330_WSON" (at 0 2.2 90) (layer "F.Fab") hide
        (effects (font (size 0.7 0.7) (thickness 0.15)) (justify left bottom))
    )
    (fp_text user "Author: Antmicro" (at -1.01 5.2 90) (layer "F.Fab") hide
        (effects (font (size 0.7 0.7) (thickness 0.15)) (justify left bottom))
    )
    (fp_text user "License: Apache-2.0" (at -1.01 6.4 90) (layer "F.Fab") hide
        (effects (font (size 0.7 0.7) (thickness 0.15)) (justify left bottom))
    )
    (fp_text user "${REFERENCE}" (at -1.01 3.999 90) (layer "F.Fab") hide
        (effects (font (size 0.7 0.7) (thickness 0.15)) (justify left bottom))
    )
    (fp_line (start -1 1) (end 1 1)
      (stroke (width 0.12) (type solid)) (layer "F.SilkS"))
    (fp_line (start 1 -1) (end -1.05 -1)
      (stroke (width 0.12) (type solid)) (layer "F.SilkS"))
    (fp_circle (center -1.275 -1.075) (end -1.224 -1.075)
      (stroke (width 0.15) (type solid)) (fill solid) (layer "F.SilkS"))
    (fp_rect (start -1.45 -1.25) (end 1.45 1.25)
      (stroke (width 0.05) (type solid)) (fill none) (layer "F.CrtYd"))
    (pad "1" smd roundrect (at -0.975 -0.652 90) (size 0.45 0.4) (layers "F.Cu" "F.Paste" "F.Mask") (roundrect_rratio 0.25)
      (net 138 "/Debug and JTAG/USB_3V3") (pinfunction "V_{OUT}") (pintype "power_out"))
    (pad "2" smd roundrect (at -0.975 0 90) (size 0.45 0.4) (layers "F.Cu" "F.Paste" "F.Mask") (roundrect_rratio 0.25)
      (net 734 "unconnected-(U38-NC-Pad2)") (pinfunction "NC") (pintype "no_connect"))
    (pad "3" smd roundrect (at -0.975 0.65 90) (size 0.45 0.4) (layers "F.Cu" "F.Paste" "F.Mask") (roundrect_rratio 0.25)
      (net 1 "GND") (pinfunction "GND") (pintype "power_in"))
    (pad "4" smd roundrect (at 0.973 0.65 90) (size 0.45 0.4) (layers "F.Cu" "F.Paste" "F.Mask") (roundrect_rratio 0.25)
      (net 313 "/Debug and JTAG/USB_VBUS") (pinfunction "EN") (pintype "input"))
    (pad "5" smd roundrect (at 0.973 0 90) (size 0.45 0.4) (layers "F.Cu" "F.Paste" "F.Mask") (roundrect_rratio 0.25)
      (net 735 "unconnected-(U38-PG-Pad5)") (pinfunction "PG") (pintype "open_collector+no_connect"))
    (pad "6" smd roundrect (at 0.973 -0.652 90) (size 0.45 0.4) (layers "F.Cu" "F.Paste" "F.Mask") (roundrect_rratio 0.25)
      (net 313 "/Debug and JTAG/USB_VBUS") (pinfunction "V_{IN}") (pintype "power_in"))
    (pad "7" smd roundrect (at 0 0 90) (size 1.12 1.72) (layers "F.Cu" "F.Paste" "F.Mask") (roundrect_rratio 0.1)
      (net 1 "GND") (pinfunction "GND") (pintype "passive"))
  )

  (footprint "kria-k26-devboard-footprints:USON-10_2.5x1mm_P0.5mm" (layer "F.Cu")
    (at 174.3 141.9 -90)
    (descr "USON-10 2.5x1mm_ Pitch 0.5mm")
    (tags "USON-10 2.5x1mm Pitch 0.5mm")
    (property "Author" "Antmicro")
    (property "License" "Apache-2.0")
    (property "MPN" "TPD4E05U06QDQARQ1")
    (property "Manufacturer" "Texas Instruments")
    (property "Sheetfile" "pmod.kicad_sch")
    (property "Sheetname" "PMOD")
    (property "ki_description" "ESD protection")
    (property "ki_keywords" "SMT, DIODE, IC, TVS, ESD")
    (attr smd)
    (fp_text reference "U15" (at 0.018 -1.7 -90) (layer "F.SilkS")
        (effects (font (size 0.7 0.7) (thickness 0.15)) (justify left bottom))
    )
    (fp_text value "TPD4E05U06QDQARQ1" (at 0.018 2.499 -90) (layer "F.Fab")
        (effects (font (size 0.7 0.7) (thickness 0.15)) (justify left bottom))
    )
    (fp_text user "Author: Antmicro" (at -0.802 5.7 -90) (layer "F.Fab") hide
        (effects (font (size 0.7 0.7) (thickness 0.15)) (justify left bottom))
    )
    (fp_text user "License: Apache-2.0" (at -0.802 6.9 -90) (layer "F.Fab") hide
        (effects (font (size 0.7 0.7) (thickness 0.15)) (justify left bottom))
    )
    (fp_text user "${REFERENCE}" (at -0.802 4.498 -90) (layer "F.Fab") hide
        (effects (font (size 0.7 0.7) (thickness 0.15)) (justify left bottom))
    )
    (fp_line (start 0.498 -1.401) (end -0.5 -1.401)
      (stroke (width 0.15) (type solid)) (layer "F.SilkS"))
    (fp_line (start 0.498 1.398) (end -0.5 1.398)
      (stroke (width 0.15) (type solid)) (layer "F.SilkS"))
    (fp_circle (center -0.68 -1.27) (end -0.63 -1.27)
      (stroke (width 0.15) (type solid)) (fill solid) (layer "F.SilkS"))
    (fp_rect (start -0.8 -1.5) (end 0.8 1.499)
      (stroke (width 0.05) (type solid)) (fill none) (layer "F.CrtYd"))
    (fp_line (start -0.5 -1) (end -0.5 1.249)
      (stroke (width 0.15) (type solid)) (layer "F.Fab"))
    (fp_line (start -0.5 1.249) (end 0.498 1.249)
      (stroke (width 0.15) (type solid)) (layer "F.Fab"))
    (fp_line (start -0.25 -1.25) (end -0.5 -1)
      (stroke (width 0.15) (type solid)) (layer "F.Fab"))
    (fp_line (start 0.498 -1.25) (end -0.25 -1.25)
      (stroke (width 0.15) (type solid)) (layer "F.Fab"))
    (fp_line (start 0.498 -1.25) (end 0.498 1.249)
      (stroke (width 0.15) (type solid)) (layer "F.Fab"))
    (pad "1" smd roundrect (at -0.387 -1 180) (size 0.25 0.55) (layers "F.Cu" "F.Paste" "F.Mask") (roundrect_rratio 0.25)
      (net 146 "/PMOD/HDA15") (pintype "passive"))
    (pad "2" smd roundrect (at -0.387 -0.5 180) (size 0.25 0.55) (layers "F.Cu" "F.Paste" "F.Mask") (roundrect_rratio 0.25)
      (net 147 "/PMOD/HDA16_CC") (pintype "passive"))
    (pad "3" smd roundrect (at -0.387 0 180) (size 0.4 0.55) (layers "F.Cu" "F.Paste" "F.Mask") (roundrect_rratio 0.25)
      (net 1 "GND") (pintype "power_in"))
    (pad "4" smd roundrect (at -0.387 0.498 180) (size 0.25 0.55) (layers "F.Cu" "F.Paste" "F.Mask") (roundrect_rratio 0.25)
      (net 148 "/PMOD/HDA17") (pintype "passive"))
    (pad "5" smd roundrect (at -0.387 0.998 180) (size 0.25 0.55) (layers "F.Cu" "F.Paste" "F.Mask") (roundrect_rratio 0.25)
      (net 152 "/PMOD/HDA18") (pintype "passive"))
    (pad "6" smd roundrect (at 0.385 0.998 180) (size 0.25 0.55) (layers "F.Cu" "F.Paste" "F.Mask") (roundrect_rratio 0.25)
      (net 152 "/PMOD/HDA18") (pintype "passive"))
    (pad "7" smd roundrect (at 0.385 0.498 180) (size 0.25 0.55) (layers "F.Cu" "F.Paste" "F.Mask") (roundrect_rratio 0.25)
      (net 148 "/PMOD/HDA17") (pintype "passive"))
    (pad "8" smd roundrect (at 0.385 0 180) (size 0.4 0.55) (layers "F.Cu" "F.Paste" "F.Mask") (roundrect_rratio 0.25)
      (net 1 "GND") (pintype "passive"))
    (pad "9" smd roundrect (at 0.385 -0.5 180) (size 0.25 0.55) (layers "F.Cu" "F.Paste" "F.Mask") (roundrect_rratio 0.25)
      (net 147 "/PMOD/HDA16_CC") (pintype "passive"))
    (pad "10" smd roundrect (at 0.385 -1 180) (size 0.25 0.55) (layers "F.Cu" "F.Paste" "F.Mask") (roundrect_rratio 0.25)
      (net 146 "/PMOD/HDA15") (pintype "passive"))
  )

  (footprint "kria-k26-devboard-footprints:D_SOD-323F" (layer "F.Cu")
    (at 154.31 111.01 -90)
    (property "Author" "Antmicro")
    (property "License" "Apache-2.0")
    (property "MPN" "1N4148WS")
    (property "Manufacturer" "ON Semiconductor")
    (property "Sheetfile" "debug.kicad_sch")
    (property "Sheetname" "Debug and JTAG")
    (property "ki_description" "Small Signal Fast Switching Diode")
    (attr smd)
    (fp_text reference "D7" (at 2.95 -0.935 -90) (layer "F.SilkS")
        (effects (font (size 0.7 0.7) (thickness 0.15)) (justify left bottom))
    )
    (fp_text value "1N4148WS" (at -1.7 1.9 -90) (layer "F.Fab") hide
        (effects (font (size 0.7 0.7) (thickness 0.15)) (justify left bottom))
    )
    (fp_text user "Author: Antmicro" (at -1.8 4.46 -90) (layer "F.Fab") hide
        (effects (font (size 0.7 0.7) (thickness 0.15)) (justify left bottom))
    )
    (fp_text user "${REFERENCE}" (at -1.8 3.2 -90) (layer "F.Fab") hide
        (effects (font (size 0.7 0.7) (thickness 0.15)) (justify left bottom))
    )
    (fp_text user "License: Apache-2.0" (at -1.8 5.8 -90) (layer "F.Fab") hide
        (effects (font (size 0.7 0.7) (thickness 0.15)) (justify left bottom))
    )
    (fp_line (start -0.975 -0.75) (end -0.975 -0.45)
      (stroke (width 0.15) (type solid)) (layer "F.SilkS"))
    (fp_line (start -0.975 0.748) (end -0.975 0.45)
      (stroke (width 0.15) (type solid)) (layer "F.SilkS"))
    (fp_line (start -0.625 -0.75) (end -0.975 -0.75)
      (stroke (width 0.15) (type solid)) (layer "F.SilkS"))
    (fp_line (start -0.625 0.748) (end -0.975 0.748)
      (stroke (width 0.15) (type solid)) (layer "F.SilkS"))
    (fp_line (start -0.5 -0.426) (end -0.5 0.424)
      (stroke (width 0.15) (type solid)) (layer "F.SilkS"))
    (fp_line (start 0.623 -0.75) (end 0.973 -0.75)
      (stroke (width 0.15) (type solid)) (layer "F.SilkS"))
    (fp_line (start 0.973 -0.75) (end 0.973 -0.45)
      (stroke (width 0.15) (type solid)) (layer "F.SilkS"))
    (fp_line (start 0.973 0.45) (end 0.973 0.748)
      (stroke (width 0.15) (type solid)) (layer "F.SilkS"))
    (fp_line (start 0.973 0.748) (end 0.623 0.748)
      (stroke (width 0.15) (type solid)) (layer "F.SilkS"))
    (fp_rect (start -1.6 -0.827) (end 1.599 0.825)
      (stroke (width 0.05) (type solid)) (fill none) (layer "F.CrtYd"))
    (fp_line (start -0.85 -0.625) (end 0.848 -0.625)
      (stroke (width 0.15) (type solid)) (layer "F.Fab"))
    (fp_line (start -0.85 0.623) (end -0.85 -0.625)
      (stroke (width 0.15) (type solid)) (layer "F.Fab"))
    (fp_line (start -0.85 0.623) (end 0.848 0.623)
      (stroke (width 0.15) (type solid)) (layer "F.Fab"))
    (fp_line (start 0.848 -0.625) (end 0.848 0.623)
      (stroke (width 0.15) (type solid)) (layer "F.Fab"))
    (pad "A" smd roundrect (at 1.05 0 270) (size 0.8 0.6) (layers "F.Cu" "F.Paste" "F.Mask") (roundrect_rratio 0.15)
      (net 266 "/Debug and JTAG/USBB_VBUS") (pinfunction "A") (pintype "passive"))
    (pad "K" smd roundrect (at -1.051 0 270) (size 0.8 0.6) (layers "F.Cu" "F.Paste" "F.Mask") (roundrect_rratio 0.15)
      (net 313 "/Debug and JTAG/USB_VBUS") (pinfunction "K") (pintype "passive"))
  )

  (footprint "kria-k26-devboard-footprints:D_SOD-323F" (layer "F.Cu")
    (at 154.325 107.8 90)
    (property "Author" "Antmicro")
    (property "License" "Apache-2.0")
    (property "MPN" "1N4148WS")
    (property "Manufacturer" "ON Semiconductor")
    (property "Sheetfile" "debug.kicad_sch")
    (property "Sheetname" "Debug and JTAG")
    (property "ki_description" "Small Signal Fast Switching Diode")
    (attr smd)
    (fp_text reference "D6" (at 1.53 0.295 90) (layer "F.SilkS")
        (effects (font (size 0.7 0.7) (thickness 0.15)) (justify left bottom))
    )
    (fp_text value "1N4148WS" (at -1.7 1.9 90) (layer "F.Fab") hide
        (effects (font (size 0.7 0.7) (thickness 0.15)) (justify left bottom))
    )
    (fp_text user "License: Apache-2.0" (at -1.8 5.8 90) (layer "F.Fab") hide
        (effects (font (size 0.7 0.7) (thickness 0.15)) (justify left bottom))
    )
    (fp_text user "${REFERENCE}" (at -1.8 3.2 90) (layer "F.Fab") hide
        (effects (font (size 0.7 0.7) (thickness 0.15)) (justify left bottom))
    )
    (fp_text user "Author: Antmicro" (at -1.8 4.46 90) (layer "F.Fab") hide
        (effects (font (size 0.7 0.7) (thickness 0.15)) (justify left bottom))
    )
    (fp_line (start -0.975 -0.75) (end -0.975 -0.45)
      (stroke (width 0.15) (type solid)) (layer "F.SilkS"))
    (fp_line (start -0.975 0.748) (end -0.975 0.45)
      (stroke (width 0.15) (type solid)) (layer "F.SilkS"))
    (fp_line (start -0.625 -0.75) (end -0.975 -0.75)
      (stroke (width 0.15) (type solid)) (layer "F.SilkS"))
    (fp_line (start -0.625 0.748) (end -0.975 0.748)
      (stroke (width 0.15) (type solid)) (layer "F.SilkS"))
    (fp_line (start -0.5 -0.426) (end -0.5 0.424)
      (stroke (width 0.15) (type solid)) (layer "F.SilkS"))
    (fp_line (start 0.623 -0.75) (end 0.973 -0.75)
      (stroke (width 0.15) (type solid)) (layer "F.SilkS"))
    (fp_line (start 0.973 -0.75) (end 0.973 -0.45)
      (stroke (width 0.15) (type solid)) (layer "F.SilkS"))
    (fp_line (start 0.973 0.45) (end 0.973 0.748)
      (stroke (width 0.15) (type solid)) (layer "F.SilkS"))
    (fp_line (start 0.973 0.748) (end 0.623 0.748)
      (stroke (width 0.15) (type solid)) (layer "F.SilkS"))
    (fp_rect (start -1.6 -0.827) (end 1.599 0.825)
      (stroke (width 0.05) (type solid)) (fill none) (layer "F.CrtYd"))
    (fp_line (start -0.85 -0.625) (end 0.848 -0.625)
      (stroke (width 0.15) (type solid)) (layer "F.Fab"))
    (fp_line (start -0.85 0.623) (end -0.85 -0.625)
      (stroke (width 0.15) (type solid)) (layer "F.Fab"))
    (fp_line (start -0.85 0.623) (end 0.848 0.623)
      (stroke (width 0.15) (type solid)) (layer "F.Fab"))
    (fp_line (start 0.848 -0.625) (end 0.848 0.623)
      (stroke (width 0.15) (type solid)) (layer "F.Fab"))
    (pad "A" smd roundrect (at 1.05 0 90) (size 0.8 0.6) (layers "F.Cu" "F.Paste" "F.Mask") (roundrect_rratio 0.15)
      (net 265 "/Debug and JTAG/USBC_VBUS") (pinfunction "A") (pintype "passive"))
    (pad "K" smd roundrect (at -1.051 0 90) (size 0.8 0.6) (layers "F.Cu" "F.Paste" "F.Mask") (roundrect_rratio 0.15)
      (net 313 "/Debug and JTAG/USB_VBUS") (pinfunction "K") (pintype "passive"))
  )

  (footprint "kria-k26-devboard-footprints:R_0402_1005Metric" (layer "F.Cu")
    (at 87.2744 115.0112 180)
    (descr "Resistor SMD 0402")
    (tags "resistor SMD 0402")
    (property "Author" "Antmicro")
    (property "License" "Apache-2.0")
    (property "MPN" "CR0402-FX-1002GLF")
    (property "Manufacturer" "Bourns")
    (property "Sheetfile" "k26_som.kicad_sch")
    (property "Sheetname" "Xilinx K26 SOM")
    (property "Tolerance" "1%")
    (property "Val" "10k")
    (property "ki_description" "10k resistor in 0402 package with 1% tolerance")
    (attr smd)
    (fp_text reference "R155" (at 1.0744 4.9912 180) (layer "F.SilkS")
        (effects (font (size 0.7 0.7) (thickness 0.15)) (justify left bottom))
    )
    (fp_text value "R_10k_0402" (at 0 1.4 180) (layer "F.Fab") hide
        (effects (font (size 0.7 0.7) (thickness 0.15)) (justify left bottom))
    )
    (fp_text user "${REFERENCE}" (at -0.95 3.168 180) (layer "F.Fab") hide
        (effects (font (size 0.7 0.7) (thickness 0.15)) (justify left bottom))
    )
    (fp_text user "Author: Antmicro" (at -0.95 4.169 180) (layer "F.Fab") hide
        (effects (font (size 0.7 0.7) (thickness 0.15)) (justify left bottom))
    )
    (fp_text user "License: Apache-2.0" (at -0.95 5.169 180) (layer "F.Fab") hide
        (effects (font (size 0.7 0.7) (thickness 0.15)) (justify left bottom))
    )
    (fp_rect (start -0.93 -0.47) (end 0.93 0.47)
      (stroke (width 0.05) (type solid)) (fill none) (layer "F.CrtYd"))
    (fp_rect (start -0.5 -0.25) (end 0.5 0.25)
      (stroke (width 0.15) (type solid)) (fill none) (layer "F.Fab"))
    (pad "1" smd roundrect (at -0.485 0 180) (size 0.59 0.64) (layers "F.Cu" "F.Paste" "F.Mask") (roundrect_rratio 0.25)
      (net 409 "/Xilinx K26 SOM/MIO31_SHUTDOWN") (pintype "passive"))
    (pad "2" smd roundrect (at 0.485 0 180) (size 0.59 0.64) (layers "F.Cu" "F.Paste" "F.Mask") (roundrect_rratio 0.25)
      (net 1 "GND") (pintype "passive"))
  )

  (footprint "kria-k26-devboard-footprints:R_0402_1005Metric" (layer "F.Cu")
    (at 117.16 122.11 -90)
    (descr "Resistor SMD 0402")
    (tags "resistor SMD 0402")
    (property "Author" "Antmicro")
    (property "License" "Apache-2.0")
    (property "MPN" "CR0402-FX-4750GLF")
    (property "Manufacturer" "Bourns")
    (property "Sheetfile" "clock.kicad_sch")
    (property "Sheetname" "Clock distribution")
    (property "Tolerance" "1%")
    (property "Val" "475R")
    (property "ki_description" "475R resistor in 0402 package with 1% tolerance")
    (attr smd)
    (fp_text reference "R22" (at -0.75 -1.52 90) (layer "F.SilkS")
        (effects (font (size 0.7 0.7) (thickness 0.15)) (justify right bottom))
    )
    (fp_text value "R_475R_0402" (at 0 1.4 90) (layer "F.Fab") hide
        (effects (font (size 0.7 0.7) (thickness 0.15)) (justify right bottom))
    )
    (fp_text user "${REFERENCE}" (at -0.95 3.168 90) (layer "F.Fab") hide
        (effects (font (size 0.7 0.7) (thickness 0.15)) (justify right bottom))
    )
    (fp_text user "Author: Antmicro" (at -0.95 4.169 90) (layer "F.Fab") hide
        (effects (font (size 0.7 0.7) (thickness 0.15)) (justify right bottom))
    )
    (fp_text user "License: Apache-2.0" (at -0.95 5.169 90) (layer "F.Fab") hide
        (effects (font (size 0.7 0.7) (thickness 0.15)) (justify right bottom))
    )
    (fp_rect (start -0.93 -0.47) (end 0.93 0.47)
      (stroke (width 0.05) (type solid)) (fill none) (layer "F.CrtYd"))
    (fp_rect (start -0.5 -0.25) (end 0.5 0.25)
      (stroke (width 0.15) (type solid)) (fill none) (layer "F.Fab"))
    (pad "1" smd roundrect (at -0.485 0 270) (size 0.59 0.64) (layers "F.Cu" "F.Paste" "F.Mask") (roundrect_rratio 0.25)
      (net 642 "Net-(U7-I_{REF})") (pintype "passive"))
    (pad "2" smd roundrect (at 0.485 0 270) (size 0.59 0.64) (layers "F.Cu" "F.Paste" "F.Mask") (roundrect_rratio 0.25)
      (net 1 "GND") (pintype "passive"))
  )

  (footprint "kria-k26-devboard-footprints:R_0603_1608Metric" (layer "F.Cu")
    (at 176.2 115.5 180)
    (descr "Resistor SMD 0603")
    (tags "resistor SMD 0603")
    (property "Author" "Antmicro")
    (property "License" "Apache-2.0")
    (property "MPN" "PMR03EZPJ000")
    (property "Manufacturer" "ROHM Semiconductor")
    (property "Max. Curr." "22.4A")
    (property "Sheetfile" "dc-dc-conventers.kicad_sch")
    (property "Sheetname" "DC/DC conventers")
    (property "Val" "0R")
    (property "ki_description" "Metal strip 0Ohm jumper 22.4A")
    (property "ki_keywords" "Metal strip 0Ohm jumper 22.4A high power hpwr current")
    (attr smd)
    (fp_text reference "R164" (at 1.04 0.94 180) (layer "F.SilkS")
        (effects (font (size 0.7 0.7) (thickness 0.15)) (justify left bottom))
    )
    (fp_text value "R_0R_22.4A_0603" (at 0 1.6 180) (layer "F.Fab") hide
        (effects (font (size 0.7 0.7) (thickness 0.15)) (justify left bottom))
    )
    (fp_text user "${REFERENCE}" (at -1.25 3.898 180) (layer "F.Fab") hide
        (effects (font (size 0.7 0.7) (thickness 0.15)) (justify left bottom))
    )
    (fp_text user "Author: Antmicro" (at -1.25 4.9 180) (layer "F.Fab") hide
        (effects (font (size 0.7 0.7) (thickness 0.15)) (justify left bottom))
    )
    (fp_text user "License: Apache-2.0" (at -1.25 5.9 180) (layer "F.Fab") hide
        (effects (font (size 0.7 0.7) (thickness 0.15)) (justify left bottom))
    )
    (fp_line (start -0.3 -0.3) (end 0.3 -0.3)
      (stroke (width 0.15) (type solid)) (layer "F.SilkS"))
    (fp_line (start -0.3 0.3) (end 0.3 0.3)
      (stroke (width 0.15) (type solid)) (layer "F.SilkS"))
    (fp_rect (start -1.25 -0.7) (end 1.25 0.7)
      (stroke (width 0.05) (type solid)) (fill none) (layer "F.CrtYd"))
    (fp_rect (start -0.8 -0.4) (end 0.8 0.4)
      (stroke (width 0.15) (type solid)) (fill none) (layer "F.Fab"))
    (pad "1" smd roundrect (at -0.7 0 180) (size 0.6 0.8) (layers "F.Cu" "F.Paste" "F.Mask") (roundrect_rratio 0.2)
      (net 767 "/Power Supply/DC/DC conventers/PS_1V8_OUT") (pintype "passive"))
    (pad "2" smd roundrect (at 0.7 0 180) (size 0.6 0.8) (layers "F.Cu" "F.Paste" "F.Mask") (roundrect_rratio 0.2)
      (net 17 "PS_1V8") (pintype "passive"))
  )

  (footprint "kria-k26-devboard-footprints:C_0603_1608Metric" (layer "F.Cu")
    (at 79.115 90.9 180)
    (descr "Capacitor SMD 0603")
    (tags "capacitor 0603")
    (property "Author" "Antmicro")
    (property "License" "Apache-2.0")
    (property "MPN" "GRM188R61A106KE69D")
    (property "Manufacturer" "Murata")
    (property "Sheetfile" "camera.kicad_sch")
    (property "Sheetname" "Camera interface")
    (property "Val" "10u")
    (property "Voltage" "")
    (property "ki_description" " ")
    (attr smd)
    (fp_text reference "C247" (at 4.054 -0.375 180) (layer "F.SilkS")
        (effects (font (size 0.7 0.7) (thickness 0.15)) (justify left bottom))
    )
    (fp_text value "C_10u_0603" (at 0 1.6 180) (layer "F.Fab") hide
        (effects (font (size 0.7 0.7) (thickness 0.15)) (justify left bottom))
    )
    (fp_text user "License: Apache-2.0" (at -1.682 5.895 180) (layer "F.Fab") hide
        (effects (font (size 0.7 0.7) (thickness 0.15)) (justify left bottom))
    )
    (fp_text user "${REFERENCE}" (at -1.682 3.895 180) (layer "F.Fab") hide
        (effects (font (size 0.7 0.7) (thickness 0.15)) (justify left bottom))
    )
    (fp_text user "Author: Antmicro" (at -1.682 4.894 180) (layer "F.Fab") hide
        (effects (font (size 0.7 0.7) (thickness 0.15)) (justify left bottom))
    )
    (fp_line (start -0.3 -0.3) (end 0.3 -0.3)
      (stroke (width 0.15) (type solid)) (layer "F.SilkS"))
    (fp_line (start -0.3 0.3) (end 0.3 0.3)
      (stroke (width 0.15) (type solid)) (layer "F.SilkS"))
    (fp_rect (start -1.24 -0.7) (end 1.24 0.7)
      (stroke (width 0.05) (type solid)) (fill none) (layer "F.CrtYd"))
    (fp_rect (start -0.8 -0.4) (end 0.8 0.4)
      (stroke (width 0.15) (type solid)) (fill none) (layer "F.Fab"))
    (pad "1" smd roundrect (at -0.7 0 180) (size 0.6 0.8) (layers "F.Cu" "F.Paste" "F.Mask") (roundrect_rratio 0.2)
      (net 20 "PL_3V3") (pintype "passive"))
    (pad "2" smd roundrect (at 0.7 0 180) (size 0.6 0.8) (layers "F.Cu" "F.Paste" "F.Mask") (roundrect_rratio 0.2)
      (net 1 "GND") (pintype "passive"))
  )

  (footprint "kria-k26-devboard-footprints:TP_SMD_0.75mm" (layer "F.Cu")
    (at 81.55 102.9 180)
    (property "Author" "Antmicro")
    (property "License" "Apache-2.0")
    (property "MPN" "")
    (property "Manufacturer" "")
    (property "Sheetfile" "k26_som.kicad_sch")
    (property "Sheetname" "Xilinx K26 SOM")
    (property "ki_description" "Test Point 0.75mm")
    (attr exclude_from_pos_files)
    (fp_text reference "TP58" (at 3.36 -0.2808 180) (layer "F.SilkS")
        (effects (font (size 0.7 0.7) (thickness 0.15)) (justify left bottom))
    )
    (fp_text value "TP_0.75mm_SMD" (at 0 1.2 180) (layer "F.Fab") hide
        (effects (font (size 0.7 0.7) (thickness 0.15)) (justify left bottom))
    )
    (fp_text user "License: Apache-2.0" (at -0.4 5.101 180) (layer "F.Fab") hide
        (effects (font (size 0.7 0.7) (thickness 0.15)) (justify left bottom))
    )
    (fp_text user "${REFERENCE}" (at -0.4 2.7 180) (layer "F.Fab") hide
        (effects (font (size 0.7 0.7) (thickness 0.15)) (justify left bottom))
    )
    (fp_text user "Author: Antmicro" (at -0.4 3.901 180) (layer "F.Fab") hide
        (effects (font (size 0.7 0.7) (thickness 0.15)) (justify left bottom))
    )
    (pad "1" smd circle (at 0 0 180) (size 0.75 0.75) (layers "F.Cu" "F.Mask")
      (net 476 "/Xilinx K26 SOM/MIO26") (pinfunction "1") (pintype "passive"))
  )

  (footprint "kria-k26-devboard-footprints:SW_KMR211NGLFS_SMD" (layer "F.Cu")
    (at 83.65 150.1)
    (descr "KMR211G")
    (tags "SPST Button Switch")
    (property "Author" "Antmicro")
    (property "License" "Apache-2.0")
    (property "MPN" "KMR211NGLFS")
    (property "Manufacturer" "C&K")
    (property "Sheetfile" "k26_som.kicad_sch")
    (property "Sheetname" "Xilinx K26 SOM")
    (attr smd)
    (fp_text reference "S2" (at -2.75 -2.03) (layer "F.SilkS")
        (effects (font (size 0.7 0.7) (thickness 0.15)) (justify left bottom))
    )
    (fp_text value "SW_SPST_KMR211NGLFS" (at -3 3) (layer "F.Fab") hide
        (effects (font (size 0.7 0.7) (thickness 0.15)) (justify left bottom))
    )
    (fp_text user "License: Apache-2.0" (at -3 6.75) (layer "F.Fab") hide
        (effects (font (size 0.7 0.7) (thickness 0.15)) (justify left bottom))
    )
    (fp_text user "Author: Antmicro" (at -3 5.5) (layer "F.Fab") hide
        (effects (font (size 0.7 0.7) (thickness 0.15)) (justify left bottom))
    )
    (fp_text user "${REFERENCE}" (at -3 4.25) (layer "F.Fab") hide
        (effects (font (size 0.7 0.7) (thickness 0.15)) (justify left bottom))
    )
    (fp_line (start -2.101 -1.601) (end -2.101 -1.48)
      (stroke (width 0.15) (type solid)) (layer "F.SilkS"))
    (fp_line (start -2.101 -1.601) (end 2.1 -1.601)
      (stroke (width 0.15) (type solid)) (layer "F.SilkS"))
    (fp_line (start -2.101 1.58) (end -2.101 1.459)
      (stroke (width 0.15) (type solid)) (layer "F.SilkS"))
    (fp_line (start -2.101 1.6) (end 2.1 1.6)
      (stroke (width 0.15) (type solid)) (layer "F.SilkS"))
    (fp_line (start 2.1 -1.601) (end 2.1 -1.48)
      (stroke (width 0.15) (type solid)) (layer "F.SilkS"))
    (fp_line (start 2.1 1.6) (end 2.1 1.499)
      (stroke (width 0.15) (type solid)) (layer "F.SilkS"))
    (fp_rect (start -2.751 -1.75) (end 2.748 1.749)
      (stroke (width 0.05) (type solid)) (fill none) (layer "F.CrtYd"))
    (fp_line (start -2.101 -1.601) (end -2.101 1.6)
      (stroke (width 0.15) (type solid)) (layer "F.Fab"))
    (fp_line (start -2.101 1.6) (end 2.1 1.6)
      (stroke (width 0.15) (type solid)) (layer "F.Fab"))
    (fp_line (start -0.25 -0.802) (end 0.248 -0.802)
      (stroke (width 0.15) (type solid)) (layer "F.Fab"))
    (fp_line (start 0.248 0.8) (end -0.25 0.8)
      (stroke (width 0.15) (type solid)) (layer "F.Fab"))
    (fp_line (start 2.1 -1.601) (end -2.101 -1.601)
      (stroke (width 0.15) (type solid)) (layer "F.Fab"))
    (fp_line (start 2.1 1.6) (end 2.1 -1.601)
      (stroke (width 0.15) (type solid)) (layer "F.Fab"))
    (fp_arc (start -0.25 0.8) (mid -1.051001 -0.001) (end -0.25 -0.802)
      (stroke (width 0.15) (type solid)) (layer "F.Fab"))
    (fp_arc (start 0.248 -0.802) (mid 1.050001 -0.001) (end 0.248 0.8)
      (stroke (width 0.15) (type solid)) (layer "F.Fab"))
    (pad "1" smd rect (at 2.048 -0.802) (size 0.9 1) (layers "F.Cu" "F.Paste" "F.Mask")
      (net 1 "GND") (pintype "passive"))
    (pad "2" smd rect (at 2.048 0.8) (size 0.9 1) (layers "F.Cu" "F.Paste" "F.Mask")
      (net 467 "/Xilinx K26 SOM/MIO12_FWUEN_C2M_L") (pintype "passive"))
    (pad "3" smd rect (at -2.05 -0.802) (size 0.9 1) (layers "F.Cu" "F.Paste" "F.Mask")
      (net 1 "GND") (pintype "passive"))
    (pad "4" smd rect (at -2.05 0.8) (size 0.9 1) (layers "F.Cu" "F.Paste" "F.Mask")
      (net 467 "/Xilinx K26 SOM/MIO12_FWUEN_C2M_L") (pintype "passive"))
  )

  (footprint "kria-k26-devboard-footprints:Fiducial_1mm_Mask2mm" (layer "F.Cu")
    (at 182.9 149.2)
    (descr "Circular Fiducial, 1mm bare copper, 3mm soldermask opening")
    (tags "fiducial")
    (attr smd board_only exclude_from_bom)
    (fp_text reference "FID2" (at 0 -2.4765) (layer "F.SilkS")
        (effects (font (size 1 1) (thickness 0.15)))
    )
    (fp_text value "Fiducial_1mm_Mask2mm" (at 0 2.6035) (layer "F.Fab") hide
        (effects (font (size 1 1) (thickness 0.15)))
    )
    (fp_text user "${REFERENCE}" (at 0 0) (layer "F.Fab")
        (effects (font (size 0.4 0.4) (thickness 0.06)))
    )
    (fp_text user "License: Apache-2.0" (at -1.25 7.003) (layer "F.Fab") hide
        (effects (font (size 0.7 0.7) (thickness 0.15)) (justify left bottom))
    )
    (fp_text user "Author: Antmicro" (at -1.25 5.803) (layer "F.Fab") hide
        (effects (font (size 0.7 0.7) (thickness 0.15)) (justify left bottom))
    )
    (fp_circle (center 0 0) (end 1.24 0)
      (stroke (width 0.05) (type solid)) (fill none) (layer "F.CrtYd"))
    (fp_circle (center 0 0) (end 0.999 0)
      (stroke (width 0.15) (type solid)) (fill none) (layer "F.Fab"))
    (pad "" smd circle (at 0 0) (size 1 1) (layers "F.Cu" "F.Mask")
      (solder_mask_margin 0.5) (clearance 0.5))
  )

  (footprint "kria-k26-devboard-footprints:Fiducial_1mm_Mask2mm" (layer "F.Cu")
    (at 83.69 144.37)
    (descr "Circular Fiducial, 1mm bare copper, 3mm soldermask opening")
    (tags "fiducial")
    (attr smd board_only exclude_from_bom)
    (fp_text reference "FID1" (at -0.02 -1.9) (layer "F.SilkS")
        (effects (font (size 1 1) (thickness 0.15)))
    )
    (fp_text value "Fiducial_1mm_Mask2mm" (at 0 2.6035) (layer "F.Fab") hide
        (effects (font (size 1 1) (thickness 0.15)))
    )
    (fp_text user "${REFERENCE}" (at 0 0) (layer "F.Fab")
        (effects (font (size 0.4 0.4) (thickness 0.06)))
    )
    (fp_text user "License: Apache-2.0" (at -1.25 7.003) (layer "F.Fab") hide
        (effects (font (size 0.7 0.7) (thickness 0.15)) (justify left bottom))
    )
    (fp_text user "Author: Antmicro" (at -1.25 5.803) (layer "F.Fab") hide
        (effects (font (size 0.7 0.7) (thickness 0.15)) (justify left bottom))
    )
    (fp_circle (center 0 0) (end 1.24 0)
      (stroke (width 0.05) (type solid)) (fill none) (layer "F.CrtYd"))
    (fp_circle (center 0 0) (end 0.999 0)
      (stroke (width 0.15) (type solid)) (fill none) (layer "F.Fab"))
    (pad "" smd circle (at 0 0) (size 1 1) (layers "F.Cu" "F.Mask")
      (solder_mask_margin 0.5) (clearance 0.5))
  )

  (footprint "kria-k26-devboard-footprints:R_0603_1608Metric" (layer "F.Cu")
    (at 166.7 138.8 180)
    (descr "Resistor SMD 0603")
    (tags "resistor SMD 0603")
    (property "Author" "Antmicro")
    (property "License" "Apache-2.0")
    (property "MPN" "PMR03EZPJ000")
    (property "Manufacturer" "ROHM Semiconductor")
    (property "Max. Curr." "22.4A")
    (property "Sheetfile" "dc-dc-conventers.kicad_sch")
    (property "Sheetname" "DC/DC conventers")
    (property "Val" "0R")
    (property "ki_description" "Metal strip 0Ohm jumper 22.4A")
    (property "ki_keywords" "Metal strip 0Ohm jumper 22.4A high power hpwr current")
    (attr smd)
    (fp_text reference "R162" (at 2.12 -1.38 180) (layer "F.SilkS")
        (effects (font (size 0.7 0.7) (thickness 0.15)) (justify left bottom))
    )
    (fp_text value "R_0R_22.4A_0603" (at 0 1.6 180) (layer "F.Fab") hide
        (effects (font (size 0.7 0.7) (thickness 0.15)) (justify left bottom))
    )
    (fp_text user "License: Apache-2.0" (at -1.25 5.9 180) (layer "F.Fab") hide
        (effects (font (size 0.7 0.7) (thickness 0.15)) (justify left bottom))
    )
    (fp_text user "Author: Antmicro" (at -1.25 4.9 180) (layer "F.Fab") hide
        (effects (font (size 0.7 0.7) (thickness 0.15)) (justify left bottom))
    )
    (fp_text user "${REFERENCE}" (at -1.25 3.898 180) (layer "F.Fab") hide
        (effects (font (size 0.7 0.7) (thickness 0.15)) (justify left bottom))
    )
    (fp_line (start -0.3 -0.3) (end 0.3 -0.3)
      (stroke (width 0.15) (type solid)) (layer "F.SilkS"))
    (fp_line (start -0.3 0.3) (end 0.3 0.3)
      (stroke (width 0.15) (type solid)) (layer "F.SilkS"))
    (fp_rect (start -1.25 -0.7) (end 1.25 0.7)
      (stroke (width 0.05) (type solid)) (fill none) (layer "F.CrtYd"))
    (fp_rect (start -0.8 -0.4) (end 0.8 0.4)
      (stroke (width 0.15) (type solid)) (fill none) (layer "F.Fab"))
    (pad "1" smd roundrect (at -0.7 0 180) (size 0.6 0.8) (layers "F.Cu" "F.Paste" "F.Mask") (roundrect_rratio 0.2)
      (net 765 "/Power Supply/DC/DC conventers/PS_3V3_OUT") (pintype "passive"))
    (pad "2" smd roundrect (at 0.7 0 180) (size 0.6 0.8) (layers "F.Cu" "F.Paste" "F.Mask") (roundrect_rratio 0.2)
      (net 15 "PS_3V3") (pintype "passive"))
  )

  (footprint "kria-k26-devboard-footprints:C_0402_1005Metric" (layer "F.Cu")
    (at 79.425 89.6 180)
    (descr "Capacitor SMD 0402")
    (tags "capacitor SMD 0402")
    (property "Author" "Antmicro")
    (property "Dielectric" "X5R")
    (property "License" "Apache-2.0")
    (property "MPN" "GRM155R61H104KE14D")
    (property "Manufacturer" "Murata")
    (property "Sheetfile" "camera.kicad_sch")
    (property "Sheetname" "Camera interface")
    (property "Val" "100n")
    (property "Voltage" "50V")
    (property "ki_description" " ")
    (attr smd)
    (fp_text reference "C244" (at 3.845 -0.37 180) (layer "F.SilkS")
        (effects (font (size 0.7 0.7) (thickness 0.15)) (justify left bottom))
    )
    (fp_text value "C_100n_0402" (at 0 1.4 180) (layer "F.Fab") hide
        (effects (font (size 0.7 0.7) (thickness 0.15)) (justify left bottom))
    )
    (fp_text user "Author: Antmicro" (at -0.932 4.17 180) (layer "F.Fab") hide
        (effects (font (size 0.7 0.7) (thickness 0.15)) (justify left bottom))
    )
    (fp_text user "${REFERENCE}" (at -0.932 3.168 180) (layer "F.Fab") hide
        (effects (font (size 0.7 0.7) (thickness 0.15)) (justify left bottom))
    )
    (fp_text user "License: Apache-2.0" (at -0.932 5.17 180) (layer "F.Fab") hide
        (effects (font (size 0.7 0.7) (thickness 0.15)) (justify left bottom))
    )
    (fp_rect (start -0.94 -0.47) (end 0.94 0.47)
      (stroke (width 0.05) (type solid)) (fill none) (layer "F.CrtYd"))
    (fp_rect (start -0.499 -0.249) (end 0.499 0.249)
      (stroke (width 0.15) (type solid)) (fill none) (layer "F.Fab"))
    (pad "1" smd roundrect (at -0.484 0 180) (size 0.59 0.64) (layers "F.Cu" "F.Paste" "F.Mask") (roundrect_rratio 0.25)
      (net 8 "SOM_5V0") (pintype "passive"))
    (pad "2" smd roundrect (at 0.484 0 180) (size 0.59 0.64) (layers "F.Cu" "F.Paste" "F.Mask") (roundrect_rratio 0.25)
      (net 1 "GND") (pintype "passive"))
  )

  (footprint "kria-k26-devboard-footprints:R_0603_1608Metric" (layer "F.Cu")
    (at 191.2 138.4 -90)
    (descr "Resistor SMD 0603")
    (tags "resistor SMD 0603")
    (property "Author" "Antmicro")
    (property "License" "Apache-2.0")
    (property "MPN" "PMR03EZPJ000")
    (property "Manufacturer" "ROHM Semiconductor")
    (property "Max. Curr." "22.4A")
    (property "Sheetfile" "dc-dc-conventers.kicad_sch")
    (property "Sheetname" "DC/DC conventers")
    (property "Val" "0R")
    (property "ki_description" "Metal strip 0Ohm jumper 22.4A")
    (property "ki_keywords" "Metal strip 0Ohm jumper 22.4A high power hpwr current")
    (attr smd)
    (fp_text reference "R159" (at 6.82 -0.35 -90) (layer "F.SilkS")
        (effects (font (size 0.7 0.7) (thickness 0.15)) (justify left bottom))
    )
    (fp_text value "R_0R_22.4A_0603" (at 0 1.6 -90) (layer "F.Fab") hide
        (effects (font (size 0.7 0.7) (thickness 0.15)) (justify left bottom))
    )
    (fp_text user "License: Apache-2.0" (at -1.25 5.9 -90) (layer "F.Fab") hide
        (effects (font (size 0.7 0.7) (thickness 0.15)) (justify left bottom))
    )
    (fp_text user "${REFERENCE}" (at -1.25 3.898 -90) (layer "F.Fab") hide
        (effects (font (size 0.7 0.7) (thickness 0.15)) (justify left bottom))
    )
    (fp_text user "Author: Antmicro" (at -1.25 4.9 -90) (layer "F.Fab") hide
        (effects (font (size 0.7 0.7) (thickness 0.15)) (justify left bottom))
    )
    (fp_line (start -0.3 -0.3) (end 0.3 -0.3)
      (stroke (width 0.15) (type solid)) (layer "F.SilkS"))
    (fp_line (start -0.3 0.3) (end 0.3 0.3)
      (stroke (width 0.15) (type solid)) (layer "F.SilkS"))
    (fp_rect (start -1.25 -0.7) (end 1.25 0.7)
      (stroke (width 0.05) (type solid)) (fill none) (layer "F.CrtYd"))
    (fp_rect (start -0.8 -0.4) (end 0.8 0.4)
      (stroke (width 0.15) (type solid)) (fill none) (layer "F.Fab"))
    (pad "1" smd roundrect (at -0.7 0 270) (size 0.6 0.8) (layers "F.Cu" "F.Paste" "F.Mask") (roundrect_rratio 0.2)
      (net 771 "/Power Supply/DC/DC conventers/PL_1V2_OUT") (pintype "passive"))
    (pad "2" smd roundrect (at 0.7 0 270) (size 0.6 0.8) (layers "F.Cu" "F.Paste" "F.Mask") (roundrect_rratio 0.2)
      (net 21 "PL_1V2") (pintype "passive"))
  )

  (footprint "kria-k26-devboard-footprints:R_0402_1005Metric" (layer "F.Cu")
    (at 111.945 91.22 180)
    (descr "Resistor SMD 0402")
    (tags "resistor SMD 0402")
    (property "Author" "Antmicro")
    (property "License" "Apache-2.0")
    (property "MPN" "CR0402-FX-2003GLF")
    (property "Manufacturer" "Bourns")
    (property "Sheetfile" "usb.kicad_sch")
    (property "Sheetname" "USB")
    (property "Tolerance" "1%")
    (property "Val" "200k")
    (property "ki_description" "200k resistor in 0402 package with 1% tolerance")
    (attr smd)
    (fp_text reference "R172" (at 3.705 -0.35 180) (layer "F.SilkS")
        (effects (font (size 0.7 0.7) (thickness 0.15)) (justify left bottom))
    )
    (fp_text value "R_200k_0402" (at 0 1.4 180) (layer "F.Fab") hide
        (effects (font (size 0.7 0.7) (thickness 0.15)) (justify left bottom))
    )
    (fp_text user "License: Apache-2.0" (at -0.95 5.169 180) (layer "F.Fab") hide
        (effects (font (size 0.7 0.7) (thickness 0.15)) (justify left bottom))
    )
    (fp_text user "${REFERENCE}" (at -0.95 3.168 180) (layer "F.Fab") hide
        (effects (font (size 0.7 0.7) (thickness 0.15)) (justify left bottom))
    )
    (fp_text user "Author: Antmicro" (at -0.95 4.169 180) (layer "F.Fab") hide
        (effects (font (size 0.7 0.7) (thickness 0.15)) (justify left bottom))
    )
    (fp_rect (start -0.93 -0.47) (end 0.93 0.47)
      (stroke (width 0.05) (type solid)) (fill none) (layer "F.CrtYd"))
    (fp_rect (start -0.5 -0.25) (end 0.5 0.25)
      (stroke (width 0.15) (type solid)) (fill none) (layer "F.Fab"))
    (pad "1" smd roundrect (at -0.485 0 180) (size 0.59 0.64) (layers "F.Cu" "F.Paste" "F.Mask") (roundrect_rratio 0.25)
      (net 666 "Net-(U17-PF26)") (pintype "passive"))
    (pad "2" smd roundrect (at 0.485 0 180) (size 0.59 0.64) (layers "F.Cu" "F.Paste" "F.Mask") (roundrect_rratio 0.25)
      (net 1 "GND") (pintype "passive"))
  )

  (footprint "kria-k26-devboard-footprints:WSON-6-1EP_2x2mm_P0.65mm" (layer "F.Cu")
    (at 151.9 107.9 90)
    (property "Author" "Antmicro")
    (property "License" "Apache-2.0")
    (property "MPN" "NCP730BMT330TBG")
    (property "Manufacturer" "ON Semiconductor")
    (property "Sheetfile" "debug.kicad_sch")
    (property "Sheetname" "Debug and JTAG")
    (property "ki_description" "Linear Voltage Regulator IC Positive Fixed 1 Output 150mA 6-WDFN (2x2)")
    (property "ki_keywords" "SMT, PMIC, IC, LDO, VOLTAGE, REGULATOR")
    (attr smd)
    (fp_text reference "U61" (at 1.56 -1.11 180) (layer "F.SilkS")
        (effects (font (size 0.7 0.7) (thickness 0.15)) (justify left bottom))
    )
    (fp_text value "NCP730BMT330_WSON" (at 0 2.2 90) (layer "F.Fab") hide
        (effects (font (size 0.7 0.7) (thickness 0.15)) (justify left bottom))
    )
    (fp_text user "License: Apache-2.0" (at -1.01 6.4 90) (layer "F.Fab") hide
        (effects (font (size 0.7 0.7) (thickness 0.15)) (justify left bottom))
    )
    (fp_text user "${REFERENCE}" (at -1.01 3.999 90) (layer "F.Fab") hide
        (effects (font (size 0.7 0.7) (thickness 0.15)) (justify left bottom))
    )
    (fp_text user "Author: Antmicro" (at -1.01 5.2 90) (layer "F.Fab") hide
        (effects (font (size 0.7 0.7) (thickness 0.15)) (justify left bottom))
    )
    (fp_line (start -1 1) (end 1 1)
      (stroke (width 0.12) (type solid)) (layer "F.SilkS"))
    (fp_line (start 1 -1) (end -1.05 -1)
      (stroke (width 0.12) (type solid)) (layer "F.SilkS"))
    (fp_circle (center -1.275 -1.075) (end -1.224 -1.075)
      (stroke (width 0.15) (type solid)) (fill solid) (layer "F.SilkS"))
    (fp_rect (start -1.45 -1.25) (end 1.45 1.25)
      (stroke (width 0.05) (type solid)) (fill none) (layer "F.CrtYd"))
    (pad "1" smd roundrect (at -0.975 -0.652 90) (size 0.45 0.4) (layers "F.Cu" "F.Paste" "F.Mask") (roundrect_rratio 0.25)
      (net 187 "/Debug and JTAG/PD_3V3") (pinfunction "V_{OUT}") (pintype "power_out"))
    (pad "2" smd roundrect (at -0.975 0 90) (size 0.45 0.4) (layers "F.Cu" "F.Paste" "F.Mask") (roundrect_rratio 0.25)
      (net 794 "unconnected-(U61-NC-Pad2)") (pinfunction "NC") (pintype "no_connect"))
    (pad "3" smd roundrect (at -0.975 0.65 90) (size 0.45 0.4) (layers "F.Cu" "F.Paste" "F.Mask") (roundrect_rratio 0.25)
      (net 1 "GND") (pinfunction "GND") (pintype "power_in"))
    (pad "4" smd roundrect (at 0.973 0.65 90) (size 0.45 0.4) (layers "F.Cu" "F.Paste" "F.Mask") (roundrect_rratio 0.25)
      (net 313 "/Debug and JTAG/USB_VBUS") (pinfunction "EN") (pintype "input"))
    (pad "5" smd roundrect (at 0.973 0 90) (size 0.45 0.4) (layers "F.Cu" "F.Paste" "F.Mask") (roundrect_rratio 0.25)
      (net 795 "unconnected-(U61-PG-Pad5)") (pinfunction "PG") (pintype "open_collector+no_connect"))
    (pad "6" smd roundrect (at 0.973 -0.652 90) (size 0.45 0.4) (layers "F.Cu" "F.Paste" "F.Mask") (roundrect_rratio 0.25)
      (net 313 "/Debug and JTAG/USB_VBUS") (pinfunction "V_{IN}") (pintype "power_in"))
    (pad "7" smd roundrect (at 0 0 90) (size 1.12 1.72) (layers "F.Cu" "F.Paste" "F.Mask") (roundrect_rratio 0.1)
      (net 1 "GND") (pinfunction "GND") (pintype "passive"))
  )

  (footprint "kria-k26-devboard-footprints:R_0603_1608Metric" (layer "F.Cu")
    (at 164.625 128.2 90)
    (descr "Resistor SMD 0603")
    (tags "resistor SMD 0603")
    (property "Author" "Antmicro")
    (property "License" "Apache-2.0")
    (property "MPN" "PMR03EZPJ000")
    (property "Manufacturer" "ROHM Semiconductor")
    (property "Max. Curr." "22.4A")
    (property "Sheetfile" "dc-dc-conventers.kicad_sch")
    (property "Sheetname" "DC/DC conventers")
    (property "Val" "0R")
    (property "ki_description" "Metal strip 0Ohm jumper 22.4A")
    (property "ki_keywords" "Metal strip 0Ohm jumper 22.4A high power hpwr current")
    (attr smd)
    (fp_text reference "R161" (at -3.73 -0.295 90) (layer "F.SilkS")
        (effects (font (size 0.7 0.7) (thickness 0.15)) (justify left bottom))
    )
    (fp_text value "R_0R_22.4A_0603" (at 0 1.6 90) (layer "F.Fab") hide
        (effects (font (size 0.7 0.7) (thickness 0.15)) (justify left bottom))
    )
    (fp_text user "${REFERENCE}" (at -1.25 3.898 90) (layer "F.Fab") hide
        (effects (font (size 0.7 0.7) (thickness 0.15)) (justify left bottom))
    )
    (fp_text user "License: Apache-2.0" (at -1.25 5.9 90) (layer "F.Fab") hide
        (effects (font (size 0.7 0.7) (thickness 0.15)) (justify left bottom))
    )
    (fp_text user "Author: Antmicro" (at -1.25 4.9 90) (layer "F.Fab") hide
        (effects (font (size 0.7 0.7) (thickness 0.15)) (justify left bottom))
    )
    (fp_line (start -0.3 -0.3) (end 0.3 -0.3)
      (stroke (width 0.15) (type solid)) (layer "F.SilkS"))
    (fp_line (start -0.3 0.3) (end 0.3 0.3)
      (stroke (width 0.15) (type solid)) (layer "F.SilkS"))
    (fp_rect (start -1.25 -0.7) (end 1.25 0.7)
      (stroke (width 0.05) (type solid)) (fill none) (layer "F.CrtYd"))
    (fp_rect (start -0.8 -0.4) (end 0.8 0.4)
      (stroke (width 0.15) (type solid)) (fill none) (layer "F.Fab"))
    (pad "1" smd roundrect (at -0.7 0 90) (size 0.6 0.8) (layers "F.Cu" "F.Paste" "F.Mask") (roundrect_rratio 0.2)
      (net 773 "/Power Supply/DC/DC conventers/SOM_5V_OUT") (pintype "passive"))
    (pad "2" smd roundrect (at 0.7 0 90) (size 0.6 0.8) (layers "F.Cu" "F.Paste" "F.Mask") (roundrect_rratio 0.2)
      (net 8 "SOM_5V0") (pintype "passive"))
  )

  (footprint "kria-k26-devboard-footprints:R_0402_1005Metric" (layer "F.Cu")
    (at 146.05 142.425 90)
    (descr "Resistor SMD 0402")
    (tags "resistor SMD 0402")
    (property "Author" "Antmicro")
    (property "License" "Apache-2.0")
    (property "MPN" "CR0402-FX-5111GLF")
    (property "Manufacturer" "Bourns")
    (property "Sheetfile" "debug.kicad_sch")
    (property "Sheetname" "Debug and JTAG")
    (property "Tolerance" "1%")
    (property "Val" "5k11")
    (property "ki_description" "5k11 resistor in 0402 package with 1% tolerance")
    (attr smd)
    (fp_text reference "R167" (at 0.945 0.37 90) (layer "F.SilkS")
        (effects (font (size 0.7 0.7) (thickness 0.15)) (justify left bottom))
    )
    (fp_text value "R_5k11_0402" (at 0 1.4 90) (layer "F.Fab") hide
        (effects (font (size 0.7 0.7) (thickness 0.15)) (justify left bottom))
    )
    (fp_text user "License: Apache-2.0" (at -0.95 5.169 90) (layer "F.Fab") hide
        (effects (font (size 0.7 0.7) (thickness 0.15)) (justify left bottom))
    )
    (fp_text user "Author: Antmicro" (at -0.95 4.169 90) (layer "F.Fab") hide
        (effects (font (size 0.7 0.7) (thickness 0.15)) (justify left bottom))
    )
    (fp_text user "${REFERENCE}" (at -0.95 3.168 90) (layer "F.Fab") hide
        (effects (font (size 0.7 0.7) (thickness 0.15)) (justify left bottom))
    )
    (fp_rect (start -0.93 -0.47) (end 0.93 0.47)
      (stroke (width 0.05) (type solid)) (fill none) (layer "F.CrtYd"))
    (fp_rect (start -0.5 -0.25) (end 0.5 0.25)
      (stroke (width 0.15) (type solid)) (fill none) (layer "F.Fab"))
    (pad "1" smd roundrect (at -0.485 0 90) (size 0.59 0.64) (layers "F.Cu" "F.Paste" "F.Mask") (roundrect_rratio 0.25)
      (net 358 "Net-(J8-CC_{2})") (pintype "passive"))
    (pad "2" smd roundrect (at 0.485 0 90) (size 0.59 0.64) (layers "F.Cu" "F.Paste" "F.Mask") (roundrect_rratio 0.25)
      (net 1 "GND") (pintype "passive"))
  )

  (footprint "kria-k26-devboard-footprints:TP_SMD_0.75mm" (layer "F.Cu")
    (at 81.55 106.95 180)
    (property "Author" "Antmicro")
    (property "License" "Apache-2.0")
    (property "MPN" "")
    (property "Manufacturer" "")
    (property "Sheetfile" "k26_som.kicad_sch")
    (property "Sheetname" "Xilinx K26 SOM")
    (property "ki_description" "Test Point 0.75mm")
    (attr exclude_from_pos_files)
    (fp_text reference "TP57" (at 3.36 -0.2808 180) (layer "F.SilkS")
        (effects (font (size 0.7 0.7) (thickness 0.15)) (justify left bottom))
    )
    (fp_text value "TP_0.75mm_SMD" (at 0 1.2 180) (layer "F.Fab") hide
        (effects (font (size 0.7 0.7) (thickness 0.15)) (justify left bottom))
    )
    (fp_text user "License: Apache-2.0" (at -0.4 5.101 180) (layer "F.Fab") hide
        (effects (font (size 0.7 0.7) (thickness 0.15)) (justify left bottom))
    )
    (fp_text user "${REFERENCE}" (at -0.4 2.7 180) (layer "F.Fab") hide
        (effects (font (size 0.7 0.7) (thickness 0.15)) (justify left bottom))
    )
    (fp_text user "Author: Antmicro" (at -0.4 3.901 180) (layer "F.Fab") hide
        (effects (font (size 0.7 0.7) (thickness 0.15)) (justify left bottom))
    )
    (pad "1" smd circle (at 0 0 180) (size 0.75 0.75) (layers "F.Cu" "F.Mask")
      (net 475 "/Xilinx K26 SOM/PWR_GD_PL_M2C") (pinfunction "1") (pintype "passive"))
  )

  (footprint "kria-k26-devboard-footprints:TP_SMD_0.75mm" (layer "F.Cu")
    (at 155.7492 150.8 -90)
    (property "Author" "Antmicro")
    (property "License" "Apache-2.0")
    (property "MPN" "")
    (property "Manufacturer" "")
    (property "Sheetfile" "debug.kicad_sch")
    (property "Sheetname" "Debug and JTAG")
    (property "ki_description" "Test Point 0.75mm")
    (attr exclude_from_pos_files)
    (fp_text reference "TP65" (at -0.47 -0.4308 -90) (layer "F.SilkS")
        (effects (font (size 0.7 0.7) (thickness 0.15)) (justify left bottom))
    )
    (fp_text value "TP_0.75mm_SMD" (at 0 1.2 -90) (layer "F.Fab") hide
        (effects (font (size 0.7 0.7) (thickness 0.15)) (justify left bottom))
    )
    (fp_text user "${REFERENCE}" (at -0.4 2.7 -90) (layer "F.Fab") hide
        (effects (font (size 0.7 0.7) (thickness 0.15)) (justify left bottom))
    )
    (fp_text user "License: Apache-2.0" (at -0.4 5.101 -90) (layer "F.Fab") hide
        (effects (font (size 0.7 0.7) (thickness 0.15)) (justify left bottom))
    )
    (fp_text user "Author: Antmicro" (at -0.4 3.901 -90) (layer "F.Fab") hide
        (effects (font (size 0.7 0.7) (thickness 0.15)) (justify left bottom))
    )
    (pad "1" smd circle (at 0 0 270) (size 0.75 0.75) (layers "F.Cu" "F.Mask")
      (net 1 "GND") (pinfunction "1") (pintype "passive"))
  )

  (footprint "kria-k26-devboard-footprints:R_0603_1608Metric" (layer "F.Cu")
    (at 181.5 137.9)
    (descr "Resistor SMD 0603")
    (tags "resistor SMD 0603")
    (property "Author" "Antmicro")
    (property "License" "Apache-2.0")
    (property "MPN" "PMR03EZPJ000")
    (property "Manufacturer" "ROHM Semiconductor")
    (property "Max. Curr." "22.4A")
    (property "Sheetfile" "dc-dc-conventers.kicad_sch")
    (property "Sheetname" "DC/DC conventers")
    (property "Val" "0R")
    (property "ki_description" "Metal strip 0Ohm jumper 22.4A")
    (property "ki_keywords" "Metal strip 0Ohm jumper 22.4A high power hpwr current")
    (attr smd)
    (fp_text reference "R158" (at -1.09 2.98 90) (layer "F.SilkS")
        (effects (font (size 0.7 0.7) (thickness 0.15)) (justify left bottom))
    )
    (fp_text value "R_0R_22.4A_0603" (at 0 1.6) (layer "F.Fab") hide
        (effects (font (size 0.7 0.7) (thickness 0.15)) (justify left bottom))
    )
    (fp_text user "${REFERENCE}" (at -1.25 3.898) (layer "F.Fab") hide
        (effects (font (size 0.7 0.7) (thickness 0.15)) (justify left bottom))
    )
    (fp_text user "License: Apache-2.0" (at -1.25 5.9) (layer "F.Fab") hide
        (effects (font (size 0.7 0.7) (thickness 0.15)) (justify left bottom))
    )
    (fp_text user "Author: Antmicro" (at -1.25 4.9) (layer "F.Fab") hide
        (effects (font (size 0.7 0.7) (thickness 0.15)) (justify left bottom))
    )
    (fp_line (start -0.3 -0.3) (end 0.3 -0.3)
      (stroke (width 0.15) (type solid)) (layer "F.SilkS"))
    (fp_line (start -0.3 0.3) (end 0.3 0.3)
      (stroke (width 0.15) (type solid)) (layer "F.SilkS"))
    (fp_rect (start -1.25 -0.7) (end 1.25 0.7)
      (stroke (width 0.05) (type solid)) (fill none) (layer "F.CrtYd"))
    (fp_rect (start -0.8 -0.4) (end 0.8 0.4)
      (stroke (width 0.15) (type solid)) (fill none) (layer "F.Fab"))
    (pad "1" smd roundrect (at -0.7 0) (size 0.6 0.8) (layers "F.Cu" "F.Paste" "F.Mask") (roundrect_rratio 0.2)
      (net 770 "/Power Supply/DC/DC conventers/PL_3V3_OUT") (pintype "passive"))
    (pad "2" smd roundrect (at 0.7 0) (size 0.6 0.8) (layers "F.Cu" "F.Paste" "F.Mask") (roundrect_rratio 0.2)
      (net 20 "PL_3V3") (pintype "passive"))
  )

  (footprint "kria-k26-devboard-footprints:R_0402_1005Metric" (layer "F.Cu")
    (at 139.75 138)
    (descr "Resistor SMD 0402")
    (tags "resistor SMD 0402")
    (property "Author" "Antmicro")
    (property "License" "Apache-2.0")
    (property "MPN" "CR0402-FX-1002GLF")
    (property "Manufacturer" "Bourns")
    (property "Sheetfile" "sd-3-card.kicad_sch")
    (property "Sheetname" "SD 3.0 card")
    (property "Tolerance" "1%")
    (property "Val" "10k")
    (property "ki_description" "10k resistor in 0402 package with 1% tolerance")
    (attr smd)
    (fp_text reference "R168" (at -0.09 1.18) (layer "F.SilkS")
        (effects (font (size 0.7 0.7) (thickness 0.15)) (justify left bottom))
    )
    (fp_text value "R_10k_0402" (at 0 1.4) (layer "F.Fab") hide
        (effects (font (size 0.7 0.7) (thickness 0.15)) (justify left bottom))
    )
    (fp_text user "License: Apache-2.0" (at -0.95 5.169) (layer "F.Fab") hide
        (effects (font (size 0.7 0.7) (thickness 0.15)) (justify left bottom))
    )
    (fp_text user "${REFERENCE}" (at -0.95 3.168) (layer "F.Fab") hide
        (effects (font (size 0.7 0.7) (thickness 0.15)) (justify left bottom))
    )
    (fp_text user "Author: Antmicro" (at -0.95 4.169) (layer "F.Fab") hide
        (effects (font (size 0.7 0.7) (thickness 0.15)) (justify left bottom))
    )
    (fp_rect (start -0.93 -0.47) (end 0.93 0.47)
      (stroke (width 0.05) (type solid)) (fill none) (layer "F.CrtYd"))
    (fp_rect (start -0.5 -0.25) (end 0.5 0.25)
      (stroke (width 0.15) (type solid)) (fill none) (layer "F.Fab"))
    (pad "1" smd roundrect (at -0.485 0) (size 0.59 0.64) (layers "F.Cu" "F.Paste" "F.Mask") (roundrect_rratio 0.25)
      (net 695 "Net-(U6-ST)") (pintype "passive"))
    (pad "2" smd roundrect (at 0.485 0) (size 0.59 0.64) (layers "F.Cu" "F.Paste" "F.Mask") (roundrect_rratio 0.25)
      (net 17 "PS_1V8") (pintype "passive"))
  )

  (footprint "kria-k26-devboard-footprints:R_0402_1005Metric" (layer "F.Cu")
    (at 174.82 127.73 90)
    (descr "Resistor SMD 0402")
    (tags "resistor SMD 0402")
    (property "Author" "Antmicro")
    (property "License" "Apache-2.0")
    (property "MPN" "CR0402-FX-1473GLF")
    (property "Manufacturer" "Bourns")
    (property "Sheetfile" "dc-dc-conventers.kicad_sch")
    (property "Sheetname" "DC/DC conventers")
    (property "Tolerance" "1%")
    (property "Val" "147k")
    (property "ki_description" "147k resistor in 0402 package with 1% tolerance")
    (attr smd)
    (fp_text reference "R124" (at -1.37 -2.6 90) (layer "F.SilkS")
        (effects (font (size 0.7 0.7) (thickness 0.15)) (justify left bottom))
    )
    (fp_text value "R_147k_0402" (at 0 1.4 90) (layer "F.Fab") hide
        (effects (font (size 0.7 0.7) (thickness 0.15)) (justify left bottom))
    )
    (fp_text user "Author: Antmicro" (at -0.95 4.169 90) (layer "F.Fab") hide
        (effects (font (size 0.7 0.7) (thickness 0.15)) (justify left bottom))
    )
    (fp_text user "License: Apache-2.0" (at -0.95 5.169 90) (layer "F.Fab") hide
        (effects (font (size 0.7 0.7) (thickness 0.15)) (justify left bottom))
    )
    (fp_text user "${REFERENCE}" (at -0.95 3.168 90) (layer "F.Fab") hide
        (effects (font (size 0.7 0.7) (thickness 0.15)) (justify left bottom))
    )
    (fp_rect (start -0.93 -0.47) (end 0.93 0.47)
      (stroke (width 0.05) (type solid)) (fill none) (layer "F.CrtYd"))
    (fp_rect (start -0.5 -0.25) (end 0.5 0.25)
      (stroke (width 0.15) (type solid)) (fill none) (layer "F.Fab"))
    (pad "1" smd roundrect (at -0.485 0 90) (size 0.59 0.64) (layers "F.Cu" "F.Paste" "F.Mask") (roundrect_rratio 0.25)
      (net 774 "/Power Supply/DC/DC conventers/SOM_5V_FB") (pintype "passive"))
    (pad "2" smd roundrect (at 0.485 0 90) (size 0.59 0.64) (layers "F.Cu" "F.Paste" "F.Mask") (roundrect_rratio 0.25)
      (net 255 "Net-(U48-FB)") (pintype "passive"))
  )

  (footprint "kria-k26-devboard-footprints:R_0603_1608Metric" (layer "F.Cu")
    (at 166.1 115.4 180)
    (descr "Resistor SMD 0603")
    (tags "resistor SMD 0603")
    (property "Author" "Antmicro")
    (property "License" "Apache-2.0")
    (property "MPN" "PMR03EZPJ000")
    (property "Manufacturer" "ROHM Semiconductor")
    (property "Max. Curr." "22.4A")
    (property "Sheetfile" "dc-dc-conventers.kicad_sch")
    (property "Sheetname" "DC/DC conventers")
    (property "Val" "0R")
    (property "ki_description" "Metal strip 0Ohm jumper 22.4A")
    (property "ki_keywords" "Metal strip 0Ohm jumper 22.4A high power hpwr current")
    (attr smd)
    (fp_text reference "R156" (at 1.46 -0.88 270) (layer "F.SilkS")
        (effects (font (size 0.7 0.7) (thickness 0.15)) (justify left bottom))
    )
    (fp_text value "R_0R_22.4A_0603" (at 0 1.6 180) (layer "F.Fab") hide
        (effects (font (size 0.7 0.7) (thickness 0.15)) (justify left bottom))
    )
    (fp_text user "${REFERENCE}" (at -1.25 3.898 180) (layer "F.Fab") hide
        (effects (font (size 0.7 0.7) (thickness 0.15)) (justify left bottom))
    )
    (fp_text user "License: Apache-2.0" (at -1.25 5.9 180) (layer "F.Fab") hide
        (effects (font (size 0.7 0.7) (thickness 0.15)) (justify left bottom))
    )
    (fp_text user "Author: Antmicro" (at -1.25 4.9 180) (layer "F.Fab") hide
        (effects (font (size 0.7 0.7) (thickness 0.15)) (justify left bottom))
    )
    (fp_line (start -0.3 -0.3) (end 0.3 -0.3)
      (stroke (width 0.15) (type solid)) (layer "F.SilkS"))
    (fp_line (start -0.3 0.3) (end 0.3 0.3)
      (stroke (width 0.15) (type solid)) (layer "F.SilkS"))
    (fp_rect (start -1.25 -0.7) (end 1.25 0.7)
      (stroke (width 0.05) (type solid)) (fill none) (layer "F.CrtYd"))
    (fp_rect (start -0.8 -0.4) (end 0.8 0.4)
      (stroke (width 0.15) (type solid)) (fill none) (layer "F.Fab"))
    (pad "1" smd roundrect (at -0.7 0 180) (size 0.6 0.8) (layers "F.Cu" "F.Paste" "F.Mask") (roundrect_rratio 0.2)
      (net 768 "/Power Supply/DC/DC conventers/PS_1V2_OUT") (pintype "passive"))
    (pad "2" smd roundrect (at 0.7 0 180) (size 0.6 0.8) (layers "F.Cu" "F.Paste" "F.Mask") (roundrect_rratio 0.2)
      (net 18 "PS_1V2") (pintype "passive"))
  )

  (footprint "kria-k26-devboard-footprints:TP_SMD_0.75mm" (layer "F.Cu")
    (at 102.65 148.8)
    (property "Author" "Antmicro")
    (property "License" "Apache-2.0")
    (property "MPN" "")
    (property "Manufacturer" "")
    (property "Sheetfile" "i2c.kicad_sch")
    (property "Sheetname" "I2C ")
    (property "ki_description" "Test Point 0.75mm")
    (attr exclude_from_pos_files)
    (fp_text reference "TP61" (at -2.93 0.33 180) (layer "F.SilkS")
        (effects (font (size 0.7 0.7) (thickness 0.15)) (justify left bottom))
    )
    (fp_text value "TP_0.75mm_SMD" (at 0 1.2) (layer "F.Fab") hide
        (effects (font (size 0.7 0.7) (thickness 0.15)) (justify left bottom))
    )
    (fp_text user "License: Apache-2.0" (at -0.4 5.101) (layer "F.Fab") hide
        (effects (font (size 0.7 0.7) (thickness 0.15)) (justify left bottom))
    )
    (fp_text user "${REFERENCE}" (at -0.4 2.7) (layer "F.Fab") hide
        (effects (font (size 0.7 0.7) (thickness 0.15)) (justify left bottom))
    )
    (fp_text user "Author: Antmicro" (at -0.4 3.901) (layer "F.Fab") hide
        (effects (font (size 0.7 0.7) (thickness 0.15)) (justify left bottom))
    )
    (pad "1" smd circle (at 0 0) (size 0.75 0.75) (layers "F.Cu" "F.Mask")
      (net 153 "/I2C /MIO24_I2C_SCK") (pinfunction "1") (pintype "passive"))
  )

  (footprint "kria-k26-devboard-footprints:TP_SMD_0.75mm" (layer "F.Cu")
    (at 154.7492 150.8 -90)
    (property "Author" "Antmicro")
    (property "License" "Apache-2.0")
    (property "MPN" "")
    (property "Manufacturer" "")
    (property "Sheetfile" "debug.kicad_sch")
    (property "Sheetname" "Debug and JTAG")
    (property "ki_description" "Test Point 0.75mm")
    (attr exclude_from_pos_files)
    (fp_text reference "TP64" (at -0.47 -0.4308 -90) (layer "F.SilkS")
        (effects (font (size 0.7 0.7) (thickness 0.15)) (justify left bottom))
    )
    (fp_text value "TP_0.75mm_SMD" (at 0 1.2 -90) (layer "F.Fab") hide
        (effects (font (size 0.7 0.7) (thickness 0.15)) (justify left bottom))
    )
    (fp_text user "License: Apache-2.0" (at -0.4 5.101 -90) (layer "F.Fab") hide
        (effects (font (size 0.7 0.7) (thickness 0.15)) (justify left bottom))
    )
    (fp_text user "${REFERENCE}" (at -0.4 2.7 -90) (layer "F.Fab") hide
        (effects (font (size 0.7 0.7) (thickness 0.15)) (justify left bottom))
    )
    (fp_text user "Author: Antmicro" (at -0.4 3.901 -90) (layer "F.Fab") hide
        (effects (font (size 0.7 0.7) (thickness 0.15)) (justify left bottom))
    )
    (pad "1" smd circle (at 0 0 270) (size 0.75 0.75) (layers "F.Cu" "F.Mask")
      (net 700 "Net-(U40-CDBUS1)") (pinfunction "1") (pintype "passive"))
  )

  (footprint "kria-k26-devboard-footprints:Fiducial_1mm_Mask2mm" (layer "F.Cu")
    (at 174.4 55.1)
    (descr "Circular Fiducial, 1mm bare copper, 3mm soldermask opening")
    (tags "fiducial")
    (attr smd board_only exclude_from_bom)
    (fp_text reference "FID3" (at -0.07 3.21 90) (layer "F.SilkS")
        (effects (font (size 1 1) (thickness 0.15)))
    )
    (fp_text value "Fiducial_1mm_Mask2mm" (at 0 2.6035) (layer "F.Fab") hide
        (effects (font (size 1 1) (thickness 0.15)))
    )
    (fp_text user "License: Apache-2.0" (at -1.25 7.003) (layer "F.Fab") hide
        (effects (font (size 0.7 0.7) (thickness 0.15)) (justify left bottom))
    )
    (fp_text user "${REFERENCE}" (at 0 0) (layer "F.Fab")
        (effects (font (size 0.4 0.4) (thickness 0.06)))
    )
    (fp_text user "Author: Antmicro" (at -1.25 5.803) (layer "F.Fab") hide
        (effects (font (size 0.7 0.7) (thickness 0.15)) (justify left bottom))
    )
    (fp_circle (center 0 0) (end 1.24 0)
      (stroke (width 0.05) (type solid)) (fill none) (layer "F.CrtYd"))
    (fp_circle (center 0 0) (end 0.999 0)
      (stroke (width 0.15) (type solid)) (fill none) (layer "F.Fab"))
    (pad "" smd circle (at 0 0) (size 1 1) (layers "F.Cu" "F.Mask")
      (solder_mask_margin 0.5) (clearance 0.5))
  )

  (footprint "kria-k26-devboard-footprints:XILINX-KRIA-K26" locked (layer "F.Cu")
    (at 86.38 147.61)
    (property "Author" "Antmicro")
    (property "Description" "System-On-Modules - SOM K26C SOM")
    (property "License" "Apache-2.0")
    (property "MPN" "SM-K26-XCL2GC")
    (property "Manufacturer" "Xilinx")
    (property "Sheetfile" "k26_som.kicad_sch")
    (property "Sheetname" "Xilinx K26 SOM")
    (attr exclude_from_pos_files)
    (fp_text reference "M1" (at 0 0.5) (layer "F.SilkS") hide
        (effects (font (size 1 1) (thickness 0.15)))
    )
    (fp_text value "XILINX-KRIA-K26" (at 4.572 1.976) (layer "F.Fab") hide
        (effects (font (size 1 1) (thickness 0.15)))
    )
    (fp_text user "Author: Antmicro" (at -0.002 5.176) (layer "F.Fab") hide
        (effects (font (size 0.7 0.7) (thickness 0.15)) (justify left bottom))
    )
    (fp_text user "${REFERENCE}" (at -0.002 3.975) (layer "F.Fab") hide
        (effects (font (size 0.7 0.7) (thickness 0.15)) (justify left bottom))
    )
    (fp_text user "License: Apache-2.0" (at -0.002 6.376) (layer "F.Fab") hide
        (effects (font (size 0.7 0.7) (thickness 0.15)) (justify left bottom))
    )
    (fp_line (start 0 -56.82) (end 0 -3.181)
      (stroke (width 0.15) (type solid)) (layer "F.SilkS"))
    (fp_line (start 3.18 -60) (end 73.819 -60)
      (stroke (width 0.15) (type solid)) (layer "F.SilkS"))
    (fp_line (start 3.18 0) (end 73.819 0)
      (stroke (width 0.15) (type solid)) (layer "F.SilkS"))
    (fp_line (start 76.999 -56.82) (end 76.999 -3.181)
      (stroke (width 0.15) (type solid)) (layer "F.SilkS"))
    (fp_arc (start 0 -56.82) (mid 0.931 -59.069) (end 3.18 -60)
      (stroke (width 0.15) (type solid)) (layer "F.SilkS"))
    (fp_arc (start 3.18 0) (mid 0.931146 -0.931854) (end 0 -3.181)
      (stroke (width 0.15) (type solid)) (layer "F.SilkS"))
    (fp_arc (start 73.819 -60) (mid 76.06801 -59.06901) (end 76.999 -56.82)
      (stroke (width 0.15) (type solid)) (layer "F.SilkS"))
    (fp_arc (start 76.999 -3.181) (mid 76.067854 -0.931854) (end 73.819 0)
      (stroke (width 0.15) (type solid)) (layer "F.SilkS"))
    (fp_line (start 2.45 -51.66) (end 7.11 -51.66)
      (stroke (width 0.05) (type solid)) (layer "F.CrtYd"))
    (fp_line (start 2.45 -8.34) (end 2.45 -51.66)
      (stroke (width 0.05) (type solid)) (layer "F.CrtYd"))
    (fp_line (start 7.11 -51.66) (end 7.95 -50.83)
      (stroke (width 0.05) (type solid)) (layer "F.CrtYd"))
    (fp_line (start 7.11 -8.34) (end 2.45 -8.34)
      (stroke (width 0.05) (type solid)) (layer "F.CrtYd"))
    (fp_line (start 7.95 -50.83) (end 7.95 -9.18)
      (stroke (width 0.05) (type solid)) (layer "F.CrtYd"))
    (fp_line (start 7.95 -9.18) (end 7.11 -8.34)
      (stroke (width 0.05) (type solid)) (layer "F.CrtYd"))
    (fp_line (start 69.04 -51.66) (end 73.71 -51.66)
      (stroke (width 0.05) (type solid)) (layer "F.CrtYd"))
    (fp_line (start 69.04 -8.34) (end 69.04 -51.66)
      (stroke (width 0.05) (type solid)) (layer "F.CrtYd"))
    (fp_line (start 73.71 -51.66) (end 74.54 -50.83)
      (stroke (width 0.05) (type solid)) (layer "F.CrtYd"))
    (fp_line (start 73.71 -8.34) (end 69.04 -8.34)
      (stroke (width 0.05) (type solid)) (layer "F.CrtYd"))
    (fp_line (start 74.54 -50.83) (end 74.54 -9.18)
      (stroke (width 0.05) (type solid)) (layer "F.CrtYd"))
    (fp_line (start 74.54 -9.18) (end 73.71 -8.34)
      (stroke (width 0.05) (type solid)) (layer "F.CrtYd"))
  )

  (footprint "kria-k26-devboard-footprints:SOT-416" (layer "F.Cu")
    (at 183.2 117.5 90)
    (descr "SOT-416")
    (tags "SOT-416")
    (property "Author" "Antmicro")
    (property "License" "Apache-2.0")
    (property "MPN" "DTC014TEBTL")
    (property "Manufacturer" "ROHM Semiconductor")
    (property "Sheetfile" "dc-dc-conventers.kicad_sch")
    (property "Sheetname" "DC/DC conventers")
    (property "ki_description" "Digital NPN Transistor, 10k/NONE, EMT-3")
    (attr smd)
    (fp_text reference "Q18" (at -1.8 -0.89 180) (layer "F.SilkS")
        (effects (font (size 0.7 0.7) (thickness 0.15)) (justify left bottom))
    )
    (fp_text value "DTC014T_SOT-416" (at 0 2 90) (layer "F.Fab") hide
        (effects (font (size 0.7 0.7) (thickness 0.15)) (justify left bottom))
    )
    (fp_text user "Author: Antmicro" (at -1 4.602 90) (layer "F.Fab") hide
        (effects (font (size 0.7 0.7) (thickness 0.15)) (justify left bottom))
    )
    (fp_text user "${REFERENCE}" (at -1 3.4 90) (layer "F.Fab") hide
        (effects (font (size 0.7 0.7) (thickness 0.15)) (justify left bottom))
    )
    (fp_text user "License: Apache-2.0" (at -1 5.802 90) (layer "F.Fab") hide
        (effects (font (size 0.7 0.7) (thickness 0.15)) (justify left bottom))
    )
    (fp_line (start -0.5 -0.15) (end -0.5 0.15)
      (stroke (width 0.15) (type solid)) (layer "F.SilkS"))
    (fp_line (start 0.5 0.9) (end -0.5 0.9)
      (stroke (width 0.15) (type solid)) (layer "F.SilkS"))
    (fp_line (start 0.5 0.9) (end 0.5 0.7)
      (stroke (width 0.15) (type solid)) (layer "F.SilkS"))
    (fp_line (start 0.508 -0.9) (end -0.5 -0.9)
      (stroke (width 0.15) (type solid)) (layer "F.SilkS"))
    (fp_line (start 0.508 -0.9) (end 0.508 -0.592)
      (stroke (width 0.15) (type solid)) (layer "F.SilkS"))
    (fp_rect (start -1 -1.05) (end 1 1.05)
      (stroke (width 0.05) (type solid)) (fill none) (layer "F.CrtYd"))
    (fp_line (start -0.05 -0.9) (end -0.45 -0.5)
      (stroke (width 0.15) (type solid)) (layer "F.Fab"))
    (fp_rect (start 0.45 0.9) (end -0.45 -0.9)
      (stroke (width 0.15) (type solid)) (fill none) (layer "F.Fab"))
    (pad "1" smd rect (at -0.652 -0.5 90) (size 0.6 0.5) (layers "F.Cu" "F.Paste" "F.Mask")
      (net 767 "/Power Supply/DC/DC conventers/PS_1V8_OUT") (pinfunction "B") (pintype "input"))
    (pad "2" smd rect (at -0.652 0.498 90) (size 0.6 0.5) (layers "F.Cu" "F.Paste" "F.Mask")
      (net 1 "GND") (pinfunction "E") (pintype "passive"))
    (pad "3" smd rect (at 0.65 0 90) (size 0.6 0.5) (layers "F.Cu" "F.Paste" "F.Mask")
      (net 337 "Net-(Q18-C)") (pinfunction "C") (pintype "passive"))
  )

  (footprint "kria-k26-devboard-footprints:TP_SMD_0.75mm" (layer "F.Cu")
    (at 82.229289 107.9 180)
    (property "Author" "Antmicro")
    (property "License" "Apache-2.0")
    (property "MPN" "")
    (property "Manufacturer" "")
    (property "Sheetfile" "k26_som.kicad_sch")
    (property "Sheetname" "Xilinx K26 SOM")
    (property "ki_description" "Test Point 0.75mm")
    (attr exclude_from_pos_files)
    (fp_text reference "TP56" (at 4.029289 -0.27 180) (layer "F.SilkS")
        (effects (font (size 0.7 0.7) (thickness 0.15)) (justify left bottom))
    )
    (fp_text value "TP_0.75mm_SMD" (at 0 1.2 180) (layer "F.Fab") hide
        (effects (font (size 0.7 0.7) (thickness 0.15)) (justify left bottom))
    )
    (fp_text user "${REFERENCE}" (at -0.4 2.7 180) (layer "F.Fab") hide
        (effects (font (size 0.7 0.7) (thickness 0.15)) (justify left bottom))
    )
    (fp_text user "License: Apache-2.0" (at -0.4 5.101 180) (layer "F.Fab") hide
        (effects (font (size 0.7 0.7) (thickness 0.15)) (justify left bottom))
    )
    (fp_text user "Author: Antmicro" (at -0.4 3.901 180) (layer "F.Fab") hide
        (effects (font (size 0.7 0.7) (thickness 0.15)) (justify left bottom))
    )
    (pad "1" smd circle (at 0 0 180) (size 0.75 0.75) (layers "F.Cu" "F.Mask")
      (net 474 "/Xilinx K26 SOM/PWRGD_LPD_M2C") (pinfunction "1") (pintype "passive"))
  )

  (footprint "kria-k26-devboard-footprints:TP_SMD_0.75mm" (layer "F.Cu")
    (at 81.55 104.95 180)
    (property "Author" "Antmicro")
    (property "License" "Apache-2.0")
    (property "MPN" "")
    (property "Manufacturer" "")
    (property "Sheetfile" "k26_som.kicad_sch")
    (property "Sheetname" "Xilinx K26 SOM")
    (property "ki_description" "Test Point 0.75mm")
    (attr exclude_from_pos_files)
    (fp_text reference "TP54" (at 3.36 -0.2808 180) (layer "F.SilkS")
        (effects (font (size 0.7 0.7) (thickness 0.15)) (justify left bottom))
    )
    (fp_text value "TP_0.75mm_SMD" (at 0 1.2 180) (layer "F.Fab") hide
        (effects (font (size 0.7 0.7) (thickness 0.15)) (justify left bottom))
    )
    (fp_text user "${REFERENCE}" (at -0.4 2.7 180) (layer "F.Fab") hide
        (effects (font (size 0.7 0.7) (thickness 0.15)) (justify left bottom))
    )
    (fp_text user "License: Apache-2.0" (at -0.4 5.101 180) (layer "F.Fab") hide
        (effects (font (size 0.7 0.7) (thickness 0.15)) (justify left bottom))
    )
    (fp_text user "Author: Antmicro" (at -0.4 3.901 180) (layer "F.Fab") hide
        (effects (font (size 0.7 0.7) (thickness 0.15)) (justify left bottom))
    )
    (pad "1" smd circle (at 0 0 180) (size 0.75 0.75) (layers "F.Cu" "F.Mask")
      (net 457 "/Xilinx K26 SOM/PWROFF_C2M_L") (pinfunction "1") (pintype "passive"))
  )

  (footprint "kria-k26-devboard-footprints:TP_SMD_0.75mm" (layer "F.Cu")
    (at 82.229289 105.95 180)
    (property "Author" "Antmicro")
    (property "License" "Apache-2.0")
    (property "MPN" "")
    (property "Manufacturer" "")
    (property "Sheetfile" "k26_som.kicad_sch")
    (property "Sheetname" "Xilinx K26 SOM")
    (property "ki_description" "Test Point 0.75mm")
    (attr exclude_from_pos_files)
    (fp_text reference "TP53" (at 4.029289 -0.27 180) (layer "F.SilkS")
        (effects (font (size 0.7 0.7) (thickness 0.15)) (justify left bottom))
    )
    (fp_text value "TP_0.75mm_SMD" (at 0 1.2 180) (layer "F.Fab") hide
        (effects (font (size 0.7 0.7) (thickness 0.15)) (justify left bottom))
    )
    (fp_text user "License: Apache-2.0" (at -0.4 5.101 180) (layer "F.Fab") hide
        (effects (font (size 0.7 0.7) (thickness 0.15)) (justify left bottom))
    )
    (fp_text user "Author: Antmicro" (at -0.4 3.901 180) (layer "F.Fab") hide
        (effects (font (size 0.7 0.7) (thickness 0.15)) (justify left bottom))
    )
    (fp_text user "${REFERENCE}" (at -0.4 2.7 180) (layer "F.Fab") hide
        (effects (font (size 0.7 0.7) (thickness 0.15)) (justify left bottom))
    )
    (pad "1" smd circle (at 0 0 180) (size 0.75 0.75) (layers "F.Cu" "F.Mask")
      (net 456 "/Xilinx K26 SOM/PS_ERROR_STATUS_M2C") (pinfunction "1") (pintype "passive"))
  )

  (footprint "kria-k26-devboard-footprints:R_0402_1005Metric" (layer "F.Cu")
    (at 112.65 136.03 -90)
    (descr "Resistor SMD 0402")
    (tags "resistor SMD 0402")
    (property "Author" "Antmicro")
    (property "License" "Apache-2.0")
    (property "MPN" "CR0402-FX-1001GLF")
    (property "Manufacturer" "Bourns")
    (property "Sheetfile" "reset.kicad_sch")
    (property "Sheetname" "Reset logic")
    (property "Tolerance" "1%")
    (property "Val" "1k")
    (property "ki_description" "1k resistor in 0402 package with 1% tolerance")
    (attr smd)
    (fp_text reference "R85" (at 1.09 -1.26 -90) (layer "F.SilkS")
        (effects (font (size 0.7 0.7) (thickness 0.15)) (justify left bottom))
    )
    (fp_text value "R_1k_0402" (at 0 1.4 -90) (layer "F.Fab") hide
        (effects (font (size 0.7 0.7) (thickness 0.15)) (justify left bottom))
    )
    (fp_text user "${REFERENCE}" (at -0.95 3.168 -90) (layer "F.Fab") hide
        (effects (font (size 0.7 0.7) (thickness 0.15)) (justify left bottom))
    )
    (fp_text user "Author: Antmicro" (at -0.95 4.169 -90) (layer "F.Fab") hide
        (effects (font (size 0.7 0.7) (thickness 0.15)) (justify left bottom))
    )
    (fp_text user "License: Apache-2.0" (at -0.95 5.169 -90) (layer "F.Fab") hide
        (effects (font (size 0.7 0.7) (thickness 0.15)) (justify left bottom))
    )
    (fp_rect (start -0.93 -0.47) (end 0.93 0.47)
      (stroke (width 0.05) (type solid)) (fill none) (layer "F.CrtYd"))
    (fp_rect (start -0.5 -0.25) (end 0.5 0.25)
      (stroke (width 0.15) (type solid)) (fill none) (layer "F.Fab"))
    (pad "1" smd roundrect (at -0.485 0 270) (size 0.59 0.64) (layers "F.Cu" "F.Paste" "F.Mask") (roundrect_rratio 0.25)
      (net 185 "/Clock distribution/PS_CLK_EN") (pintype "passive"))
    (pad "2" smd roundrect (at 0.485 0 270) (size 0.59 0.64) (layers "F.Cu" "F.Paste" "F.Mask") (roundrect_rratio 0.25)
      (net 15 "PS_3V3") (pintype "passive"))
  )

  (footprint "kria-k26-devboard-footprints:TP_SMD_0.75mm" (layer "F.Cu")
    (at 103.7 148.8)
    (property "Author" "Antmicro")
    (property "License" "Apache-2.0")
    (property "MPN" "")
    (property "Manufacturer" "")
    (property "Sheetfile" "i2c.kicad_sch")
    (property "Sheetname" "I2C ")
    (property "ki_description" "Test Point 0.75mm")
    (attr exclude_from_pos_files)
    (fp_text reference "TP62" (at 0.24 0.33) (layer "F.SilkS")
        (effects (font (size 0.7 0.7) (thickness 0.15)) (justify left bottom))
    )
    (fp_text value "TP_0.75mm_SMD" (at 0 1.2) (layer "F.Fab") hide
        (effects (font (size 0.7 0.7) (thickness 0.15)) (justify left bottom))
    )
    (fp_text user "License: Apache-2.0" (at -0.4 5.101) (layer "F.Fab") hide
        (effects (font (size 0.7 0.7) (thickness 0.15)) (justify left bottom))
    )
    (fp_text user "${REFERENCE}" (at -0.4 2.7) (layer "F.Fab") hide
        (effects (font (size 0.7 0.7) (thickness 0.15)) (justify left bottom))
    )
    (fp_text user "Author: Antmicro" (at -0.4 3.901) (layer "F.Fab") hide
        (effects (font (size 0.7 0.7) (thickness 0.15)) (justify left bottom))
    )
    (pad "1" smd circle (at 0 0) (size 0.75 0.75) (layers "F.Cu" "F.Mask")
      (net 432 "/I2C /MIO25_I2C_SDA") (pinfunction "1") (pintype "passive"))
  )

  (footprint "kria-k26-devboard-footprints:TP_SMD_0.75mm" (layer "F.Cu")
    (at 81.55 108.8492 180)
    (property "Author" "Antmicro")
    (property "License" "Apache-2.0")
    (property "MPN" "")
    (property "Manufacturer" "")
    (property "Sheetfile" "k26_som.kicad_sch")
    (property "Sheetname" "Xilinx K26 SOM")
    (property "ki_description" "Test Point 0.75mm")
    (attr exclude_from_pos_files)
    (fp_text reference "TP55" (at 3.36 -0.2808 180) (layer "F.SilkS")
        (effects (font (size 0.7 0.7) (thickness 0.15)) (justify left bottom))
    )
    (fp_text value "TP_0.75mm_SMD" (at 0 1.2 180) (layer "F.Fab") hide
        (effects (font (size 0.7 0.7) (thickness 0.15)) (justify left bottom))
    )
    (fp_text user "${REFERENCE}" (at -0.4 2.7 180) (layer "F.Fab") hide
        (effects (font (size 0.7 0.7) (thickness 0.15)) (justify left bottom))
    )
    (fp_text user "License: Apache-2.0" (at -0.4 5.101 180) (layer "F.Fab") hide
        (effects (font (size 0.7 0.7) (thickness 0.15)) (justify left bottom))
    )
    (fp_text user "Author: Antmicro" (at -0.4 3.901 180) (layer "F.Fab") hide
        (effects (font (size 0.7 0.7) (thickness 0.15)) (justify left bottom))
    )
    (pad "1" smd circle (at 0 0 180) (size 0.75 0.75) (layers "F.Cu" "F.Mask")
      (net 473 "/Xilinx K26 SOM/PWRGD_FPD_M2C") (pinfunction "1") (pintype "passive"))
  )

  (footprint "kria-k26-devboard-footprints:TP_SMD_0.75mm" (layer "F.Cu")
    (at 139.3 139.3 180)
    (property "Author" "Antmicro")
    (property "License" "Apache-2.0")
    (property "MPN" "")
    (property "Manufacturer" "")
    (property "Sheetfile" "sd-3-card.kicad_sch")
    (property "Sheetname" "SD 3.0 card")
    (property "ki_description" "Test Point 0.75mm")
    (attr exclude_from_pos_files)
    (fp_text reference "TP60" (at 1.23 -1.22 180) (layer "F.SilkS")
        (effects (font (size 0.7 0.7) (thickness 0.15)) (justify left bottom))
    )
    (fp_text value "TP_0.75mm_SMD" (at 0 1.2 180) (layer "F.Fab") hide
        (effects (font (size 0.7 0.7) (thickness 0.15)) (justify left bottom))
    )
    (fp_text user "Author: Antmicro" (at -0.4 3.901 180) (layer "F.Fab") hide
        (effects (font (size 0.7 0.7) (thickness 0.15)) (justify left bottom))
    )
    (fp_text user "License: Apache-2.0" (at -0.4 5.101 180) (layer "F.Fab") hide
        (effects (font (size 0.7 0.7) (thickness 0.15)) (justify left bottom))
    )
    (fp_text user "${REFERENCE}" (at -0.4 2.7 180) (layer "F.Fab") hide
        (effects (font (size 0.7 0.7) (thickness 0.15)) (justify left bottom))
    )
    (pad "1" smd circle (at 0 0 180) (size 0.75 0.75) (layers "F.Cu" "F.Mask")
      (net 695 "Net-(U6-ST)") (pinfunction "1") (pintype "passive"))
  )

  (footprint "kria-k26-devboard-footprints:C_0402_1005Metric" (layer "F.Cu")
    (at 166.885 75.9)
    (descr "Capacitor SMD 0402")
    (tags "capacitor SMD 0402")
    (property "Author" "Antmicro")
    (property "Dielectric" "X5R")
    (property "License" "Apache-2.0")
    (property "MPN" "GRM155R61H104KE14D")
    (property "Manufacturer" "Murata")
    (property "Sheetfile" "eth.kicad_sch")
    (property "Sheetname" "Ethernet")
    (property "Val" "100n")
    (property "Voltage" "50V")
    (property "ki_description" " ")
    (attr smd)
    (fp_text reference "C239" (at -1.185 -0.58) (layer "F.SilkS")
        (effects (font (size 0.7 0.7) (thickness 0.15)) (justify left bottom))
    )
    (fp_text value "C_100n_0402" (at 0 1.4) (layer "F.Fab") hide
        (effects (font (size 0.7 0.7) (thickness 0.15)) (justify left bottom))
    )
    (fp_text user "${REFERENCE}" (at -0.932 3.168) (layer "F.Fab") hide
        (effects (font (size 0.7 0.7) (thickness 0.15)) (justify left bottom))
    )
    (fp_text user "Author: Antmicro" (at -0.932 4.17) (layer "F.Fab") hide
        (effects (font (size 0.7 0.7) (thickness 0.15)) (justify left bottom))
    )
    (fp_text user "License: Apache-2.0" (at -0.932 5.17) (layer "F.Fab") hide
        (effects (font (size 0.7 0.7) (thickness 0.15)) (justify left bottom))
    )
    (fp_rect (start -0.94 -0.47) (end 0.94 0.47)
      (stroke (width 0.05) (type solid)) (fill none) (layer "F.CrtYd"))
    (fp_rect (start -0.499 -0.249) (end 0.499 0.249)
      (stroke (width 0.15) (type solid)) (fill none) (layer "F.Fab"))
    (pad "1" smd roundrect (at -0.484 0) (size 0.59 0.64) (layers "F.Cu" "F.Paste" "F.Mask") (roundrect_rratio 0.25)
      (net 332 "Net-(J5-P4)") (pintype "passive"))
    (pad "2" smd roundrect (at 0.484 0) (size 0.59 0.64) (layers "F.Cu" "F.Paste" "F.Mask") (roundrect_rratio 0.25)
      (net 1 "GND") (pintype "passive"))
  )

  (footprint "kria-k26-devboard-footprints:C_0603_1608Metric" (layer "F.Cu")
    (at 79.115 88.3 180)
    (descr "Capacitor SMD 0603")
    (tags "capacitor 0603")
    (property "Author" "Antmicro")
    (property "License" "Apache-2.0")
    (property "MPN" "GRM188R61A106KE69D")
    (property "Manufacturer" "Murata")
    (property "Sheetfile" "camera.kicad_sch")
    (property "Sheetname" "Camera interface")
    (property "Val" "10u")
    (property "Voltage" "")
    (property "ki_description" " ")
    (attr smd)
    (fp_text reference "C245" (at 4.054 -0.375 180) (layer "F.SilkS")
        (effects (font (size 0.7 0.7) (thickness 0.15)) (justify left bottom))
    )
    (fp_text value "C_10u_0603" (at 0 1.6 180) (layer "F.Fab") hide
        (effects (font (size 0.7 0.7) (thickness 0.15)) (justify left bottom))
    )
    (fp_text user "License: Apache-2.0" (at -1.682 5.895 180) (layer "F.Fab") hide
        (effects (font (size 0.7 0.7) (thickness 0.15)) (justify left bottom))
    )
    (fp_text user "Author: Antmicro" (at -1.682 4.894 180) (layer "F.Fab") hide
        (effects (font (size 0.7 0.7) (thickness 0.15)) (justify left bottom))
    )
    (fp_text user "${REFERENCE}" (at -1.682 3.895 180) (layer "F.Fab") hide
        (effects (font (size 0.7 0.7) (thickness 0.15)) (justify left bottom))
    )
    (fp_line (start -0.3 -0.3) (end 0.3 -0.3)
      (stroke (width 0.15) (type solid)) (layer "F.SilkS"))
    (fp_line (start -0.3 0.3) (end 0.3 0.3)
      (stroke (width 0.15) (type solid)) (layer "F.SilkS"))
    (fp_rect (start -1.24 -0.7) (end 1.24 0.7)
      (stroke (width 0.05) (type solid)) (fill none) (layer "F.CrtYd"))
    (fp_rect (start -0.8 -0.4) (end 0.8 0.4)
      (stroke (width 0.15) (type solid)) (fill none) (layer "F.Fab"))
    (pad "1" smd roundrect (at -0.7 0 180) (size 0.6 0.8) (layers "F.Cu" "F.Paste" "F.Mask") (roundrect_rratio 0.2)
      (net 8 "SOM_5V0") (pintype "passive"))
    (pad "2" smd roundrect (at 0.7 0 180) (size 0.6 0.8) (layers "F.Cu" "F.Paste" "F.Mask") (roundrect_rratio 0.2)
      (net 1 "GND") (pintype "passive"))
  )

  (footprint "kria-k26-devboard-footprints:C_0402_1005Metric" (layer "F.Cu")
    (at 83.9 147.6)
    (descr "Capacitor SMD 0402")
    (tags "capacitor SMD 0402")
    (property "Author" "Antmicro")
    (property "Dielectric" "X5R")
    (property "License" "Apache-2.0")
    (property "MPN" "GRM155R61H104KE14D")
    (property "Manufacturer" "Murata")
    (property "Sheetfile" "k26_som.kicad_sch")
    (property "Sheetname" "Xilinx K26 SOM")
    (property "Val" "100n")
    (property "Voltage" "50V")
    (property "ki_description" " ")
    (attr smd)
    (fp_text reference "C241" (at -1.2 -0.55) (layer "F.SilkS")
        (effects (font (size 0.7 0.7) (thickness 0.15)) (justify left bottom))
    )
    (fp_text value "C_100n_0402" (at 0 1.4) (layer "F.Fab") hide
        (effects (font (size 0.7 0.7) (thickness 0.15)) (justify left bottom))
    )
    (fp_text user "Author: Antmicro" (at -0.932 4.17) (layer "F.Fab") hide
        (effects (font (size 0.7 0.7) (thickness 0.15)) (justify left bottom))
    )
    (fp_text user "License: Apache-2.0" (at -0.932 5.17) (layer "F.Fab") hide
        (effects (font (size 0.7 0.7) (thickness 0.15)) (justify left bottom))
    )
    (fp_text user "${REFERENCE}" (at -0.932 3.168) (layer "F.Fab") hide
        (effects (font (size 0.7 0.7) (thickness 0.15)) (justify left bottom))
    )
    (fp_rect (start -0.94 -0.47) (end 0.94 0.47)
      (stroke (width 0.05) (type solid)) (fill none) (layer "F.CrtYd"))
    (fp_rect (start -0.499 -0.249) (end 0.499 0.249)
      (stroke (width 0.15) (type solid)) (fill none) (layer "F.Fab"))
    (pad "1" smd roundrect (at -0.484 0) (size 0.59 0.64) (layers "F.Cu" "F.Paste" "F.Mask") (roundrect_rratio 0.25)
      (net 467 "/Xilinx K26 SOM/MIO12_FWUEN_C2M_L") (pintype "passive"))
    (pad "2" smd roundrect (at 0.484 0) (size 0.59 0.64) (layers "F.Cu" "F.Paste" "F.Mask") (roundrect_rratio 0.25)
      (net 1 "GND") (pintype "passive"))
  )

  (footprint "kria-k26-devboard-footprints:C_0402_1005Metric" (layer "F.Cu")
    (at 164.405 75.9)
    (descr "Capacitor SMD 0402")
    (tags "capacitor SMD 0402")
    (property "Author" "Antmicro")
    (property "Dielectric" "X5R")
    (property "License" "Apache-2.0")
    (property "MPN" "GRM155R61H104KE14D")
    (property "Manufacturer" "Murata")
    (property "Sheetfile" "eth.kicad_sch")
    (property "Sheetname" "Ethernet")
    (property "Val" "100n")
    (property "Voltage" "50V")
    (property "ki_description" " ")
    (attr smd)
    (fp_text reference "C240" (at -1.495 -0.59) (layer "F.SilkS")
        (effects (font (size 0.7 0.7) (thickness 0.15)) (justify left bottom))
    )
    (fp_text value "C_100n_0402" (at 0 1.4) (layer "F.Fab") hide
        (effects (font (size 0.7 0.7) (thickness 0.15)) (justify left bottom))
    )
    (fp_text user "License: Apache-2.0" (at -0.932 5.17) (layer "F.Fab") hide
        (effects (font (size 0.7 0.7) (thickness 0.15)) (justify left bottom))
    )
    (fp_text user "Author: Antmicro" (at -0.932 4.17) (layer "F.Fab") hide
        (effects (font (size 0.7 0.7) (thickness 0.15)) (justify left bottom))
    )
    (fp_text user "${REFERENCE}" (at -0.932 3.168) (layer "F.Fab") hide
        (effects (font (size 0.7 0.7) (thickness 0.15)) (justify left bottom))
    )
    (fp_rect (start -0.94 -0.47) (end 0.94 0.47)
      (stroke (width 0.05) (type solid)) (fill none) (layer "F.CrtYd"))
    (fp_rect (start -0.499 -0.249) (end 0.499 0.249)
      (stroke (width 0.15) (type solid)) (fill none) (layer "F.Fab"))
    (pad "1" smd roundrect (at -0.484 0) (size 0.59 0.64) (layers "F.Cu" "F.Paste" "F.Mask") (roundrect_rratio 0.25)
      (net 333 "Net-(J5-P5)") (pintype "passive"))
    (pad "2" smd roundrect (at 0.484 0) (size 0.59 0.64) (layers "F.Cu" "F.Paste" "F.Mask") (roundrect_rratio 0.25)
      (net 1 "GND") (pintype "passive"))
  )

  (footprint "kria-k26-devboard-footprints:TP_SMD_0.75mm" (layer "F.Cu")
    (at 82.229289 101.870711 180)
    (property "Author" "Antmicro")
    (property "License" "Apache-2.0")
    (property "MPN" "")
    (property "Manufacturer" "")
    (property "Sheetfile" "k26_som.kicad_sch")
    (property "Sheetname" "Xilinx K26 SOM")
    (property "ki_description" "Test Point 0.75mm")
    (attr exclude_from_pos_files)
    (fp_text reference "TP59" (at 4.029289 -0.27 180) (layer "F.SilkS")
        (effects (font (size 0.7 0.7) (thickness 0.15)) (justify left bottom))
    )
    (fp_text value "TP_0.75mm_SMD" (at 0 1.2 180) (layer "F.Fab") hide
        (effects (font (size 0.7 0.7) (thickness 0.15)) (justify left bottom))
    )
    (fp_text user "Author: Antmicro" (at -0.4 3.901 180) (layer "F.Fab") hide
        (effects (font (size 0.7 0.7) (thickness 0.15)) (justify left bottom))
    )
    (fp_text user "${REFERENCE}" (at -0.4 2.7 180) (layer "F.Fab") hide
        (effects (font (size 0.7 0.7) (thickness 0.15)) (justify left bottom))
    )
    (fp_text user "License: Apache-2.0" (at -0.4 5.101 180) (layer "F.Fab") hide
        (effects (font (size 0.7 0.7) (thickness 0.15)) (justify left bottom))
    )
    (pad "1" smd circle (at 0 0 180) (size 0.75 0.75) (layers "F.Cu" "F.Mask")
      (net 458 "/Xilinx K26 SOM/MIO35_WD_OUT") (pinfunction "1") (pintype "passive"))
  )

  (footprint "kria-k26-devboard-footprints:R_0402_1005Metric" (layer "F.Cu")
    (at 111.94 92.24 180)
    (descr "Resistor SMD 0402")
    (tags "resistor SMD 0402")
    (property "Author" "Antmicro")
    (property "License" "Apache-2.0")
    (property "MPN" "CR0402-FX-2003GLF")
    (property "Manufacturer" "Bourns")
    (property "Sheetfile" "usb.kicad_sch")
    (property "Sheetname" "USB")
    (property "Tolerance" "1%")
    (property "Val" "200k")
    (property "ki_description" "200k resistor in 0402 package with 1% tolerance")
    (attr smd)
    (fp_text reference "R173" (at 3.705 -0.35 180) (layer "F.SilkS")
        (effects (font (size 0.7 0.7) (thickness 0.15)) (justify left bottom))
    )
    (fp_text value "R_200k_0402" (at 0 1.4 180) (layer "F.Fab") hide
        (effects (font (size 0.7 0.7) (thickness 0.15)) (justify left bottom))
    )
    (fp_text user "License: Apache-2.0" (at -0.95 5.169 180) (layer "F.Fab") hide
        (effects (font (size 0.7 0.7) (thickness 0.15)) (justify left bottom))
    )
    (fp_text user "${REFERENCE}" (at -0.95 3.168 180) (layer "F.Fab") hide
        (effects (font (size 0.7 0.7) (thickness 0.15)) (justify left bottom))
    )
    (fp_text user "Author: Antmicro" (at -0.95 4.169 180) (layer "F.Fab") hide
        (effects (font (size 0.7 0.7) (thickness 0.15)) (justify left bottom))
    )
    (fp_rect (start -0.93 -0.47) (end 0.93 0.47)
      (stroke (width 0.05) (type solid)) (fill none) (layer "F.CrtYd"))
    (fp_rect (start -0.5 -0.25) (end 0.5 0.25)
      (stroke (width 0.15) (type solid)) (fill none) (layer "F.Fab"))
    (pad "1" smd roundrect (at -0.485 0 180) (size 0.59 0.64) (layers "F.Cu" "F.Paste" "F.Mask") (roundrect_rratio 0.25)
      (net 667 "Net-(U17-PF27)") (pintype "passive"))
    (pad "2" smd roundrect (at 0.485 0 180) (size 0.59 0.64) (layers "F.Cu" "F.Paste" "F.Mask") (roundrect_rratio 0.25)
      (net 1 "GND") (pintype "passive"))
  )

  (footprint "kria-k26-devboard-footprints:TP_SMD_0.75mm" (layer "F.Cu")
    (at 82.229289 103.95 180)
    (property "Author" "Antmicro")
    (property "License" "Apache-2.0")
    (property "MPN" "")
    (property "Manufacturer" "")
    (property "Sheetfile" "k26_som.kicad_sch")
    (property "Sheetname" "Xilinx K26 SOM")
    (property "ki_description" "Test Point 0.75mm")
    (attr exclude_from_pos_files)
    (fp_text reference "TP52" (at 4.029289 -0.27 180) (layer "F.SilkS")
        (effects (font (size 0.7 0.7) (thickness 0.15)) (justify left bottom))
    )
    (fp_text value "TP_0.75mm_SMD" (at 0 1.2 180) (layer "F.Fab") hide
        (effects (font (size 0.7 0.7) (thickness 0.15)) (justify left bottom))
    )
    (fp_text user "License: Apache-2.0" (at -0.4 5.101 180) (layer "F.Fab") hide
        (effects (font (size 0.7 0.7) (thickness 0.15)) (justify left bottom))
    )
    (fp_text user "Author: Antmicro" (at -0.4 3.901 180) (layer "F.Fab") hide
        (effects (font (size 0.7 0.7) (thickness 0.15)) (justify left bottom))
    )
    (fp_text user "${REFERENCE}" (at -0.4 2.7 180) (layer "F.Fab") hide
        (effects (font (size 0.7 0.7) (thickness 0.15)) (justify left bottom))
    )
    (pad "1" smd circle (at 0 0 180) (size 0.75 0.75) (layers "F.Cu" "F.Mask")
      (net 455 "/Xilinx K26 SOM/PS_ERROR_OUT_M2C") (pinfunction "1") (pintype "passive"))
  )

  (footprint "kria-k26-devboard-footprints:C_0402_1005Metric" (layer "F.Cu")
    (at 79.425 92.175 180)
    (descr "Capacitor SMD 0402")
    (tags "capacitor SMD 0402")
    (property "Author" "Antmicro")
    (property "Dielectric" "X5R")
    (property "License" "Apache-2.0")
    (property "MPN" "GRM155R61H104KE14D")
    (property "Manufacturer" "Murata")
    (property "Sheetfile" "camera.kicad_sch")
    (property "Sheetname" "Camera interface")
    (property "Val" "100n")
    (property "Voltage" "50V")
    (property "ki_description" " ")
    (attr smd)
    (fp_text reference "C246" (at 3.845 -0.335 180) (layer "F.SilkS")
        (effects (font (size 0.7 0.7) (thickness 0.15)) (justify left bottom))
    )
    (fp_text value "C_100n_0402" (at 0 1.4 180) (layer "F.Fab") hide
        (effects (font (size 0.7 0.7) (thickness 0.15)) (justify left bottom))
    )
    (fp_text user "${REFERENCE}" (at -0.932 3.168 180) (layer "F.Fab") hide
        (effects (font (size 0.7 0.7) (thickness 0.15)) (justify left bottom))
    )
    (fp_text user "Author: Antmicro" (at -0.932 4.17 180) (layer "F.Fab") hide
        (effects (font (size 0.7 0.7) (thickness 0.15)) (justify left bottom))
    )
    (fp_text user "License: Apache-2.0" (at -0.932 5.17 180) (layer "F.Fab") hide
        (effects (font (size 0.7 0.7) (thickness 0.15)) (justify left bottom))
    )
    (fp_rect (start -0.94 -0.47) (end 0.94 0.47)
      (stroke (width 0.05) (type solid)) (fill none) (layer "F.CrtYd"))
    (fp_rect (start -0.499 -0.249) (end 0.499 0.249)
      (stroke (width 0.15) (type solid)) (fill none) (layer "F.Fab"))
    (pad "1" smd roundrect (at -0.484 0 180) (size 0.59 0.64) (layers "F.Cu" "F.Paste" "F.Mask") (roundrect_rratio 0.25)
      (net 20 "PL_3V3") (pintype "passive"))
    (pad "2" smd roundrect (at 0.484 0 180) (size 0.59 0.64) (layers "F.Cu" "F.Paste" "F.Mask") (roundrect_rratio 0.25)
      (net 1 "GND") (pintype "passive"))
  )

  (footprint "kria-k26-devboard-footprints:TP_SMD_0.75mm" (layer "F.Cu")
    (at 153.7492 150.825 -90)
    (property "Author" "Antmicro")
    (property "License" "Apache-2.0")
    (property "MPN" "")
    (property "Manufacturer" "")
    (property "Sheetfile" "debug.kicad_sch")
    (property "Sheetname" "Debug and JTAG")
    (property "ki_description" "Test Point 0.75mm")
    (attr exclude_from_pos_files)
    (fp_text reference "TP63" (at -0.47 -0.4308 -90) (layer "F.SilkS")
        (effects (font (size 0.7 0.7) (thickness 0.15)) (justify left bottom))
    )
    (fp_text value "TP_0.75mm_SMD" (at 0 1.2 -90) (layer "F.Fab") hide
        (effects (font (size 0.7 0.7) (thickness 0.15)) (justify left bottom))
    )
    (fp_text user "${REFERENCE}" (at -0.4 2.7 -90) (layer "F.Fab") hide
        (effects (font (size 0.7 0.7) (thickness 0.15)) (justify left bottom))
    )
    (fp_text user "Author: Antmicro" (at -0.4 3.901 -90) (layer "F.Fab") hide
        (effects (font (size 0.7 0.7) (thickness 0.15)) (justify left bottom))
    )
    (fp_text user "License: Apache-2.0" (at -0.4 5.101 -90) (layer "F.Fab") hide
        (effects (font (size 0.7 0.7) (thickness 0.15)) (justify left bottom))
    )
    (pad "1" smd circle (at 0 0 270) (size 0.75 0.75) (layers "F.Cu" "F.Mask")
      (net 699 "Net-(U40-CDBUS0)") (pinfunction "1") (pintype "passive"))
  )

  (footprint "kria-k26-devboard-footprints:C_0402_1005Metric" (layer "B.Cu")
    (at 120.6 100.288999 90)
    (descr "Capacitor SMD 0402")
    (tags "capacitor SMD 0402")
    (property "Author" "Antmicro")
    (property "Dielectric" "X5R")
    (property "License" "Apache-2.0")
    (property "MPN" "GRM155R61H104KE14D")
    (property "Manufacturer" "Murata")
    (property "Sheetfile" "usb.kicad_sch")
    (property "Sheetname" "USB")
    (property "Val" "100n")
    (property "Voltage" "50V")
    (property "ki_description" " ")
    (attr smd)
    (fp_text reference "C80" (at 0.858999 1.33 270) (layer "B.SilkS")
        (effects (font (size 0.7 0.7) (thickness 0.15)) (justify left bottom mirror))
    )
    (fp_text value "C_100n_0402" (at 0 -1.4 270) (layer "B.Fab") hide
        (effects (font (size 0.7 0.7) (thickness 0.15)) (justify left bottom mirror))
    )
    (fp_text user "License: Apache-2.0" (at -0.932 -5.17 270) (layer "B.Fab") hide
        (effects (font (size 0.7 0.7) (thickness 0.15)) (justify left bottom mirror))
    )
    (fp_text user "${REFERENCE}" (at -0.932 -3.168 270) (layer "B.Fab") hide
        (effects (font (size 0.7 0.7) (thickness 0.15)) (justify left bottom mirror))
    )
    (fp_text user "Author: Antmicro" (at -0.932 -4.17 270) (layer "B.Fab") hide
        (effects (font (size 0.7 0.7) (thickness 0.15)) (justify left bottom mirror))
    )
    (fp_rect (start -0.94 0.47) (end 0.94 -0.47)
      (stroke (width 0.05) (type solid)) (fill none) (layer "B.CrtYd"))
    (fp_rect (start -0.499 0.249) (end 0.499 -0.249)
      (stroke (width 0.15) (type solid)) (fill none) (layer "B.Fab"))
    (pad "1" smd roundrect (at -0.484 0 90) (size 0.59 0.64) (layers "B.Cu" "B.Paste" "B.Mask") (roundrect_rratio 0.25)
      (net 17 "PS_1V8") (pintype "passive"))
    (pad "2" smd roundrect (at 0.484 0 90) (size 0.59 0.64) (layers "B.Cu" "B.Paste" "B.Mask") (roundrect_rratio 0.25)
      (net 1 "GND") (pintype "passive"))
  )

  (footprint "kria-k26-devboard-footprints:C_0402_1005Metric" (layer "B.Cu")
    (at 122.749 99.004 180)
    (descr "Capacitor SMD 0402")
    (tags "capacitor SMD 0402")
    (property "Author" "Antmicro")
    (property "Dielectric" "X5R")
    (property "License" "Apache-2.0")
    (property "MPN" "GRM155R61H104KE14D")
    (property "Manufacturer" "Murata")
    (property "Sheetfile" "usb.kicad_sch")
    (property "Sheetname" "USB")
    (property "Val" "100n")
    (property "Voltage" "50V")
    (property "ki_description" " ")
    (attr smd)
    (fp_text reference "C83" (at -1.521 0.594) (layer "B.SilkS")
        (effects (font (size 0.7 0.7) (thickness 0.15)) (justify left bottom mirror))
    )
    (fp_text value "C_100n_0402" (at 0 -1.4) (layer "B.Fab") hide
        (effects (font (size 0.7 0.7) (thickness 0.15)) (justify left bottom mirror))
    )
    (fp_text user "License: Apache-2.0" (at -0.932 -5.17) (layer "B.Fab") hide
        (effects (font (size 0.7 0.7) (thickness 0.15)) (justify left bottom mirror))
    )
    (fp_text user "${REFERENCE}" (at -0.932 -3.168) (layer "B.Fab") hide
        (effects (font (size 0.7 0.7) (thickness 0.15)) (justify left bottom mirror))
    )
    (fp_text user "Author: Antmicro" (at -0.932 -4.17) (layer "B.Fab") hide
        (effects (font (size 0.7 0.7) (thickness 0.15)) (justify left bottom mirror))
    )
    (fp_rect (start -0.94 0.47) (end 0.94 -0.47)
      (stroke (width 0.05) (type solid)) (fill none) (layer "B.CrtYd"))
    (fp_rect (start -0.499 0.249) (end 0.499 -0.249)
      (stroke (width 0.15) (type solid)) (fill none) (layer "B.Fab"))
    (pad "1" smd roundrect (at -0.484 0 180) (size 0.59 0.64) (layers "B.Cu" "B.Paste" "B.Mask") (roundrect_rratio 0.25)
      (net 17 "PS_1V8") (pintype "passive"))
    (pad "2" smd roundrect (at 0.484 0 180) (size 0.59 0.64) (layers "B.Cu" "B.Paste" "B.Mask") (roundrect_rratio 0.25)
      (net 1 "GND") (pintype "passive"))
  )

  (footprint "kria-k26-devboard-footprints:C_0402_1005Metric" (layer "B.Cu")
    (at 120.65 97.14 -90)
    (descr "Capacitor SMD 0402")
    (tags "capacitor SMD 0402")
    (property "Author" "Antmicro")
    (property "Dielectric" "")
    (property "License" "Apache-2.0")
    (property "MPN" "GRM155R61A475MEAAD")
    (property "Manufacturer" "Murata")
    (property "Sheetfile" "usb.kicad_sch")
    (property "Sheetname" "USB")
    (property "Val" "4u7")
    (property "Voltage" "")
    (property "ki_description" " ")
    (attr smd)
    (fp_text reference "C86" (at -1.154 1.479 90) (layer "B.SilkS")
        (effects (font (size 0.7 0.7) (thickness 0.15)) (justify left bottom mirror))
    )
    (fp_text value "C_4u7_0402" (at 0 -1.4 90) (layer "B.Fab") hide
        (effects (font (size 0.7 0.7) (thickness 0.15)) (justify left bottom mirror))
    )
    (fp_text user "Author: Antmicro" (at -0.932 -4.17 90) (layer "B.Fab") hide
        (effects (font (size 0.7 0.7) (thickness 0.15)) (justify left bottom mirror))
    )
    (fp_text user "${REFERENCE}" (at -0.932 -3.168 90) (layer "B.Fab") hide
        (effects (font (size 0.7 0.7) (thickness 0.15)) (justify left bottom mirror))
    )
    (fp_text user "License: Apache-2.0" (at -0.932 -5.17 90) (layer "B.Fab") hide
        (effects (font (size 0.7 0.7) (thickness 0.15)) (justify left bottom mirror))
    )
    (fp_rect (start -0.94 0.47) (end 0.94 -0.47)
      (stroke (width 0.05) (type solid)) (fill none) (layer "B.CrtYd"))
    (fp_rect (start -0.499 0.249) (end 0.499 -0.249)
      (stroke (width 0.15) (type solid)) (fill none) (layer "B.Fab"))
    (pad "1" smd roundrect (at -0.484 0 270) (size 0.59 0.64) (layers "B.Cu" "B.Paste" "B.Mask") (roundrect_rratio 0.25)
      (net 154 "Net-(U23-VDD_3V3)") (pintype "passive"))
    (pad "2" smd roundrect (at 0.484 0 270) (size 0.59 0.64) (layers "B.Cu" "B.Paste" "B.Mask") (roundrect_rratio 0.25)
      (net 1 "GND") (pintype "passive"))
  )

  (footprint "kria-k26-devboard-footprints:C_0402_1005Metric" (layer "B.Cu")
    (at 121.599 97.154 -90)
    (descr "Capacitor SMD 0402")
    (tags "capacitor SMD 0402")
    (property "Author" "Antmicro")
    (property "Dielectric" "X5R")
    (property "License" "Apache-2.0")
    (property "MPN" "GRM155R61H104KE14D")
    (property "Manufacturer" "Murata")
    (property "Sheetfile" "usb.kicad_sch")
    (property "Sheetname" "USB")
    (property "Val" "100n")
    (property "Voltage" "50V")
    (property "ki_description" " ")
    (attr smd)
    (fp_text reference "C89" (at -1.154 1.479 90) (layer "B.SilkS")
        (effects (font (size 0.7 0.7) (thickness 0.15)) (justify left bottom mirror))
    )
    (fp_text value "C_100n_0402" (at 0 -1.4 90) (layer "B.Fab") hide
        (effects (font (size 0.7 0.7) (thickness 0.15)) (justify left bottom mirror))
    )
    (fp_text user "Author: Antmicro" (at -0.932 -4.17 90) (layer "B.Fab") hide
        (effects (font (size 0.7 0.7) (thickness 0.15)) (justify left bottom mirror))
    )
    (fp_text user "License: Apache-2.0" (at -0.932 -5.17 90) (layer "B.Fab") hide
        (effects (font (size 0.7 0.7) (thickness 0.15)) (justify left bottom mirror))
    )
    (fp_text user "${REFERENCE}" (at -0.932 -3.168 90) (layer "B.Fab") hide
        (effects (font (size 0.7 0.7) (thickness 0.15)) (justify left bottom mirror))
    )
    (fp_rect (start -0.94 0.47) (end 0.94 -0.47)
      (stroke (width 0.05) (type solid)) (fill none) (layer "B.CrtYd"))
    (fp_rect (start -0.499 0.249) (end 0.499 -0.249)
      (stroke (width 0.15) (type solid)) (fill none) (layer "B.Fab"))
    (pad "1" smd roundrect (at -0.484 0 270) (size 0.59 0.64) (layers "B.Cu" "B.Paste" "B.Mask") (roundrect_rratio 0.25)
      (net 8 "SOM_5V0") (pintype "passive"))
    (pad "2" smd roundrect (at 0.484 0 270) (size 0.59 0.64) (layers "B.Cu" "B.Paste" "B.Mask") (roundrect_rratio 0.25)
      (net 1 "GND") (pintype "passive"))
  )

  (footprint "kria-k26-devboard-footprints:C_0805_2012Metric" (layer "B.Cu")
    (at 96.19 94.91)
    (descr "Capacitor SMD 0805")
    (tags "capacitor SMD 0805")
    (property "Author" "Antmicro")
    (property "Dielectric" "")
    (property "License" "Apache-2.0")
    (property "MPN" "C0805C476M9PACTU")
    (property "Manufacturer" "KEMET")
    (property "Sheetfile" "k26_som.kicad_sch")
    (property "Sheetname" "Xilinx K26 SOM")
    (property "Val" "47u")
    (property "Voltage" "")
    (property "ki_description" " ")
    (attr smd)
    (fp_text reference "C119" (at 4.695 0.435 180) (layer "B.SilkS")
        (effects (font (size 0.7 0.7) (thickness 0.15)) (justify left bottom mirror))
    )
    (fp_text value "C_47u_0805" (at 0 -1.947 180) (layer "B.Fab") hide
        (effects (font (size 0.7 0.7) (thickness 0.15)) (justify left bottom mirror))
    )
    (fp_text user "${REFERENCE}" (at -1.9 -3.947 180) (layer "B.Fab") hide
        (effects (font (size 0.7 0.7) (thickness 0.15)) (justify left bottom mirror))
    )
    (fp_text user "Author: Antmicro" (at -1.9 -5.947 180) (layer "B.Fab") hide
        (effects (font (size 0.7 0.7) (thickness 0.15)) (justify left bottom mirror))
    )
    (fp_text user "License: Apache-2.0" (at -1.9 -4.947 180) (layer "B.Fab") hide
        (effects (font (size 0.7 0.7) (thickness 0.15)) (justify left bottom mirror))
    )
    (fp_line (start -0.3 -0.8) (end 0.3 -0.8)
      (stroke (width 0.15) (type solid)) (layer "B.SilkS"))
    (fp_line (start -0.3 0.8) (end 0.3 0.8)
      (stroke (width 0.15) (type solid)) (layer "B.SilkS"))
    (fp_rect (start -1.9 0.93) (end 1.9 -0.93)
      (stroke (width 0.05) (type solid)) (fill none) (layer "B.CrtYd"))
    (fp_rect (start -0.95 0.675) (end 0.95 -0.675)
      (stroke (width 0.15) (type solid)) (fill none) (layer "B.Fab"))
    (pad "1" smd rect (at -1.05 0) (size 1.2 1.2) (layers "B.Cu" "B.Paste" "B.Mask")
      (net 8 "SOM_5V0") (pintype "passive"))
    (pad "2" smd rect (at 1.05 0) (size 1.2 1.2) (layers "B.Cu" "B.Paste" "B.Mask")
      (net 1 "GND") (pintype "passive"))
  )

  (footprint "kria-k26-devboard-footprints:C_0805_2012Metric" (layer "B.Cu")
    (at 96.215 96.785)
    (descr "Capacitor SMD 0805")
    (tags "capacitor SMD 0805")
    (property "Author" "Antmicro")
    (property "Dielectric" "")
    (property "License" "Apache-2.0")
    (property "MPN" "C0805C476M9PACTU")
    (property "Manufacturer" "KEMET")
    (property "Sheetfile" "k26_som.kicad_sch")
    (property "Sheetname" "Xilinx K26 SOM")
    (property "Val" "47u")
    (property "Voltage" "")
    (property "ki_description" " ")
    (attr smd)
    (fp_text reference "C120" (at 4.695 0.435 180) (layer "B.SilkS")
        (effects (font (size 0.7 0.7) (thickness 0.15)) (justify left bottom mirror))
    )
    (fp_text value "C_47u_0805" (at 0 -1.947 180) (layer "B.Fab") hide
        (effects (font (size 0.7 0.7) (thickness 0.15)) (justify left bottom mirror))
    )
    (fp_text user "${REFERENCE}" (at -1.9 -3.947 180) (layer "B.Fab") hide
        (effects (font (size 0.7 0.7) (thickness 0.15)) (justify left bottom mirror))
    )
    (fp_text user "Author: Antmicro" (at -1.9 -5.947 180) (layer "B.Fab") hide
        (effects (font (size 0.7 0.7) (thickness 0.15)) (justify left bottom mirror))
    )
    (fp_text user "License: Apache-2.0" (at -1.9 -4.947 180) (layer "B.Fab") hide
        (effects (font (size 0.7 0.7) (thickness 0.15)) (justify left bottom mirror))
    )
    (fp_line (start -0.3 -0.8) (end 0.3 -0.8)
      (stroke (width 0.15) (type solid)) (layer "B.SilkS"))
    (fp_line (start -0.3 0.8) (end 0.3 0.8)
      (stroke (width 0.15) (type solid)) (layer "B.SilkS"))
    (fp_rect (start -1.9 0.93) (end 1.9 -0.93)
      (stroke (width 0.05) (type solid)) (fill none) (layer "B.CrtYd"))
    (fp_rect (start -0.95 0.675) (end 0.95 -0.675)
      (stroke (width 0.15) (type solid)) (fill none) (layer "B.Fab"))
    (pad "1" smd rect (at -1.05 0) (size 1.2 1.2) (layers "B.Cu" "B.Paste" "B.Mask")
      (net 8 "SOM_5V0") (pintype "passive"))
    (pad "2" smd rect (at 1.05 0) (size 1.2 1.2) (layers "B.Cu" "B.Paste" "B.Mask")
      (net 1 "GND") (pintype "passive"))
  )

  (footprint "kria-k26-devboard-footprints:C_0402_1005Metric" (layer "B.Cu")
    (at 95.5 99.2)
    (descr "Capacitor SMD 0402")
    (tags "capacitor SMD 0402")
    (property "Author" "Antmicro")
    (property "Dielectric" "")
    (property "License" "Apache-2.0")
    (property "MPN" "C1005X6S1A105K050BC")
    (property "Manufacturer" "TDK")
    (property "Sheetfile" "k26_som.kicad_sch")
    (property "Sheetname" "Xilinx K26 SOM")
    (property "Val" "1u")
    (property "Voltage" "")
    (property "ki_description" " ")
    (attr smd)
    (fp_text reference "C121" (at 1.39 2.34 180) (layer "B.SilkS")
        (effects (font (size 0.7 0.7) (thickness 0.15)) (justify left bottom mirror))
    )
    (fp_text value "C_1u_0402" (at 0 -1.4 180) (layer "B.Fab") hide
        (effects (font (size 0.7 0.7) (thickness 0.15)) (justify left bottom mirror))
    )
    (fp_text user "License: Apache-2.0" (at -0.932 -5.17 180) (layer "B.Fab") hide
        (effects (font (size 0.7 0.7) (thickness 0.15)) (justify left bottom mirror))
    )
    (fp_text user "${REFERENCE}" (at -0.932 -3.168 180) (layer "B.Fab") hide
        (effects (font (size 0.7 0.7) (thickness 0.15)) (justify left bottom mirror))
    )
    (fp_text user "Author: Antmicro" (at -0.932 -4.17 180) (layer "B.Fab") hide
        (effects (font (size 0.7 0.7) (thickness 0.15)) (justify left bottom mirror))
    )
    (fp_rect (start -0.94 0.47) (end 0.94 -0.47)
      (stroke (width 0.05) (type solid)) (fill none) (layer "B.CrtYd"))
    (fp_rect (start -0.499 0.249) (end 0.499 -0.249)
      (stroke (width 0.15) (type solid)) (fill none) (layer "B.Fab"))
    (pad "1" smd roundrect (at -0.484 0) (size 0.59 0.64) (layers "B.Cu" "B.Paste" "B.Mask") (roundrect_rratio 0.25)
      (net 8 "SOM_5V0") (pintype "passive"))
    (pad "2" smd roundrect (at 0.484 0) (size 0.59 0.64) (layers "B.Cu" "B.Paste" "B.Mask") (roundrect_rratio 0.25)
      (net 1 "GND") (pintype "passive"))
  )

  (footprint "kria-k26-devboard-footprints:C_0402_1005Metric" (layer "B.Cu")
    (at 95.5 98.2)
    (descr "Capacitor SMD 0402")
    (tags "capacitor SMD 0402")
    (property "Author" "Antmicro")
    (property "Dielectric" "X5R")
    (property "License" "Apache-2.0")
    (property "MPN" "GRM155R61H104KE14D")
    (property "Manufacturer" "Murata")
    (property "Sheetfile" "k26_som.kicad_sch")
    (property "Sheetname" "Xilinx K26 SOM")
    (property "Val" "100n")
    (property "Voltage" "50V")
    (property "ki_description" " ")
    (attr smd)
    (fp_text reference "C122" (at 1.39 2.34 180) (layer "B.SilkS")
        (effects (font (size 0.7 0.7) (thickness 0.15)) (justify left bottom mirror))
    )
    (fp_text value "C_100n_0402" (at 0 -1.4 180) (layer "B.Fab") hide
        (effects (font (size 0.7 0.7) (thickness 0.15)) (justify left bottom mirror))
    )
    (fp_text user "${REFERENCE}" (at -0.932 -3.168 180) (layer "B.Fab") hide
        (effects (font (size 0.7 0.7) (thickness 0.15)) (justify left bottom mirror))
    )
    (fp_text user "License: Apache-2.0" (at -0.932 -5.17 180) (layer "B.Fab") hide
        (effects (font (size 0.7 0.7) (thickness 0.15)) (justify left bottom mirror))
    )
    (fp_text user "Author: Antmicro" (at -0.932 -4.17 180) (layer "B.Fab") hide
        (effects (font (size 0.7 0.7) (thickness 0.15)) (justify left bottom mirror))
    )
    (fp_rect (start -0.94 0.47) (end 0.94 -0.47)
      (stroke (width 0.05) (type solid)) (fill none) (layer "B.CrtYd"))
    (fp_rect (start -0.499 0.249) (end 0.499 -0.249)
      (stroke (width 0.15) (type solid)) (fill none) (layer "B.Fab"))
    (pad "1" smd roundrect (at -0.484 0) (size 0.59 0.64) (layers "B.Cu" "B.Paste" "B.Mask") (roundrect_rratio 0.25)
      (net 8 "SOM_5V0") (pintype "passive"))
    (pad "2" smd roundrect (at 0.484 0) (size 0.59 0.64) (layers "B.Cu" "B.Paste" "B.Mask") (roundrect_rratio 0.25)
      (net 1 "GND") (pintype "passive"))
  )

  (footprint "kria-k26-devboard-footprints:C_0402_1005Metric" (layer "B.Cu")
    (at 92.5 127.775)
    (descr "Capacitor SMD 0402")
    (tags "capacitor SMD 0402")
    (property "Author" "Antmicro")
    (property "Dielectric" "X5R")
    (property "License" "Apache-2.0")
    (property "MPN" "GRM155R61H104KE14D")
    (property "Manufacturer" "Murata")
    (property "Sheetfile" "k26_som.kicad_sch")
    (property "Sheetname" "Xilinx K26 SOM")
    (property "Val" "100n")
    (property "Voltage" "50V")
    (property "ki_description" " ")
    (attr smd)
    (fp_text reference "C129" (at 3.77 0.335 180) (layer "B.SilkS")
        (effects (font (size 0.7 0.7) (thickness 0.15)) (justify left bottom mirror))
    )
    (fp_text value "C_100n_0402" (at 0 -1.4 180) (layer "B.Fab") hide
        (effects (font (size 0.7 0.7) (thickness 0.15)) (justify left bottom mirror))
    )
    (fp_text user "License: Apache-2.0" (at -0.932 -5.17 180) (layer "B.Fab") hide
        (effects (font (size 0.7 0.7) (thickness 0.15)) (justify left bottom mirror))
    )
    (fp_text user "Author: Antmicro" (at -0.932 -4.17 180) (layer "B.Fab") hide
        (effects (font (size 0.7 0.7) (thickness 0.15)) (justify left bottom mirror))
    )
    (fp_text user "${REFERENCE}" (at -0.932 -3.168 180) (layer "B.Fab") hide
        (effects (font (size 0.7 0.7) (thickness 0.15)) (justify left bottom mirror))
    )
    (fp_rect (start -0.94 0.47) (end 0.94 -0.47)
      (stroke (width 0.05) (type solid)) (fill none) (layer "B.CrtYd"))
    (fp_rect (start -0.499 0.249) (end 0.499 -0.249)
      (stroke (width 0.15) (type solid)) (fill none) (layer "B.Fab"))
    (pad "1" smd roundrect (at -0.484 0) (size 0.59 0.64) (layers "B.Cu" "B.Paste" "B.Mask") (roundrect_rratio 0.25)
      (net 20 "PL_3V3") (pintype "passive"))
    (pad "2" smd roundrect (at 0.484 0) (size 0.59 0.64) (layers "B.Cu" "B.Paste" "B.Mask") (roundrect_rratio 0.25)
      (net 1 "GND") (pintype "passive"))
  )

  (footprint "kria-k26-devboard-footprints:C_0402_1005Metric" (layer "B.Cu")
    (at 77.7 129.4 180)
    (descr "Capacitor SMD 0402")
    (tags "capacitor SMD 0402")
    (property "Author" "Antmicro")
    (property "Dielectric" "X5R")
    (property "License" "Apache-2.0")
    (property "MPN" "GRM155R61H104KE14D")
    (property "Manufacturer" "Murata")
    (property "Sheetfile" "debug.kicad_sch")
    (property "Sheetname" "Debug and JTAG")
    (property "Val" "100n")
    (property "Voltage" "50V")
    (property "ki_description" " ")
    (attr smd)
    (fp_text reference "C161" (at -1.44 0.61) (layer "B.SilkS")
        (effects (font (size 0.7 0.7) (thickness 0.15)) (justify left bottom mirror))
    )
    (fp_text value "C_100n_0402" (at 0 -1.4) (layer "B.Fab") hide
        (effects (font (size 0.7 0.7) (thickness 0.15)) (justify left bottom mirror))
    )
    (fp_text user "Author: Antmicro" (at -0.932 -4.17) (layer "B.Fab") hide
        (effects (font (size 0.7 0.7) (thickness 0.15)) (justify left bottom mirror))
    )
    (fp_text user "License: Apache-2.0" (at -0.932 -5.17) (layer "B.Fab") hide
        (effects (font (size 0.7 0.7) (thickness 0.15)) (justify left bottom mirror))
    )
    (fp_text user "${REFERENCE}" (at -0.932 -3.168) (layer "B.Fab") hide
        (effects (font (size 0.7 0.7) (thickness 0.15)) (justify left bottom mirror))
    )
    (fp_rect (start -0.94 0.47) (end 0.94 -0.47)
      (stroke (width 0.05) (type solid)) (fill none) (layer "B.CrtYd"))
    (fp_rect (start -0.499 0.249) (end 0.499 -0.249)
      (stroke (width 0.15) (type solid)) (fill none) (layer "B.Fab"))
    (pad "1" smd roundrect (at -0.484 0 180) (size 0.59 0.64) (layers "B.Cu" "B.Paste" "B.Mask") (roundrect_rratio 0.25)
      (net 17 "PS_1V8") (pintype "passive"))
    (pad "2" smd roundrect (at 0.484 0 180) (size 0.59 0.64) (layers "B.Cu" "B.Paste" "B.Mask") (roundrect_rratio 0.25)
      (net 1 "GND") (pintype "passive"))
  )

  (footprint "kria-k26-devboard-footprints:SOT-23-3" (layer "B.Cu")
    (at 119.85 146.05)
    (property "Author" "Antmicro")
    (property "License" "Apache-2.0")
    (property "MPN" "BSS123")
    (property "Manufacturer" "ON Semiconductor")
    (property "Sheetfile" "sd-3-card.kicad_sch")
    (property "Sheetname" "SD 3.0 card")
    (attr smd)
    (fp_text reference "Q1" (at 0.71 2.48 180) (layer "B.SilkS")
        (effects (font (size 0.7 0.7) (thickness 0.15)) (justify left bottom mirror))
    )
    (fp_text value "BSS123" (at -1.9 -2.7 180) (layer "B.Fab") hide
        (effects (font (size 0.7 0.7) (thickness 0.15)) (justify left bottom mirror))
    )
    (fp_text user "Author: Antmicro" (at -1.837 -5.3 180) (layer "B.Fab") hide
        (effects (font (size 0.7 0.7) (thickness 0.15)) (justify left bottom mirror))
    )
    (fp_text user "License: Apache-2.0" (at -1.8 -6.8 180) (layer "B.Fab") hide
        (effects (font (size 0.7 0.7) (thickness 0.15)) (justify left bottom mirror))
    )
    (fp_text user "${REFERENCE}" (at -1.837 -4 180) (layer "B.Fab") hide
        (effects (font (size 0.7 0.7) (thickness 0.15)) (justify left bottom mirror))
    )
    (fp_line (start -1.45 1.35) (end -0.85 1.35)
      (stroke (width 0.15) (type solid)) (layer "B.SilkS"))
    (fp_line (start -0.85 1.35) (end -0.7 1.5)
      (stroke (width 0.15) (type solid)) (layer "B.SilkS"))
    (fp_line (start -0.7 -1.5) (end -0.7 -1.35)
      (stroke (width 0.15) (type solid)) (layer "B.SilkS"))
    (fp_line (start 0.7 -1.5) (end -0.7 -1.5)
      (stroke (width 0.15) (type solid)) (layer "B.SilkS"))
    (fp_line (start 0.7 -0.4) (end 0.7 -1.5)
      (stroke (width 0.15) (type solid)) (layer "B.SilkS"))
    (fp_line (start 0.7 0.4) (end 0.7 1.5)
      (stroke (width 0.15) (type solid)) (layer "B.SilkS"))
    (fp_line (start 0.7 1.5) (end -0.7 1.5)
      (stroke (width 0.15) (type solid)) (layer "B.SilkS"))
    (fp_line (start -1.75 -1.4) (end -1.75 -0.5)
      (stroke (width 0.05) (type solid)) (layer "B.CrtYd"))
    (fp_line (start -1.75 -0.5) (end -0.85 -0.5)
      (stroke (width 0.05) (type solid)) (layer "B.CrtYd"))
    (fp_line (start -1.75 0.5) (end -1.75 1.4)
      (stroke (width 0.05) (type solid)) (layer "B.CrtYd"))
    (fp_line (start -0.9 1.4) (end -1.75 1.4)
      (stroke (width 0.05) (type solid)) (layer "B.CrtYd"))
    (fp_line (start -0.9 1.6) (end -0.9 1.4)
      (stroke (width 0.05) (type solid)) (layer "B.CrtYd"))
    (fp_line (start -0.9 1.6) (end 0.825 1.6)
      (stroke (width 0.05) (type solid)) (layer "B.CrtYd"))
    (fp_line (start -0.85 -1.65) (end -0.85 -1.4)
      (stroke (width 0.05) (type solid)) (layer "B.CrtYd"))
    (fp_line (start -0.85 -1.4) (end -1.75 -1.4)
      (stroke (width 0.05) (type solid)) (layer "B.CrtYd"))
    (fp_line (start -0.85 -0.5) (end -0.85 0.5)
      (stroke (width 0.05) (type solid)) (layer "B.CrtYd"))
    (fp_line (start -0.85 0.5) (end -1.75 0.5)
      (stroke (width 0.05) (type solid)) (layer "B.CrtYd"))
    (fp_line (start 0.825 0.45) (end 1.75 0.45)
      (stroke (width 0.05) (type solid)) (layer "B.CrtYd"))
    (fp_line (start 0.825 1.6) (end 0.825 0.45)
      (stroke (width 0.05) (type solid)) (layer "B.CrtYd"))
    (fp_line (start 0.85 -1.65) (end -0.85 -1.65)
      (stroke (width 0.05) (type solid)) (layer "B.CrtYd"))
    (fp_line (start 0.85 -0.45) (end 0.85 -1.65)
      (stroke (width 0.05) (type solid)) (layer "B.CrtYd"))
    (fp_line (start 1.75 -0.45) (end 0.85 -0.45)
      (stroke (width 0.05) (type solid)) (layer "B.CrtYd"))
    (fp_line (start 1.75 0.45) (end 1.75 -0.45)
      (stroke (width 0.05) (type solid)) (layer "B.CrtYd"))
    (fp_line (start -0.712 -1.519) (end 0.688 -1.519)
      (stroke (width 0.15) (type solid)) (layer "B.Fab"))
    (fp_line (start -0.712 1.325) (end -0.712 -1.523)
      (stroke (width 0.15) (type solid)) (layer "B.Fab"))
    (fp_line (start -0.437 1.526) (end -0.712 1.325)
      (stroke (width 0.15) (type solid)) (layer "B.Fab"))
    (fp_line (start -0.437 1.526) (end 0.688 1.526)
      (stroke (width 0.15) (type solid)) (layer "B.Fab"))
    (fp_line (start 0.688 -1.519) (end 0.688 1.52)
      (stroke (width 0.15) (type solid)) (layer "B.Fab"))
    (pad "1" smd roundrect (at -1.1 0.951) (size 1 0.6) (layers "B.Cu" "B.Paste" "B.Mask") (roundrect_rratio 0.15)
      (net 177 "/Reset logic/~{SD_CARD_RESET}") (pinfunction "G") (pintype "bidirectional"))
    (pad "2" smd roundrect (at -1.1 -0.949) (size 1 0.6) (layers "B.Cu" "B.Paste" "B.Mask") (roundrect_rratio 0.15)
      (net 1 "GND") (pinfunction "S") (pintype "bidirectional"))
    (pad "3" smd roundrect (at 1.1 0.0005) (size 1 0.6) (layers "B.Cu" "B.Paste" "B.Mask") (roundrect_rratio 0.15)
      (net 415 "Net-(Q1-D)") (pinfunction "D") (pintype "bidirectional"))
  )

  (footprint "kria-k26-devboard-footprints:SOT-23-3" (layer "B.Cu")
    (at 127.45 146.05)
    (property "Author" "Antmicro")
    (property "License" "Apache-2.0")
    (property "MPN" "AO3401A")
    (property "Manufacturer" "Alpha & Omega Semiconductor Inc.")
    (property "Sheetfile" "sd-3-card.kicad_sch")
    (property "Sheetname" "SD 3.0 card")
    (attr smd)
    (fp_text reference "Q2" (at 0.74 2.49 180) (layer "B.SilkS")
        (effects (font (size 0.7 0.7) (thickness 0.15)) (justify left bottom mirror))
    )
    (fp_text value "AO3401A" (at -1.9 -2.7 180) (layer "B.Fab") hide
        (effects (font (size 0.7 0.7) (thickness 0.15)) (justify left bottom mirror))
    )
    (fp_text user "License: Apache-2.0" (at -1.8 -6.8 180) (layer "B.Fab") hide
        (effects (font (size 0.7 0.7) (thickness 0.15)) (justify left bottom mirror))
    )
    (fp_text user "Author: Antmicro" (at -1.837 -5.3 180) (layer "B.Fab") hide
        (effects (font (size 0.7 0.7) (thickness 0.15)) (justify left bottom mirror))
    )
    (fp_text user "${REFERENCE}" (at -1.837 -4 180) (layer "B.Fab") hide
        (effects (font (size 0.7 0.7) (thickness 0.15)) (justify left bottom mirror))
    )
    (fp_line (start -1.45 1.35) (end -0.85 1.35)
      (stroke (width 0.15) (type solid)) (layer "B.SilkS"))
    (fp_line (start -0.85 1.35) (end -0.7 1.5)
      (stroke (width 0.15) (type solid)) (layer "B.SilkS"))
    (fp_line (start -0.7 -1.5) (end -0.7 -1.35)
      (stroke (width 0.15) (type solid)) (layer "B.SilkS"))
    (fp_line (start 0.7 -1.5) (end -0.7 -1.5)
      (stroke (width 0.15) (type solid)) (layer "B.SilkS"))
    (fp_line (start 0.7 -0.4) (end 0.7 -1.5)
      (stroke (width 0.15) (type solid)) (layer "B.SilkS"))
    (fp_line (start 0.7 0.4) (end 0.7 1.5)
      (stroke (width 0.15) (type solid)) (layer "B.SilkS"))
    (fp_line (start 0.7 1.5) (end -0.7 1.5)
      (stroke (width 0.15) (type solid)) (layer "B.SilkS"))
    (fp_line (start -1.75 -1.4) (end -1.75 -0.5)
      (stroke (width 0.05) (type solid)) (layer "B.CrtYd"))
    (fp_line (start -1.75 -0.5) (end -0.85 -0.5)
      (stroke (width 0.05) (type solid)) (layer "B.CrtYd"))
    (fp_line (start -1.75 0.5) (end -1.75 1.4)
      (stroke (width 0.05) (type solid)) (layer "B.CrtYd"))
    (fp_line (start -0.9 1.4) (end -1.75 1.4)
      (stroke (width 0.05) (type solid)) (layer "B.CrtYd"))
    (fp_line (start -0.9 1.6) (end -0.9 1.4)
      (stroke (width 0.05) (type solid)) (layer "B.CrtYd"))
    (fp_line (start -0.9 1.6) (end 0.825 1.6)
      (stroke (width 0.05) (type solid)) (layer "B.CrtYd"))
    (fp_line (start -0.85 -1.65) (end -0.85 -1.4)
      (stroke (width 0.05) (type solid)) (layer "B.CrtYd"))
    (fp_line (start -0.85 -1.4) (end -1.75 -1.4)
      (stroke (width 0.05) (type solid)) (layer "B.CrtYd"))
    (fp_line (start -0.85 -0.5) (end -0.85 0.5)
      (stroke (width 0.05) (type solid)) (layer "B.CrtYd"))
    (fp_line (start -0.85 0.5) (end -1.75 0.5)
      (stroke (width 0.05) (type solid)) (layer "B.CrtYd"))
    (fp_line (start 0.825 0.45) (end 1.75 0.45)
      (stroke (width 0.05) (type solid)) (layer "B.CrtYd"))
    (fp_line (start 0.825 1.6) (end 0.825 0.45)
      (stroke (width 0.05) (type solid)) (layer "B.CrtYd"))
    (fp_line (start 0.85 -1.65) (end -0.85 -1.65)
      (stroke (width 0.05) (type solid)) (layer "B.CrtYd"))
    (fp_line (start 0.85 -0.45) (end 0.85 -1.65)
      (stroke (width 0.05) (type solid)) (layer "B.CrtYd"))
    (fp_line (start 1.75 -0.45) (end 0.85 -0.45)
      (stroke (width 0.05) (type solid)) (layer "B.CrtYd"))
    (fp_line (start 1.75 0.45) (end 1.75 -0.45)
      (stroke (width 0.05) (type solid)) (layer "B.CrtYd"))
    (fp_line (start -0.712 -1.519) (end 0.688 -1.519)
      (stroke (width 0.15) (type solid)) (layer "B.Fab"))
    (fp_line (start -0.712 1.325) (end -0.712 -1.523)
      (stroke (width 0.15) (type solid)) (layer "B.Fab"))
    (fp_line (start -0.437 1.526) (end -0.712 1.325)
      (stroke (width 0.15) (type solid)) (layer "B.Fab"))
    (fp_line (start -0.437 1.526) (end 0.688 1.526)
      (stroke (width 0.15) (type solid)) (layer "B.Fab"))
    (fp_line (start 0.688 -1.519) (end 0.688 1.52)
      (stroke (width 0.15) (type solid)) (layer "B.Fab"))
    (pad "1" smd roundrect (at -1.1 0.951) (size 1 0.6) (layers "B.Cu" "B.Paste" "B.Mask") (roundrect_rratio 0.15)
      (net 131 "Net-(Q2-G)") (pinfunction "G") (pintype "bidirectional"))
    (pad "2" smd roundrect (at -1.1 -0.949) (size 1 0.6) (layers "B.Cu" "B.Paste" "B.Mask") (roundrect_rratio 0.15)
      (net 15 "PS_3V3") (pinfunction "S") (pintype "bidirectional"))
    (pad "3" smd roundrect (at 1.1 0.0005) (size 1 0.6) (layers "B.Cu" "B.Paste" "B.Mask") (roundrect_rratio 0.15)
      (net 317 "/SD 3.0 card/SD_VDD") (pinfunction "D") (pintype "bidirectional"))
  )

  (footprint "kria-k26-devboard-footprints:Conn_FFC_WE_68715014x22_ALT" locked (layer "B.Cu")
    (at 79.76 102 90)
    (property "Author" "Antmicro")
    (property "License" "Apache-2.0")
    (property "MPN" "68715014522")
    (property "Manufacturer" "Würth Elektronik")
    (property "Sheetfile" "camera.kicad_sch")
    (property "Sheetname" "Camera interface")
    (property "VSD_Class" "Antmicro Dual Camera interface")
    (property "ki_description" "FFC connector")
    (property "ki_keywords" "CONNECTOR")
    (attr smd)
    (fp_text reference "J3" (at 0 6.4 270) (layer "B.SilkS")
        (effects (font (size 0.7 0.7) (thickness 0.15)) (justify left bottom mirror))
    )
    (fp_text value "Conn_FFC_WE_68715014522_CUSTOM_TWO-SIDES" (at -0.3 -3.899 270) (layer "B.Fab")
        (effects (font (size 0.7 0.7) (thickness 0.15)) (justify left bottom mirror))
    )
    (fp_text user "License: Apache-2.0" (at -15.861 -7.9 270) (layer "B.Fab") hide
        (effects (font (size 0.7 0.7) (thickness 0.15)) (justify left bottom mirror))
    )
    (fp_text user "${REFERENCE}" (at -15.861 -5.9 270) (layer "B.Fab") hide
        (effects (font (size 0.7 0.7) (thickness 0.15)) (justify left bottom mirror))
    )
    (fp_text user "Author: Antmicro" (at -15.861 -6.9 270) (layer "B.Fab") hide
        (effects (font (size 0.7 0.7) (thickness 0.15)) (justify left bottom mirror))
    )
    (fp_line (start -15.861 -1.298) (end -15.861 2.15)
      (stroke (width 0.15) (type solid)) (layer "B.SilkS"))
    (fp_line (start -15.83 2.15) (end -12.5 2.15)
      (stroke (width 0.15) (type solid)) (layer "B.SilkS"))
    (fp_line (start -12.561 -1.33) (end -15.84 -1.33)
      (stroke (width 0.15) (type solid)) (layer "B.SilkS"))
    (fp_line (start -12.5 1.325) (end -12.5 -1.33)
      (stroke (width 0.15) (type solid)) (layer "B.SilkS"))
    (fp_line (start -12.5 1.325) (end 12.499 1.325)
      (stroke (width 0.15) (type solid)) (layer "B.SilkS"))
    (fp_line (start -12.5 2.15) (end -12.5 3.4)
      (stroke (width 0.15) (type solid)) (layer "B.SilkS"))
    (fp_line (start -12.5 2.976) (end 12.499 2.976)
      (stroke (width 0.15) (type solid)) (layer "B.SilkS"))
    (fp_line (start 12.499 -1.29) (end 15.839 -1.29)
      (stroke (width 0.15) (type solid)) (layer "B.SilkS"))
    (fp_line (start 12.499 1.325) (end 12.499 -1.259)
      (stroke (width 0.15) (type solid)) (layer "B.SilkS"))
    (fp_line (start 12.499 2.15) (end 12.499 2.976)
      (stroke (width 0.15) (type solid)) (layer "B.SilkS"))
    (fp_line (start 15.81 2.15) (end 12.499 2.15)
      (stroke (width 0.15) (type solid)) (layer "B.SilkS"))
    (fp_line (start 15.839 -1.29) (end 15.839 2.15)
      (stroke (width 0.15) (type solid)) (layer "B.SilkS"))
    (fp_circle (center -12.25 3.86) (end -12.2 3.81)
      (stroke (width 0.15) (type solid)) (fill solid) (layer "B.SilkS"))
    (fp_rect (start -16.201 6.001) (end 16.198 -3.548)
      (stroke (width 0.05) (type solid)) (fill none) (layer "B.CrtYd"))
    (pad "1" smd roundrect locked (at -12.25 2.15 90) (size 0.3 1.2) (layers "B.Cu" "B.Paste" "B.Mask") (roundrect_rratio 0.25)
      (net 219 "/Camera interface/HPA04_N") (pintype "passive"))
    (pad "2" smd roundrect locked (at -11.75 2.15 90) (size 0.3 1.2) (layers "B.Cu" "B.Paste" "B.Mask") (roundrect_rratio 0.25)
      (net 218 "/Camera interface/HPA04_P") (pintype "passive"))
    (pad "3" smd roundrect locked (at -11.25 2.15 90) (size 0.3 1.2) (layers "B.Cu" "B.Paste" "B.Mask") (roundrect_rratio 0.25)
      (net 217 "/Camera interface/HPA03_N") (pintype "passive"))
    (pad "4" smd roundrect locked (at -10.75 2.15 90) (size 0.3 1.2) (layers "B.Cu" "B.Paste" "B.Mask") (roundrect_rratio 0.25)
      (net 216 "/Camera interface/HPA03_P") (pintype "passive"))
    (pad "5" smd roundrect locked (at -10.25 2.15 90) (size 0.3 1.2) (layers "B.Cu" "B.Paste" "B.Mask") (roundrect_rratio 0.25)
      (net 215 "/Camera interface/HPA02_N") (pintype "passive"))
    (pad "6" smd roundrect locked (at -9.75 2.15 90) (size 0.3 1.2) (layers "B.Cu" "B.Paste" "B.Mask") (roundrect_rratio 0.25)
      (net 214 "/Camera interface/HPA02_P") (pintype "passive"))
    (pad "7" smd roundrect locked (at -9.25 2.15 90) (size 0.3 1.2) (layers "B.Cu" "B.Paste" "B.Mask") (roundrect_rratio 0.25)
      (net 213 "/Camera interface/HPA01_N") (pintype "passive"))
    (pad "8" smd roundrect locked (at -8.75 2.15 90) (size 0.3 1.2) (layers "B.Cu" "B.Paste" "B.Mask") (roundrect_rratio 0.25)
      (net 212 "/Camera interface/HPA01_P") (pintype "passive"))
    (pad "9" smd roundrect locked (at -8.25 2.15 90) (size 0.3 1.2) (layers "B.Cu" "B.Paste" "B.Mask") (roundrect_rratio 0.25)
      (net 1 "GND") (pintype "passive"))
    (pad "10" smd roundrect locked (at -7.75 2.15 90) (size 0.3 1.2) (layers "B.Cu" "B.Paste" "B.Mask") (roundrect_rratio 0.25)
      (net 211 "/Camera interface/HPA00_CC_N") (pintype "passive"))
    (pad "11" smd roundrect locked (at -7.25 2.15 90) (size 0.3 1.2) (layers "B.Cu" "B.Paste" "B.Mask") (roundrect_rratio 0.25)
      (net 210 "/Camera interface/HPA00_CC_P") (pintype "passive"))
    (pad "12" smd roundrect locked (at -6.75 2.15 90) (size 0.3 1.2) (layers "B.Cu" "B.Paste" "B.Mask") (roundrect_rratio 0.25)
      (net 1 "GND") (pintype "passive"))
    (pad "13" smd roundrect locked (at -6.25 2.15 90) (size 0.3 1.2) (layers "B.Cu" "B.Paste" "B.Mask") (roundrect_rratio 0.25)
      (net 416 "unconnected-(J3-Pad13)") (pintype "passive+no_connect"))
    (pad "14" smd roundrect locked (at -5.75 2.15 90) (size 0.3 1.2) (layers "B.Cu" "B.Paste" "B.Mask") (roundrect_rratio 0.25)
      (net 417 "unconnected-(J3-Pad14)") (pintype "passive+no_connect"))
    (pad "15" smd roundrect locked (at -5.25 2.15 90) (size 0.3 1.2) (layers "B.Cu" "B.Paste" "B.Mask") (roundrect_rratio 0.25)
      (net 1 "GND") (pintype "passive"))
    (pad "16" smd roundrect locked (at -4.75 2.15 90) (size 0.3 1.2) (layers "B.Cu" "B.Paste" "B.Mask") (roundrect_rratio 0.25)
      (net 418 "unconnected-(J3-Pad16)") (pintype "passive+no_connect"))
    (pad "17" smd roundrect locked (at -4.25 2.15 90) (size 0.3 1.2) (layers "B.Cu" "B.Paste" "B.Mask") (roundrect_rratio 0.25)
      (net 419 "unconnected-(J3-Pad17)") (pintype "passive+no_connect"))
    (pad "18" smd roundrect locked (at -3.75 2.15 90) (size 0.3 1.2) (layers "B.Cu" "B.Paste" "B.Mask") (roundrect_rratio 0.25)
      (net 1 "GND") (pintype "passive"))
    (pad "19" smd roundrect locked (at -3.25 2.15 90) (size 0.3 1.2) (layers "B.Cu" "B.Paste" "B.Mask") (roundrect_rratio 0.25)
      (net 209 "/Camera interface/HPA09_N") (pintype "passive"))
    (pad "20" smd roundrect locked (at -2.75 2.15 90) (size 0.3 1.2) (layers "B.Cu" "B.Paste" "B.Mask") (roundrect_rratio 0.25)
      (net 208 "/Camera interface/HPA09_P") (pintype "passive"))
    (pad "21" smd roundrect locked (at -2.25 2.15 90) (size 0.3 1.2) (layers "B.Cu" "B.Paste" "B.Mask") (roundrect_rratio 0.25)
      (net 207 "/Camera interface/HPA08_N") (pintype "passive"))
    (pad "22" smd roundrect locked (at -1.75 2.15 90) (size 0.3 1.2) (layers "B.Cu" "B.Paste" "B.Mask") (roundrect_rratio 0.25)
      (net 206 "/Camera interface/HPA08_P") (pintype "passive"))
    (pad "23" smd roundrect locked (at -1.25 2.15 90) (size 0.3 1.2) (layers "B.Cu" "B.Paste" "B.Mask") (roundrect_rratio 0.25)
      (net 205 "/Camera interface/HPA07_N") (pintype "passive"))
    (pad "24" smd roundrect locked (at -0.75 2.15 90) (size 0.3 1.2) (layers "B.Cu" "B.Paste" "B.Mask") (roundrect_rratio 0.25)
      (net 204 "/Camera interface/HPA07_P") (pintype "passive"))
    (pad "25" smd roundrect locked (at -0.25 2.15 90) (size 0.3 1.2) (layers "B.Cu" "B.Paste" "B.Mask") (roundrect_rratio 0.25)
      (net 203 "/Camera interface/HPA06_N") (pintype "passive"))
    (pad "26" smd roundrect locked (at 0.248 2.15 90) (size 0.3 1.2) (layers "B.Cu" "B.Paste" "B.Mask") (roundrect_rratio 0.25)
      (net 202 "/Camera interface/HPA06_P") (pintype "passive"))
    (pad "27" smd roundrect locked (at 0.748 2.15 90) (size 0.3 1.2) (layers "B.Cu" "B.Paste" "B.Mask") (roundrect_rratio 0.25)
      (net 1 "GND") (pintype "passive"))
    (pad "28" smd roundrect locked (at 1.249 2.15 90) (size 0.3 1.2) (layers "B.Cu" "B.Paste" "B.Mask") (roundrect_rratio 0.25)
      (net 201 "/Camera interface/HPA05_CC_N") (pintype "passive"))
    (pad "29" smd roundrect locked (at 1.749 2.15 90) (size 0.3 1.2) (layers "B.Cu" "B.Paste" "B.Mask") (roundrect_rratio 0.25)
      (net 200 "/Camera interface/HPA05_CC_P") (pintype "passive"))
    (pad "30" smd roundrect locked (at 2.249 2.15 90) (size 0.3 1.2) (layers "B.Cu" "B.Paste" "B.Mask") (roundrect_rratio 0.25)
      (net 1 "GND") (pintype "passive"))
    (pad "31" smd roundrect locked (at 2.749 2.15 90) (size 0.3 1.2) (layers "B.Cu" "B.Paste" "B.Mask") (roundrect_rratio 0.25)
      (net 420 "unconnected-(J3-Pad31)") (pintype "passive+no_connect"))
    (pad "32" smd roundrect locked (at 3.249 2.15 90) (size 0.3 1.2) (layers "B.Cu" "B.Paste" "B.Mask") (roundrect_rratio 0.25)
      (net 199 "/Camera interface/CAM0_VSYNC") (pintype "passive"))
    (pad "33" smd roundrect locked (at 3.749 2.15 90) (size 0.3 1.2) (layers "B.Cu" "B.Paste" "B.Mask") (roundrect_rratio 0.25)
      (net 198 "/Camera interface/CAM0_RST") (pintype "passive"))
    (pad "34" smd roundrect locked (at 4.248 2.15 90) (size 0.3 1.2) (layers "B.Cu" "B.Paste" "B.Mask") (roundrect_rratio 0.25)
      (net 197 "/Camera interface/CAM1_VSYNC") (pintype "passive"))
    (pad "35" smd roundrect locked (at 4.748 2.15 90) (size 0.3 1.2) (layers "B.Cu" "B.Paste" "B.Mask") (roundrect_rratio 0.25)
      (net 421 "unconnected-(J3-Pad35)") (pintype "passive+no_connect"))
    (pad "36" smd roundrect locked (at 5.248 2.15 90) (size 0.3 1.2) (layers "B.Cu" "B.Paste" "B.Mask") (roundrect_rratio 0.25)
      (net 422 "unconnected-(J3-Pad36)") (pintype "passive+no_connect"))
    (pad "37" smd roundrect locked (at 5.749 2.15 90) (size 0.3 1.2) (layers "B.Cu" "B.Paste" "B.Mask") (roundrect_rratio 0.25)
      (net 423 "unconnected-(J3-Pad37)") (pintype "passive+no_connect"))
    (pad "38" smd roundrect locked (at 6.249 2.15 90) (size 0.3 1.2) (layers "B.Cu" "B.Paste" "B.Mask") (roundrect_rratio 0.25)
      (net 424 "unconnected-(J3-Pad38)") (pintype "passive+no_connect"))
    (pad "39" smd roundrect locked (at 6.749 2.15 90) (size 0.3 1.2) (layers "B.Cu" "B.Paste" "B.Mask") (roundrect_rratio 0.25)
      (net 196 "/Camera interface/CCI0_I2C_SDA_3V3") (pintype "passive"))
    (pad "40" smd roundrect locked (at 7.249 2.15 90) (size 0.3 1.2) (layers "B.Cu" "B.Paste" "B.Mask") (roundrect_rratio 0.25)
      (net 195 "/Camera interface/CCI0_I2C_SCL_3V3") (pintype "passive"))
    (pad "41" smd roundrect locked (at 7.749 2.15 90) (size 0.3 1.2) (layers "B.Cu" "B.Paste" "B.Mask") (roundrect_rratio 0.25)
      (net 194 "/Camera interface/CCI1_I2C_SDA_3V3") (pintype "passive"))
    (pad "42" smd roundrect locked (at 8.249 2.15 90) (size 0.3 1.2) (layers "B.Cu" "B.Paste" "B.Mask") (roundrect_rratio 0.25)
      (net 193 "/Camera interface/CCI1_I2C_SCL_3V3") (pintype "passive"))
    (pad "43" smd roundrect locked (at 8.749 2.15 90) (size 0.3 1.2) (layers "B.Cu" "B.Paste" "B.Mask") (roundrect_rratio 0.25)
      (net 425 "unconnected-(J3-Pad43)") (pintype "passive+no_connect"))
    (pad "44" smd roundrect locked (at 9.249 2.15 90) (size 0.3 1.2) (layers "B.Cu" "B.Paste" "B.Mask") (roundrect_rratio 0.25)
      (net 426 "unconnected-(J3-Pad44)") (pintype "passive+no_connect"))
    (pad "45" smd roundrect locked (at 9.749 2.15 90) (size 0.3 1.2) (layers "B.Cu" "B.Paste" "B.Mask") (roundrect_rratio 0.25)
      (net 427 "unconnected-(J3-Pad45)") (pintype "passive+no_connect"))
    (pad "46" smd roundrect locked (at 10.249 2.15 90) (size 0.3 1.2) (layers "B.Cu" "B.Paste" "B.Mask") (roundrect_rratio 0.25)
      (net 428 "unconnected-(J3-Pad46)") (pintype "passive+no_connect"))
    (pad "47" smd roundrect locked (at 10.749 2.15 90) (size 0.3 1.2) (layers "B.Cu" "B.Paste" "B.Mask") (roundrect_rratio 0.25)
      (net 20 "PL_3V3") (pintype "passive"))
    (pad "48" smd roundrect locked (at 11.249 2.15 90) (size 0.3 1.2) (layers "B.Cu" "B.Paste" "B.Mask") (roundrect_rratio 0.25)
      (net 20 "PL_3V3") (pintype "passive"))
    (pad "49" smd roundrect locked (at 11.749 2.15 90) (size 0.3 1.2) (layers "B.Cu" "B.Paste" "B.Mask") (roundrect_rratio 0.25)
      (net 8 "SOM_5V0") (pintype "passive"))
    (pad "50" smd roundrect locked (at 12.249 2.15 90) (size 0.3 1.2) (layers "B.Cu" "B.Paste" "B.Mask") (roundrect_rratio 0.25)
      (net 8 "SOM_5V0") (pintype "passive"))
    (pad "MP1" smd roundrect locked (at -14.201 4 90) (size 2.7 3) (layers "B.Cu" "B.Paste" "B.Mask") (roundrect_rratio 0.05)
      (net 1 "GND") (pinfunction "MP") (pintype "passive"))
    (pad "MP1" smd roundrect locked (at -14.198 0.3 90) (size 2.7 3) (layers "B.Cu" "B.Paste" "B.Mask") (roundrect_rratio 0.05)
      (net 1 "GND") (pinfunction "MP") (pintype "passive"))
    (pad "MP2" smd roundrect locked (at 14.198 0.3 90) (size 2.7 3) (layers "B.Cu" "B.Paste" "B.Mask") (roundrect_rratio 0.05)
      (net 1 "GND") (pinfunction "MP") (pintype "passive"))
    (pad "MP2" smd roundrect locked (at 14.198 4 90) (size 2.7 3) (layers "B.Cu" "B.Paste" "B.Mask") (roundrect_rratio 0.05)
      (net 1 "GND") (pinfunction "MP") (pintype "passive"))
  )

  (footprint "kria-k26-devboard-footprints:Spacer_Drill3mm_H1.5mm_9774015243R" (layer "B.Cu")
    (at 98.788558 122.024722 180)
    (property "Author" "Antmicro")
    (property "License" "Apache-2.0")
    (property "MPN" "9774015243R")
    (property "Manufacturer" "Würth Elektronik")
    (property "Sheetfile" "pcie-m2-key-e.kicad_sch")
    (property "Sheetname" "PCIE M2 key E ")
    (attr through_hole)
    (fp_text reference "SP5" (at -0.091442 -3.555278) (layer "B.SilkS")
        (effects (font (size 0.7 0.7) (thickness 0.15)) (justify left bottom mirror))
    )
    (fp_text value "Spacer_H1.5mm_9774015243R" (at -2.176 -4.25) (layer "B.Fab") hide
        (effects (font (size 0.7 0.7) (thickness 0.15)) (justify left bottom mirror))
    )
    (fp_text user "${REFERENCE}" (at -2.25 -5.5) (layer "B.Fab") hide
        (effects (font (size 0.7 0.7) (thickness 0.15)) (justify left bottom mirror))
    )
    (fp_text user "Author: Antmicro" (at -2.2 -6.75) (layer "B.Fab") hide
        (effects (font (size 0.7 0.7) (thickness 0.15)) (justify left bottom mirror))
    )
    (fp_text user "License: Apache-2.0" (at -2.2 -8) (layer "B.Fab") hide
        (effects (font (size 0.7 0.7) (thickness 0.15)) (justify left bottom mirror))
    )
    (pad "1" thru_hole circle (at 0 0 180) (size 5.3 5.3) (drill 3) (layers "B.Cu" "B.Mask")
      (net 1 "GND") (pintype "passive"))
  )

  (footprint "kria-k26-devboard-footprints:Bus_M.2_Socket_Key_E_TE_1-2199119-6" (layer "B.Cu")
    (at 128.52 122.02 90)
    (property "Author" "Antmicro")
    (property "License" "Apache-2.0")
    (property "MPN" "2199119-6")
    (property "Manufacturer" "TE Connectivity")
    (property "Sheetfile" "pcie-m2-key-e.kicad_sch")
    (property "Sheetname" "PCIE M2 key E ")
    (property "ki_description" "Key E, PCI connector")
    (property "ki_keywords" "HORIZONTAL, SMT, PCIE, CONNECTOR")
    (attr smd)
    (fp_text reference "J12" (at 20.781 0.78) (layer "B.SilkS")
        (effects (font (size 0.7 0.7) (thickness 0.15)) (justify left bottom mirror))
    )
    (fp_text value "Bus_M.2_2199119-6" (at -2 -9.6 270) (layer "B.Fab") hide
        (effects (font (size 0.7 0.7) (thickness 0.15)) (justify left bottom mirror))
    )
    (fp_text user "${REFERENCE}" (at -2 -11 270) (layer "B.Fab") hide
        (effects (font (size 0.7 0.7) (thickness 0.15)) (justify left bottom mirror))
    )
    (fp_text user "License: Apache-2.0" (at -1.95 -13.8 270) (layer "B.Fab") hide
        (effects (font (size 0.7 0.7) (thickness 0.15)) (justify left bottom mirror))
    )
    (fp_text user "Author: Antmicro" (at -1.95 -12.364 270) (layer "B.Fab") hide
        (effects (font (size 0.7 0.7) (thickness 0.15)) (justify left bottom mirror))
    )
    (fp_line (start -10.999 -2.87) (end -10.999 1.481)
      (stroke (width 0.15) (type solid)) (layer "B.SilkS"))
    (fp_line (start -9.599 -4.12) (end -9.249 -4.12)
      (stroke (width 0.15) (type solid)) (layer "B.SilkS"))
    (fp_line (start -9.599 -2.87) (end -10.999 -2.87)
      (stroke (width 0.15) (type solid)) (layer "B.SilkS"))
    (fp_line (start -9.599 -2.87) (end -9.599 -4.12)
      (stroke (width 0.15) (type solid)) (layer "B.SilkS"))
    (fp_line (start -3.75 -4.12) (end -1.75 -4.12)
      (stroke (width 0.15) (type solid)) (layer "B.SilkS"))
    (fp_line (start -3.499 3.88) (end -1.499 3.88)
      (stroke (width 0.15) (type solid)) (layer "B.SilkS"))
    (fp_line (start 9.251 -4.12) (end 9.601 -4.12)
      (stroke (width 0.15) (type solid)) (layer "B.SilkS"))
    (fp_line (start 9.601 -4.12) (end 9.601 -2.87)
      (stroke (width 0.15) (type solid)) (layer "B.SilkS"))
    (fp_line (start 10.999 -2.87) (end 9.601 -2.87)
      (stroke (width 0.15) (type solid)) (layer "B.SilkS"))
    (fp_line (start 10.999 1.481) (end 10.999 -2.87)
      (stroke (width 0.15) (type solid)) (layer "B.SilkS"))
    (fp_line (start -11.2 -3.07) (end -9.8 -3.07)
      (stroke (width 0.05) (type solid)) (layer "B.CrtYd"))
    (fp_line (start -11.2 4.76) (end -11.2 -3.07)
      (stroke (width 0.05) (type solid)) (layer "B.CrtYd"))
    (fp_line (start -9.8 -4.8) (end 9.85 -4.8)
      (stroke (width 0.05) (type solid)) (layer "B.CrtYd"))
    (fp_line (start -9.8 -3.07) (end -9.8 -4.8)
      (stroke (width 0.05) (type solid)) (layer "B.CrtYd"))
    (fp_line (start 9.85 -4.8) (end 9.85 -3.07)
      (stroke (width 0.05) (type solid)) (layer "B.CrtYd"))
    (fp_line (start 9.85 -3.07) (end 11.2 -3.07)
      (stroke (width 0.05) (type solid)) (layer "B.CrtYd"))
    (fp_line (start 11.2 -3.07) (end 11.2 4.76)
      (stroke (width 0.05) (type solid)) (layer "B.CrtYd"))
    (fp_line (start 11.2 4.76) (end -11.2 4.76)
      (stroke (width 0.05) (type solid)) (layer "B.CrtYd"))
    (fp_line (start -10 0.251) (end 9.998 0.251)
      (stroke (width 0.15) (type solid)) (layer "B.Fab"))
    (pad "" np_thru_hole circle (at -10 -1.498 90) (size 1.15 1.15) (drill 1.15) (layers "*.Cu" "*.Mask"))
    (pad "" np_thru_hole circle (at 9.998 -1.498 90) (size 1.6 1.6) (drill 1.6) (layers "*.Cu" "*.Mask"))
    (pad "1" smd rect (at -9.25 3.75 90) (size 0.3 1.55) (layers "B.Cu" "B.Paste" "B.Mask")
      (net 1 "GND") (pinfunction "GND") (pintype "power_in"))
    (pad "2" smd rect (at -9.002 -3.749 90) (size 0.3 1.55) (layers "B.Cu" "B.Paste" "B.Mask")
      (net 15 "PS_3V3") (pinfunction "3.3V") (pintype "power_in"))
    (pad "3" smd rect (at -8.752 3.75 90) (size 0.3 1.55) (layers "B.Cu" "B.Paste" "B.Mask")
      (net 361 "/PCIE M2 key E /M2_USB_P") (pinfunction "USB_D+") (pintype "bidirectional"))
    (pad "4" smd rect (at -8.502 -3.749 90) (size 0.3 1.55) (layers "B.Cu" "B.Paste" "B.Mask")
      (net 15 "PS_3V3") (pinfunction "3.3V") (pintype "passive"))
    (pad "5" smd rect (at -8.252 3.75 90) (size 0.3 1.55) (layers "B.Cu" "B.Paste" "B.Mask")
      (net 360 "/PCIE M2 key E /M2_USB_N") (pinfunction "USB_D-") (pintype "bidirectional"))
    (pad "6" smd rect (at -8.001 -3.749 90) (size 0.3 1.55) (layers "B.Cu" "B.Paste" "B.Mask")
      (net 369 "unconnected-(J12-~{LED_1}-Pad6)") (pinfunction "~{LED_1}") (pintype "output+no_connect"))
    (pad "7" smd rect (at -7.751 3.75 90) (size 0.3 1.55) (layers "B.Cu" "B.Paste" "B.Mask")
      (net 1 "GND") (pinfunction "GND") (pintype "passive"))
    (pad "8" smd rect (at -7.501 -3.749 90) (size 0.3 1.55) (layers "B.Cu" "B.Paste" "B.Mask")
      (net 370 "unconnected-(J12-PCM_CLK-Pad8)") (pinfunction "PCM_CLK") (pintype "bidirectional+no_connect"))
    (pad "9" smd rect (at -7.251 3.75 90) (size 0.3 1.55) (layers "B.Cu" "B.Paste" "B.Mask")
      (net 371 "unconnected-(J12-SDIO_CLK-Pad9)") (pinfunction "SDIO_CLK") (pintype "input+no_connect"))
    (pad "10" smd rect (at -7.001 -3.749 90) (size 0.3 1.55) (layers "B.Cu" "B.Paste" "B.Mask")
      (net 372 "unconnected-(J12-PCM_SYNC-Pad10)") (pinfunction "PCM_SYNC") (pintype "bidirectional+no_connect"))
    (pad "11" smd rect (at -6.751 3.75 90) (size 0.3 1.55) (layers "B.Cu" "B.Paste" "B.Mask")
      (net 373 "unconnected-(J12-SDIO_CMD-Pad11)") (pinfunction "SDIO_CMD") (pintype "bidirectional+no_connect"))
    (pad "12" smd rect (at -6.501 -3.749 90) (size 0.3 1.55) (layers "B.Cu" "B.Paste" "B.Mask")
      (net 374 "unconnected-(J12-PCM_OUT-Pad12)") (pinfunction "PCM_OUT") (pintype "bidirectional+no_connect"))
    (pad "13" smd rect (at -6.251 3.75 90) (size 0.3 1.55) (layers "B.Cu" "B.Paste" "B.Mask")
      (net 375 "unconnected-(J12-SDIO_D0-Pad13)") (pinfunction "SDIO_D0") (pintype "bidirectional+no_connect"))
    (pad "14" smd rect (at -6.001 -3.749 90) (size 0.3 1.55) (layers "B.Cu" "B.Paste" "B.Mask")
      (net 376 "unconnected-(J12-PCM_IN-Pad14)") (pinfunction "PCM_IN") (pintype "bidirectional+no_connect"))
    (pad "15" smd rect (at -5.751 3.75 90) (size 0.3 1.55) (layers "B.Cu" "B.Paste" "B.Mask")
      (net 377 "unconnected-(J12-SDIO_D1-Pad15)") (pinfunction "SDIO_D1") (pintype "bidirectional+no_connect"))
    (pad "16" smd rect (at -5.501 -3.749 90) (size 0.3 1.55) (layers "B.Cu" "B.Paste" "B.Mask")
      (net 378 "unconnected-(J12-~{LED_2}-Pad16)") (pinfunction "~{LED_2}") (pintype "output+no_connect"))
    (pad "17" smd rect (at -5.251 3.75 90) (size 0.3 1.55) (layers "B.Cu" "B.Paste" "B.Mask")
      (net 379 "unconnected-(J12-SDIO_D2-Pad17)") (pinfunction "SDIO_D2") (pintype "bidirectional+no_connect"))
    (pad "18" smd rect (at -5.002 -3.749 90) (size 0.3 1.55) (layers "B.Cu" "B.Paste" "B.Mask")
      (net 1 "GND") (pinfunction "GND") (pintype "passive"))
    (pad "19" smd rect (at -4.752 3.75 90) (size 0.3 1.55) (layers "B.Cu" "B.Paste" "B.Mask")
      (net 381 "unconnected-(J12-SDIO_D3-Pad19)") (pinfunction "SDIO_D3") (pintype "bidirectional+no_connect"))
    (pad "20" smd rect (at -4.502 -3.749 90) (size 0.3 1.55) (layers "B.Cu" "B.Paste" "B.Mask")
      (net 382 "unconnected-(J12-~{UART_WAKE}-Pad20)") (pinfunction "~{UART_WAKE}") (pintype "output+no_connect"))
    (pad "21" smd rect (at -4.252 3.75 90) (size 0.3 1.55) (layers "B.Cu" "B.Paste" "B.Mask")
      (net 383 "unconnected-(J12-SDIO_~{WAKE}-Pad21)") (pinfunction "SDIO_~{WAKE}") (pintype "bidirectional+no_connect"))
    (pad "22" smd rect (at -4.002 -3.749 90) (size 0.3 1.55) (layers "B.Cu" "B.Paste" "B.Mask")
      (net 384 "unconnected-(J12-UART_TXD-Pad22)") (pinfunction "UART_TXD") (pintype "bidirectional+no_connect"))
    (pad "23" smd rect (at -3.751 3.75 90) (size 0.3 1.55) (layers "B.Cu" "B.Paste" "B.Mask")
      (net 385 "unconnected-(J12-SDIO_~{RESET}-Pad23)") (pinfunction "SDIO_~{RESET}") (pintype "input+no_connect"))
    (pad "32" smd rect (at -1.501 -3.749 90) (size 0.3 1.55) (layers "B.Cu" "B.Paste" "B.Mask")
      (net 386 "unconnected-(J12-UART_RXD-Pad32)") (pinfunction "UART_RXD") (pintype "bidirectional+no_connect"))
    (pad "33" smd rect (at -1.251 3.75 90) (size 0.3 1.55) (layers "B.Cu" "B.Paste" "B.Mask")
      (net 1 "GND") (pinfunction "GND") (pintype "passive"))
    (pad "34" smd rect (at -1.001 -3.749 90) (size 0.3 1.55) (layers "B.Cu" "B.Paste" "B.Mask")
      (net 387 "unconnected-(J12-UART_RTS-Pad34)") (pinfunction "UART_RTS") (pintype "bidirectional+no_connect"))
    (pad "35" smd rect (at -0.751 3.75 90) (size 0.3 1.55) (layers "B.Cu" "B.Paste" "B.Mask")
      (net 89 "/PCIE M2 key E /GTR_DP3_M2C_C_P") (pinfunction "PET0+") (pintype "input"))
    (pad "36" smd rect (at -0.501 -3.749 90) (size 0.3 1.55) (layers "B.Cu" "B.Paste" "B.Mask")
      (net 388 "unconnected-(J12-UART_CTS-Pad36)") (pinfunction "UART_CTS") (pintype "bidirectional+no_connect"))
    (pad "37" smd rect (at -0.251 3.75 90) (size 0.3 1.55) (layers "B.Cu" "B.Paste" "B.Mask")
      (net 91 "/PCIE M2 key E /GTR_DP3_M2C_C_N") (pinfunction "PET0-") (pintype "input"))
    (pad "38" smd rect (at -0.001 -3.749 90) (size 0.3 1.55) (layers "B.Cu" "B.Paste" "B.Mask")
      (net 389 "unconnected-(J12-VENDOR_1-Pad38)") (pinfunction "VENDOR_1") (pintype "bidirectional+no_connect"))
    (pad "39" smd rect (at 0.249 3.75 90) (size 0.3 1.55) (layers "B.Cu" "B.Paste" "B.Mask")
      (net 1 "GND") (pinfunction "GND") (pintype "passive"))
    (pad "40" smd rect (at 0.499 -3.749 90) (size 0.3 1.55) (layers "B.Cu" "B.Paste" "B.Mask")
      (net 390 "unconnected-(J12-VENDOR_2-Pad40)") (pinfunction "VENDOR_2") (pintype "bidirectional+no_connect"))
    (pad "41" smd rect (at 0.749 3.75 90) (size 0.3 1.55) (layers "B.Cu" "B.Paste" "B.Mask")
      (net 119 "/PCIE M2 key E /GTR_DP3_C2M_P") (pinfunction "PER0+") (pintype "output"))
    (pad "42" smd rect (at 0.999 -3.749 90) (size 0.3 1.55) (layers "B.Cu" "B.Paste" "B.Mask")
      (net 391 "unconnected-(J12-VENDOR_3-Pad42)") (pinfunction "VENDOR_3") (pintype "bidirectional+no_connect"))
    (pad "43" smd rect (at 1.249 3.75 90) (size 0.3 1.55) (layers "B.Cu" "B.Paste" "B.Mask")
      (net 120 "/PCIE M2 key E /GTR_DP3_C2M_N") (pinfunction "PER0-") (pintype "output"))
    (pad "44" smd rect (at 1.499 -3.749 90) (size 0.3 1.55) (layers "B.Cu" "B.Paste" "B.Mask")
      (net 392 "unconnected-(J12-COEX3-Pad44)") (pinfunction "COEX3") (pintype "bidirectional+no_connect"))
    (pad "45" smd rect (at 1.749 3.75 90) (size 0.3 1.55) (layers "B.Cu" "B.Paste" "B.Mask")
      (net 1 "GND") (pinfunction "GND") (pintype "passive"))
    (pad "46" smd rect (at 1.999 -3.749 90) (size 0.3 1.55) (layers "B.Cu" "B.Paste" "B.Mask")
      (net 393 "unconnected-(J12-COEX_TXD-Pad46)") (pinfunction "COEX_TXD") (pintype "bidirectional+no_connect"))
    (pad "47" smd rect (at 2.249 3.75 90) (size 0.3 1.55) (layers "B.Cu" "B.Paste" "B.Mask")
      (net 122 "/Clock distribution/GTR_REFCLK3_P") (pinfunction "REFCLK0+") (pintype "input"))
    (pad "48" smd rect (at 2.499 -3.749 90) (size 0.3 1.55) (layers "B.Cu" "B.Paste" "B.Mask")
      (net 394 "unconnected-(J12-COEX_RXD-Pad48)") (pinfunction "COEX_RXD") (pintype "bidirectional+no_connect"))
    (pad "49" smd rect (at 2.749 3.75 90) (size 0.3 1.55) (layers "B.Cu" "B.Paste" "B.Mask")
      (net 121 "/Clock distribution/GTR_REFCLK3_N") (pinfunction "REFCLK0-") (pintype "input"))
    (pad "50" smd rect (at 2.999 -3.749 90) (size 0.3 1.55) (layers "B.Cu" "B.Paste" "B.Mask")
      (net 395 "unconnected-(J12-SUSCLK-Pad50)") (pinfunction "SUSCLK") (pintype "input+no_connect"))
    (pad "51" smd rect (at 3.249 3.75 90) (size 0.3 1.55) (layers "B.Cu" "B.Paste" "B.Mask")
      (net 1 "GND") (pinfunction "GND") (pintype "passive"))
    (pad "52" smd rect (at 3.499 -3.749 90) (size 0.3 1.55) (layers "B.Cu" "B.Paste" "B.Mask")
      (net 221 "/PCIE M2 key E /~{M2_PERST}") (pinfunction "~{PERST0}") (pintype "input"))
    (pad "53" smd rect (at 3.749 3.75 90) (size 0.3 1.55) (layers "B.Cu" "B.Paste" "B.Mask")
      (net 396 "Net-(J12-~{CLKREQ0})") (pinfunction "~{CLKREQ0}") (pintype "output"))
    (pad "54" smd rect (at 3.999 -3.749 90) (size 0.3 1.55) (layers "B.Cu" "B.Paste" "B.Mask")
      (net 397 "unconnected-(J12-W_DISABLE2-Pad54)") (pinfunction "W_DISABLE2") (pintype "input+no_connect"))
    (pad "55" smd rect (at 4.249 3.75 90) (size 0.3 1.55) (layers "B.Cu" "B.Paste" "B.Mask")
      (net 227 "/PCIE M2 key E /~{M2_PEWAKE}") (pinfunction "~{PEWAKE0}") (pintype "output"))
    (pad "56" smd rect (at 4.499 -3.749 90) (size 0.3 1.55) (layers "B.Cu" "B.Paste" "B.Mask")
      (net 398 "unconnected-(J12-W_DISABLE1-Pad56)") (pinfunction "W_DISABLE1") (pintype "input+no_connect"))
    (pad "57" smd rect (at 4.749 3.75 90) (size 0.3 1.55) (layers "B.Cu" "B.Paste" "B.Mask")
      (net 1 "GND") (pinfunction "GND") (pintype "passive"))
    (pad "58" smd rect (at 4.999 -3.749 90) (size 0.3 1.55) (layers "B.Cu" "B.Paste" "B.Mask")
      (net 399 "unconnected-(J12-I2C_DATA-Pad58)") (pinfunction "I2C_DATA") (pintype "bidirectional+no_connect"))
    (pad "59" smd rect (at 5.249 3.75 90) (size 0.3 1.55) (layers "B.Cu" "B.Paste" "B.Mask")
      (net 400 "unconnected-(J12-PET1+-Pad59)") (pinfunction "PET1+") (pintype "input+no_connect"))
    (pad "60" smd rect (at 5.499 -3.749 90) (size 0.3 1.55) (layers "B.Cu" "B.Paste" "B.Mask")
      (net 401 "unconnected-(J12-I2C_CLK-Pad60)") (pinfunction "I2C_CLK") (pintype "bidirectional+no_connect"))
    (pad "61" smd rect (at 5.749 3.75 90) (size 0.3 1.55) (layers "B.Cu" "B.Paste" "B.Mask")
      (net 402 "unconnected-(J12-PET1--Pad61)") (pinfunction "PET1-") (pintype "input+no_connect"))
    (pad "62" smd rect (at 5.999 -3.749 90) (size 0.3 1.55) (layers "B.Cu" "B.Paste" "B.Mask")
      (net 403 "unconnected-(J12-~{ALERT}-Pad62)") (pinfunction "~{ALERT}") (pintype "output+no_connect"))
    (pad "63" smd rect (at 6.249 3.75 90) (size 0.3 1.55) (layers "B.Cu" "B.Paste" "B.Mask")
      (net 1 "GND") (pinfunction "GND") (pintype "passive"))
    (pad "64" smd rect (at 6.499 -3.749 90) (size 0.3 1.55) (layers "B.Cu" "B.Paste" "B.Mask")
      (net 404 "unconnected-(J12-RFU-Pad64)") (pinfunction "RFU") (pintype "no_connect"))
    (pad "65" smd rect (at 6.749 3.75 90) (size 0.3 1.55) (layers "B.Cu" "B.Paste" "B.Mask")
      (net 405 "unconnected-(J12-PER1+-Pad65)") (pinfunction "PER1+") (pintype "output+no_connect"))
    (pad "66" smd rect (at 6.998 -3.749 90) (size 0.3 1.55) (layers "B.Cu" "B.Paste" "B.Mask")
      (net 406 "unconnected-(J12-UIM_SWP-Pad66)") (pinfunction "UIM_SWP") (pintype "bidirectional+no_connect"))
    (pad "67" smd rect (at 7.248 3.75 90) (size 0.3 1.55) (layers "B.Cu" "B.Paste" "B.Mask")
      (net 407 "unconnected-(J12-PER1--Pad67)") (pinfunction "PER1-") (pintype "output+no_connect"))
    (pad "68" smd rect (at 7.498 -3.749 90) (size 0.3 1.55) (layers "B.Cu" "B.Paste" "B.Mask")
      (net 408 "unconnected-(J12-UIM_POWER_SNK-Pad68)") (pinfunction "UIM_POWER_SNK") (pintype "bidirectional+no_connect"))
    (pad "69" smd rect (at 7.748 3.75 90) (size 0.3 1.55) (layers "B.Cu" "B.Paste" "B.Mask")
      (net 1 "GND") (pinfunction "GND") (pintype "passive"))
    (pad "70" smd rect (at 7.998 -3.749 90) (size 0.3 1.55) (layers "B.Cu" "B.Paste" "B.Mask")
      (net 411 "unconnected-(J12-UIM_POWER_SRC-Pad70)") (pinfunction "UIM_POWER_SRC") (pintype "bidirectional+no_connect"))
    (pad "71" smd rect (at 8.248 3.75 90) (size 0.3 1.55) (layers "B.Cu" "B.Paste" "B.Mask")
      (net 412 "unconnected-(J12-REFCLK1+-Pad71)") (pinfunction "REFCLK1+") (pintype "input+no_connect"))
    (pad "72" smd rect (at 8.498 -3.749 90) (size 0.3 1.55) (layers "B.Cu" "B.Paste" "B.Mask")
      (net 15 "PS_3V3") (pinfunction "3.3V") (pintype "passive"))
    (pad "73" smd rect (at 8.748 3.75 90) (size 0.3 1.55) (layers "B.Cu" "B.Paste" "B.Mask")
      (net 413 "unconnected-(J12-REFCLK1--Pad73)") (pinfunction "REFCLK1-") (pintype "input+no_connect"))
    (pad "74" smd rect (at 8.998 -3.749 90) (size 0.3 1.55) (layers "B.Cu" "B.Paste" "B.Mask")
      (net 15 "PS_3V3") (pinfunction "3.3V") (pintype "passive"))
    (pad "75" smd rect (at 9.248 3.75 90) (size 0.3 1.55) (layers "B.Cu" "B.Paste" "B.Mask")
      (net 1 "GND") (pinfunction "GND") (pintype "passive"))
    (pad "MP" smd rect (at -10.351 3.002 90) (size 1.2 2.75) (layers "B.Cu" "B.Paste" "B.Mask")
      (net 1 "GND") (pinfunction "MP") (pintype "passive"))
    (pad "MP" smd rect (at 10.35 3.002 90) (size 1.2 2.75) (layers "B.Cu" "B.Paste" "B.Mask")
      (net 1 "GND") (pinfunction "MP") (pintype "passive"))
  )

  (footprint "kria-k26-devboard-footprints:UQFN-16-1.8x2.6mm_P0.4mm_Texas_RSV0016A" (layer "B.Cu")
    (at 93.6 85.9 180)
    (descr "https://www.ti.com/lit/ds/symlink/sn74avch4t245-ep.pdf?ts=1679484181203&ref_url=https%253A%252F%252Fwww.ti.com%252Fproduct%252FSN74AVCH4T245-EP%253Futm_source%253Dgoogle%2526utm_medium%253Dcpc%2526utm_campaign%253Dasc-int-null-prodfolderdynamic-cpc-pf-google-wwe_int%2526utm_content%253Dprodfolddynamic%2526ds_k%253DDYNAMIC%2BSEARCH%2BADS%2526DCM%253Dyes%2526gclid%253DCjwKCAjwzuqgBhAcEiwAdj5dRvR_WgyvqqhLxMx8zfbFv2a6tg33JIMv01Bn4M1kA4JzW1nDDW7OzhoCRbkQAvD_BwE%2526gclsrc%253Daw.ds")
    (property "Author" "Antmicro")
    (property "License" "Apache-2.0")
    (property "MPN" "74AVC4T245RSVRG4")
    (property "Manufacturer" "Texas Instruments")
    (property "Sheetfile" "dp.kicad_sch")
    (property "Sheetname" "Display Port")
    (property "ki_description" "4-Bit Dual-Supply Bus Transceiver With Configurable Voltage Translation and 3-State Outputs, TSSOP-16")
    (property "ki_keywords" "Noninverting Bidirectional")
    (attr smd)
    (fp_text reference "U1" (at -0.83 -2.58) (layer "B.SilkS")
        (effects (font (size 0.7 0.7) (thickness 0.15)) (justify left bottom mirror))
    )
    (fp_text value "74AVC4T245_UQFN" (at -1.25 -2.5) (layer "B.Fab") hide
        (effects (font (size 0.7 0.7) (thickness 0.15)) (justify left bottom mirror))
    )
    (fp_text user "." (at -1.45 0.75) (layer "B.SilkS")
        (effects (font (size 0.7 0.7) (thickness 0.15)) (justify left bottom mirror))
    )
    (fp_text user "License: Apache-2.0" (at -1.25 -6.25) (layer "B.Fab") hide
        (effects (font (size 0.7 0.7) (thickness 0.15)) (justify left bottom mirror))
    )
    (fp_text user "Author: Antmicro" (at -1.25 -5) (layer "B.Fab") hide
        (effects (font (size 0.7 0.7) (thickness 0.15)) (justify left bottom mirror))
    )
    (fp_text user "${REFERENCE}" (at -1.25 -3.75) (layer "B.Fab") hide
        (effects (font (size 0.7 0.7) (thickness 0.15)) (justify left bottom mirror))
    )
    (fp_line (start -0.9 -1.2995) (end -0.9 -0.8)
      (stroke (width 0.15) (type solid)) (layer "B.SilkS"))
    (fp_line (start -0.8 -1.2995) (end -0.9 -1.2995)
      (stroke (width 0.15) (type solid)) (layer "B.SilkS"))
    (fp_line (start -0.8 1.3) (end -0.9 1.3)
      (stroke (width 0.15) (type solid)) (layer "B.SilkS"))
    (fp_line (start 0.8 -1.3) (end 0.899 -1.3)
      (stroke (width 0.15) (type solid)) (layer "B.SilkS"))
    (fp_line (start 0.8 1.3) (end 0.9 1.3)
      (stroke (width 0.15) (type solid)) (layer "B.SilkS"))
    (fp_line (start 0.9 -0.8) (end 0.899 -1.3)
      (stroke (width 0.15) (type solid)) (layer "B.SilkS"))
    (fp_line (start 0.9 1.3) (end 0.9 0.8005)
      (stroke (width 0.15) (type solid)) (layer "B.SilkS"))
    (fp_rect (start -1.25 1.65) (end 1.25 -1.65)
      (stroke (width 0.05) (type solid)) (fill none) (layer "B.CrtYd"))
    (fp_line (start -0.902 -1.3) (end -0.902 1.301)
      (stroke (width 0.15) (type solid)) (layer "B.Fab"))
    (fp_line (start 0.9 -1.3) (end -0.902 -1.3)
      (stroke (width 0.15) (type solid)) (layer "B.Fab"))
    (fp_line (start 0.9 -1.3) (end 0.9 1.301)
      (stroke (width 0.15) (type solid)) (layer "B.Fab"))
    (fp_line (start 0.9 1.301) (end -0.902 1.301)
      (stroke (width 0.15) (type solid)) (layer "B.Fab"))
    (pad "1" smd roundrect (at -0.75 0.6 180) (size 0.7 0.2) (layers "B.Cu" "B.Paste" "B.Mask") (roundrect_rratio 0.2272727273)
      (net 1 "GND") (pinfunction "1~{OE}") (pintype "input"))
    (pad "2" smd roundrect (at -0.802 0.202 180) (size 0.6 0.2) (layers "B.Cu" "B.Paste" "B.Mask") (roundrect_rratio 0.2272727273)
      (net 15 "PS_3V3") (pinfunction "VCCB") (pintype "power_in"))
    (pad "3" smd roundrect (at -0.802 -0.2 180) (size 0.6 0.2) (layers "B.Cu" "B.Paste" "B.Mask") (roundrect_rratio 0.2272727273)
      (net 17 "PS_1V8") (pinfunction "VCCA") (pintype "power_in"))
    (pad "4" smd roundrect (at -0.802 -0.598 180) (size 0.6 0.2) (layers "B.Cu" "B.Paste" "B.Mask") (roundrect_rratio 0.2272727273)
      (net 17 "PS_1V8") (pinfunction "1DIR") (pintype "input"))
    (pad "5" smd roundrect (at -0.6 -1.199 90) (size 0.6 0.2) (layers "B.Cu" "B.Paste" "B.Mask") (roundrect_rratio 0.2272727273)
      (net 1 "GND") (pinfunction "2DIR") (pintype "input"))
    (pad "6" smd roundrect (at -0.202 -1.199 90) (size 0.6 0.2) (layers "B.Cu" "B.Paste" "B.Mask") (roundrect_rratio 0.2272727273)
      (net 116 "/Display Port/MIO27") (pinfunction "1A1") (pintype "bidirectional"))
    (pad "7" smd roundrect (at 0.2 -1.199 90) (size 0.6 0.2) (layers "B.Cu" "B.Paste" "B.Mask") (roundrect_rratio 0.2272727273)
      (net 111 "/Display Port/MIO29") (pinfunction "1A2") (pintype "bidirectional"))
    (pad "8" smd roundrect (at 0.598 -1.199 90) (size 0.6 0.2) (layers "B.Cu" "B.Paste" "B.Mask") (roundrect_rratio 0.2272727273)
      (net 112 "/Display Port/MIO30") (pinfunction "2A1") (pintype "bidirectional"))
    (pad "9" smd roundrect (at 0.8 -0.598 180) (size 0.6 0.2) (layers "B.Cu" "B.Paste" "B.Mask") (roundrect_rratio 0.2272727273)
      (net 117 "/Display Port/MIO28") (pinfunction "2A2") (pintype "bidirectional"))
    (pad "10" smd roundrect (at 0.8 -0.2 180) (size 0.6 0.2) (layers "B.Cu" "B.Paste" "B.Mask") (roundrect_rratio 0.2272727273)
      (net 1 "GND") (pinfunction "GND") (pintype "power_in"))
    (pad "11" smd roundrect (at 0.8 0.202 180) (size 0.6 0.2) (layers "B.Cu" "B.Paste" "B.Mask") (roundrect_rratio 0.2272727273)
      (net 1 "GND") (pinfunction "GND") (pintype "passive"))
    (pad "12" smd roundrect (at 0.8 0.6 180) (size 0.6 0.2) (layers "B.Cu" "B.Paste" "B.Mask") (roundrect_rratio 0.2272727273)
      (net 105 "/Display Port/DP_HPD") (pinfunction "2B2") (pintype "bidirectional"))
    (pad "13" smd roundrect (at 0.598 1.2 90) (size 0.6 0.2) (layers "B.Cu" "B.Paste" "B.Mask") (roundrect_rratio 0.2272727273)
      (net 126 "/Display Port/DP_AUX_IN") (pinfunction "2B1") (pintype "bidirectional"))
    (pad "14" smd roundrect (at 0.2 1.2 90) (size 0.6 0.2) (layers "B.Cu" "B.Paste" "B.Mask") (roundrect_rratio 0.2272727273)
      (net 125 "/Display Port/DP_OE") (pinfunction "1B2") (pintype "bidirectional"))
    (pad "15" smd roundrect (at -0.202 1.2 90) (size 0.6 0.2) (layers "B.Cu" "B.Paste" "B.Mask") (roundrect_rratio 0.2272727273)
      (net 124 "/Display Port/DP_AUX_OUT") (pinfunction "1B1") (pintype "bidirectional"))
    (pad "16" smd roundrect (at -0.6 1.2 90) (size 0.6 0.2) (layers "B.Cu" "B.Paste" "B.Mask") (roundrect_rratio 0.2272727273)
      (net 1 "GND") (pinfunction "2~{OE}") (pintype "input"))
  )

  (footprint "kria-k26-devboard-footprints:R_0402_1005Metric" (layer "B.Cu")
    (at 115.7 141.1 180)
    (descr "Resistor SMD 0402")
    (tags "resistor SMD 0402")
    (property "Author" "Antmicro")
    (property "License" "Apache-2.0")
    (property "MPN" "CR0402-FX-1002GLF")
    (property "Manufacturer" "Bourns")
    (property "Sheetfile" "reset.kicad_sch")
    (property "Sheetname" "Reset logic")
    (property "Tolerance" "1%")
    (property "Val" "10k")
    (property "ki_description" "10k resistor in 0402 package with 1% tolerance")
    (attr smd)
    (fp_text reference "R96" (at -3.07 -0.34) (layer "B.SilkS")
        (effects (font (size 0.7 0.7) (thickness 0.15)) (justify left bottom mirror))
    )
    (fp_text value "R_10k_0402" (at 0 -1.4) (layer "B.Fab") hide
        (effects (font (size 0.7 0.7) (thickness 0.15)) (justify left bottom mirror))
    )
    (fp_text user "Author: Antmicro" (at -0.95 -4.169) (layer "B.Fab") hide
        (effects (font (size 0.7 0.7) (thickness 0.15)) (justify left bottom mirror))
    )
    (fp_text user "${REFERENCE}" (at -0.95 -3.168) (layer "B.Fab") hide
        (effects (font (size 0.7 0.7) (thickness 0.15)) (justify left bottom mirror))
    )
    (fp_text user "License: Apache-2.0" (at -0.95 -5.169) (layer "B.Fab") hide
        (effects (font (size 0.7 0.7) (thickness 0.15)) (justify left bottom mirror))
    )
    (fp_rect (start -0.93 0.47) (end 0.93 -0.47)
      (stroke (width 0.05) (type solid)) (fill none) (layer "B.CrtYd"))
    (fp_rect (start -0.5 0.25) (end 0.5 -0.25)
      (stroke (width 0.15) (type solid)) (fill none) (layer "B.Fab"))
    (pad "1" smd roundrect (at -0.485 0 180) (size 0.59 0.64) (layers "B.Cu" "B.Paste" "B.Mask") (roundrect_rratio 0.25)
      (net 17 "PS_1V8") (pintype "passive"))
    (pad "2" smd roundrect (at 0.485 0 180) (size 0.59 0.64) (layers "B.Cu" "B.Paste" "B.Mask") (roundrect_rratio 0.25)
      (net 176 "/Ethernet/~{ETH_RESET}") (pintype "passive"))
  )

  (footprint "kria-k26-devboard-footprints:R_0402_1005Metric" (layer "B.Cu")
    (at 115.7 139.1 180)
    (descr "Resistor SMD 0402")
    (tags "resistor SMD 0402")
    (property "Author" "Antmicro")
    (property "License" "Apache-2.0")
    (property "MPN" "CR0402-FX-1002GLF")
    (property "Manufacturer" "Bourns")
    (property "Sheetfile" "reset.kicad_sch")
    (property "Sheetname" "Reset logic")
    (property "Tolerance" "1%")
    (property "Val" "10k")
    (property "ki_description" "10k resistor in 0402 package with 1% tolerance")
    (attr smd)
    (fp_text reference "R95" (at -3.07 -0.34) (layer "B.SilkS")
        (effects (font (size 0.7 0.7) (thickness 0.15)) (justify left bottom mirror))
    )
    (fp_text value "R_10k_0402" (at 0 -1.4) (layer "B.Fab") hide
        (effects (font (size 0.7 0.7) (thickness 0.15)) (justify left bottom mirror))
    )
    (fp_text user "License: Apache-2.0" (at -0.95 -5.169) (layer "B.Fab") hide
        (effects (font (size 0.7 0.7) (thickness 0.15)) (justify left bottom mirror))
    )
    (fp_text user "${REFERENCE}" (at -0.95 -3.168) (layer "B.Fab") hide
        (effects (font (size 0.7 0.7) (thickness 0.15)) (justify left bottom mirror))
    )
    (fp_text user "Author: Antmicro" (at -0.95 -4.169) (layer "B.Fab") hide
        (effects (font (size 0.7 0.7) (thickness 0.15)) (justify left bottom mirror))
    )
    (fp_rect (start -0.93 0.47) (end 0.93 -0.47)
      (stroke (width 0.05) (type solid)) (fill none) (layer "B.CrtYd"))
    (fp_rect (start -0.5 0.25) (end 0.5 -0.25)
      (stroke (width 0.15) (type solid)) (fill none) (layer "B.Fab"))
    (pad "1" smd roundrect (at -0.485 0 180) (size 0.59 0.64) (layers "B.Cu" "B.Paste" "B.Mask") (roundrect_rratio 0.25)
      (net 15 "PS_3V3") (pintype "passive"))
    (pad "2" smd roundrect (at 0.485 0 180) (size 0.59 0.64) (layers "B.Cu" "B.Paste" "B.Mask") (roundrect_rratio 0.25)
      (net 175 "/Reset logic/~{USB_HUB_RESET}") (pintype "passive"))
  )

  (footprint "kria-k26-devboard-footprints:R_0402_1005Metric" (layer "B.Cu")
    (at 111.65 138.25)
    (descr "Resistor SMD 0402")
    (tags "resistor SMD 0402")
    (property "Author" "Antmicro")
    (property "License" "Apache-2.0")
    (property "MPN" "CR0402-FX-1002GLF")
    (property "Manufacturer" "Bourns")
    (property "Sheetfile" "reset.kicad_sch")
    (property "Sheetname" "Reset logic")
    (property "Tolerance" "1%")
    (property "Val" "10k")
    (property "ki_description" "10k resistor in 0402 package with 1% tolerance")
    (attr smd)
    (fp_text reference "R94" (at 3.01 0.35 180) (layer "B.SilkS")
        (effects (font (size 0.7 0.7) (thickness 0.15)) (justify left bottom mirror))
    )
    (fp_text value "R_10k_0402" (at 0 -1.4 180) (layer "B.Fab") hide
        (effects (font (size 0.7 0.7) (thickness 0.15)) (justify left bottom mirror))
    )
    (fp_text user "License: Apache-2.0" (at -0.95 -5.169 180) (layer "B.Fab") hide
        (effects (font (size 0.7 0.7) (thickness 0.15)) (justify left bottom mirror))
    )
    (fp_text user "${REFERENCE}" (at -0.95 -3.168 180) (layer "B.Fab") hide
        (effects (font (size 0.7 0.7) (thickness 0.15)) (justify left bottom mirror))
    )
    (fp_text user "Author: Antmicro" (at -0.95 -4.169 180) (layer "B.Fab") hide
        (effects (font (size 0.7 0.7) (thickness 0.15)) (justify left bottom mirror))
    )
    (fp_rect (start -0.93 0.47) (end 0.93 -0.47)
      (stroke (width 0.05) (type solid)) (fill none) (layer "B.CrtYd"))
    (fp_rect (start -0.5 0.25) (end 0.5 -0.25)
      (stroke (width 0.15) (type solid)) (fill none) (layer "B.Fab"))
    (pad "1" smd roundrect (at -0.485 0) (size 0.59 0.64) (layers "B.Cu" "B.Paste" "B.Mask") (roundrect_rratio 0.25)
      (net 17 "PS_1V8") (pintype "passive"))
    (pad "2" smd roundrect (at 0.485 0) (size 0.59 0.64) (layers "B.Cu" "B.Paste" "B.Mask") (roundrect_rratio 0.25)
      (net 178 "/Reset logic/~{USB_PHY_RESET}") (pintype "passive"))
  )

  (footprint "kria-k26-devboard-footprints:R_0402_1005Metric" (layer "B.Cu")
    (at 111.2 139.665 -90)
    (descr "Resistor SMD 0402")
    (tags "resistor SMD 0402")
    (property "Author" "Antmicro")
    (property "License" "Apache-2.0")
    (property "MPN" "CR0402-FX-1002GLF")
    (property "Manufacturer" "Bourns")
    (property "Sheetfile" "reset.kicad_sch")
    (property "Sheetname" "Reset logic")
    (property "Tolerance" "1%")
    (property "Val" "10k")
    (property "ki_description" "10k resistor in 0402 package with 1% tolerance")
    (attr smd)
    (fp_text reference "R92" (at -0.485 -1.33 90) (layer "B.SilkS")
        (effects (font (size 0.7 0.7) (thickness 0.15)) (justify left bottom mirror))
    )
    (fp_text value "R_10k_0402" (at 0 -1.4 90) (layer "B.Fab") hide
        (effects (font (size 0.7 0.7) (thickness 0.15)) (justify left bottom mirror))
    )
    (fp_text user "License: Apache-2.0" (at -0.95 -5.169 90) (layer "B.Fab") hide
        (effects (font (size 0.7 0.7) (thickness 0.15)) (justify left bottom mirror))
    )
    (fp_text user "Author: Antmicro" (at -0.95 -4.169 90) (layer "B.Fab") hide
        (effects (font (size 0.7 0.7) (thickness 0.15)) (justify left bottom mirror))
    )
    (fp_text user "${REFERENCE}" (at -0.95 -3.168 90) (layer "B.Fab") hide
        (effects (font (size 0.7 0.7) (thickness 0.15)) (justify left bottom mirror))
    )
    (fp_rect (start -0.93 0.47) (end 0.93 -0.47)
      (stroke (width 0.05) (type solid)) (fill none) (layer "B.CrtYd"))
    (fp_rect (start -0.5 0.25) (end 0.5 -0.25)
      (stroke (width 0.15) (type solid)) (fill none) (layer "B.Fab"))
    (pad "1" smd roundrect (at -0.485 0 270) (size 0.59 0.64) (layers "B.Cu" "B.Paste" "B.Mask") (roundrect_rratio 0.25)
      (net 15 "PS_3V3") (pintype "passive"))
    (pad "2" smd roundrect (at 0.485 0 270) (size 0.59 0.64) (layers "B.Cu" "B.Paste" "B.Mask") (roundrect_rratio 0.25)
      (net 177 "/Reset logic/~{SD_CARD_RESET}") (pintype "passive"))
  )

  (footprint "kria-k26-devboard-footprints:C_0402_1005Metric" (layer "B.Cu")
    (at 108.95 144.9)
    (descr "Capacitor SMD 0402")
    (tags "capacitor SMD 0402")
    (property "Author" "Antmicro")
    (property "Dielectric" "X5R")
    (property "License" "Apache-2.0")
    (property "MPN" "GRM155R61H104KE14D")
    (property "Manufacturer" "Murata")
    (property "Sheetfile" "reset.kicad_sch")
    (property "Sheetname" "Reset logic")
    (property "Val" "100n")
    (property "Voltage" "50V")
    (property "ki_description" " ")
    (attr smd)
    (fp_text reference "C138" (at 1.39 1.35 180) (layer "B.SilkS")
        (effects (font (size 0.7 0.7) (thickness 0.15)) (justify left bottom mirror))
    )
    (fp_text value "C_100n_0402" (at 0 -1.4 180) (layer "B.Fab") hide
        (effects (font (size 0.7 0.7) (thickness 0.15)) (justify left bottom mirror))
    )
    (fp_text user "Author: Antmicro" (at -0.932 -4.17 180) (layer "B.Fab") hide
        (effects (font (size 0.7 0.7) (thickness 0.15)) (justify left bottom mirror))
    )
    (fp_text user "License: Apache-2.0" (at -0.932 -5.17 180) (layer "B.Fab") hide
        (effects (font (size 0.7 0.7) (thickness 0.15)) (justify left bottom mirror))
    )
    (fp_text user "${REFERENCE}" (at -0.932 -3.168 180) (layer "B.Fab") hide
        (effects (font (size 0.7 0.7) (thickness 0.15)) (justify left bottom mirror))
    )
    (fp_rect (start -0.94 0.47) (end 0.94 -0.47)
      (stroke (width 0.05) (type solid)) (fill none) (layer "B.CrtYd"))
    (fp_rect (start -0.499 0.249) (end 0.499 -0.249)
      (stroke (width 0.15) (type solid)) (fill none) (layer "B.Fab"))
    (pad "1" smd roundrect (at -0.484 0) (size 0.59 0.64) (layers "B.Cu" "B.Paste" "B.Mask") (roundrect_rratio 0.25)
      (net 15 "PS_3V3") (pintype "passive"))
    (pad "2" smd roundrect (at 0.484 0) (size 0.59 0.64) (layers "B.Cu" "B.Paste" "B.Mask") (roundrect_rratio 0.25)
      (net 1 "GND") (pintype "passive"))
  )

  (footprint "kria-k26-devboard-footprints:R_0402_1005Metric" (layer "B.Cu")
    (at 110.4 142.4 90)
    (descr "Resistor SMD 0402")
    (tags "resistor SMD 0402")
    (property "Author" "Antmicro")
    (property "License" "Apache-2.0")
    (property "MPN" "CR0402-FX-1003GLF")
    (property "Manufacturer" "Bourns")
    (property "Sheetfile" "reset.kicad_sch")
    (property "Sheetname" "Reset logic")
    (property "Tolerance" "1%")
    (property "Val" "100k")
    (property "ki_description" "100k resistor in 0402 package with 1% tolerance")
    (attr smd)
    (fp_text reference "R87" (at 1.14 1.34 270) (layer "B.SilkS")
        (effects (font (size 0.7 0.7) (thickness 0.15)) (justify left bottom mirror))
    )
    (fp_text value "R_100k_0402" (at 0 -1.4 270) (layer "B.Fab") hide
        (effects (font (size 0.7 0.7) (thickness 0.15)) (justify left bottom mirror))
    )
    (fp_text user "License: Apache-2.0" (at -0.95 -5.169 270) (layer "B.Fab") hide
        (effects (font (size 0.7 0.7) (thickness 0.15)) (justify left bottom mirror))
    )
    (fp_text user "${REFERENCE}" (at -0.95 -3.168 270) (layer "B.Fab") hide
        (effects (font (size 0.7 0.7) (thickness 0.15)) (justify left bottom mirror))
    )
    (fp_text user "Author: Antmicro" (at -0.95 -4.169 270) (layer "B.Fab") hide
        (effects (font (size 0.7 0.7) (thickness 0.15)) (justify left bottom mirror))
    )
    (fp_rect (start -0.93 0.47) (end 0.93 -0.47)
      (stroke (width 0.05) (type solid)) (fill none) (layer "B.CrtYd"))
    (fp_rect (start -0.5 0.25) (end 0.5 -0.25)
      (stroke (width 0.15) (type solid)) (fill none) (layer "B.Fab"))
    (pad "1" smd roundrect (at -0.485 0 90) (size 0.59 0.64) (layers "B.Cu" "B.Paste" "B.Mask") (roundrect_rratio 0.25)
      (net 1 "GND") (pintype "passive"))
    (pad "2" smd roundrect (at 0.485 0 90) (size 0.59 0.64) (layers "B.Cu" "B.Paste" "B.Mask") (roundrect_rratio 0.25)
      (net 675 "Net-(U33-1A1)") (pintype "passive"))
  )

  (footprint "kria-k26-devboard-footprints:C_0402_1005Metric" (layer "B.Cu")
    (at 104.35 140.425 90)
    (descr "Capacitor SMD 0402")
    (tags "capacitor SMD 0402")
    (property "Author" "Antmicro")
    (property "Dielectric" "X5R")
    (property "License" "Apache-2.0")
    (property "MPN" "GRM155R61H104KE14D")
    (property "Manufacturer" "Murata")
    (property "Sheetfile" "reset.kicad_sch")
    (property "Sheetname" "Reset logic")
    (property "Val" "100n")
    (property "Voltage" "50V")
    (property "ki_description" " ")
    (attr smd)
    (fp_text reference "C132" (at 1.415 -0.59 270) (layer "B.SilkS")
        (effects (font (size 0.7 0.7) (thickness 0.15)) (justify left bottom mirror))
    )
    (fp_text value "C_100n_0402" (at 0 -1.4 270) (layer "B.Fab") hide
        (effects (font (size 0.7 0.7) (thickness 0.15)) (justify left bottom mirror))
    )
    (fp_text user "License: Apache-2.0" (at -0.932 -5.17 270) (layer "B.Fab") hide
        (effects (font (size 0.7 0.7) (thickness 0.15)) (justify left bottom mirror))
    )
    (fp_text user "Author: Antmicro" (at -0.932 -4.17 270) (layer "B.Fab") hide
        (effects (font (size 0.7 0.7) (thickness 0.15)) (justify left bottom mirror))
    )
    (fp_text user "${REFERENCE}" (at -0.932 -3.168 270) (layer "B.Fab") hide
        (effects (font (size 0.7 0.7) (thickness 0.15)) (justify left bottom mirror))
    )
    (fp_rect (start -0.94 0.47) (end 0.94 -0.47)
      (stroke (width 0.05) (type solid)) (fill none) (layer "B.CrtYd"))
    (fp_rect (start -0.499 0.249) (end 0.499 -0.249)
      (stroke (width 0.15) (type solid)) (fill none) (layer "B.Fab"))
    (pad "1" smd roundrect (at -0.484 0 90) (size 0.59 0.64) (layers "B.Cu" "B.Paste" "B.Mask") (roundrect_rratio 0.25)
      (net 15 "PS_3V3") (pintype "passive"))
    (pad "2" smd roundrect (at 0.484 0 90) (size 0.59 0.64) (layers "B.Cu" "B.Paste" "B.Mask") (roundrect_rratio 0.25)
      (net 1 "GND") (pintype "passive"))
  )

  (footprint "kria-k26-devboard-footprints:C_0402_1005Metric" (layer "B.Cu")
    (at 108.48 141.6)
    (descr "Capacitor SMD 0402")
    (tags "capacitor SMD 0402")
    (property "Author" "Antmicro")
    (property "Dielectric" "X5R")
    (property "License" "Apache-2.0")
    (property "MPN" "GRM155R61H104KE14D")
    (property "Manufacturer" "Murata")
    (property "Sheetfile" "reset.kicad_sch")
    (property "Sheetname" "Reset logic")
    (property "Val" "100n")
    (property "Voltage" "50V")
    (property "ki_description" " ")
    (attr smd)
    (fp_text reference "C136" (at 1.52 1.31 180) (layer "B.SilkS")
        (effects (font (size 0.7 0.7) (thickness 0.15)) (justify left bottom mirror))
    )
    (fp_text value "C_100n_0402" (at 0 -1.4 180) (layer "B.Fab") hide
        (effects (font (size 0.7 0.7) (thickness 0.15)) (justify left bottom mirror))
    )
    (fp_text user "${REFERENCE}" (at -0.932 -3.168 180) (layer "B.Fab") hide
        (effects (font (size 0.7 0.7) (thickness 0.15)) (justify left bottom mirror))
    )
    (fp_text user "Author: Antmicro" (at -0.932 -4.17 180) (layer "B.Fab") hide
        (effects (font (size 0.7 0.7) (thickness 0.15)) (justify left bottom mirror))
    )
    (fp_text user "License: Apache-2.0" (at -0.932 -5.17 180) (layer "B.Fab") hide
        (effects (font (size 0.7 0.7) (thickness 0.15)) (justify left bottom mirror))
    )
    (fp_rect (start -0.94 0.47) (end 0.94 -0.47)
      (stroke (width 0.05) (type solid)) (fill none) (layer "B.CrtYd"))
    (fp_rect (start -0.499 0.249) (end 0.499 -0.249)
      (stroke (width 0.15) (type solid)) (fill none) (layer "B.Fab"))
    (pad "1" smd roundrect (at -0.484 0) (size 0.59 0.64) (layers "B.Cu" "B.Paste" "B.Mask") (roundrect_rratio 0.25)
      (net 15 "PS_3V3") (pintype "passive"))
    (pad "2" smd roundrect (at 0.484 0) (size 0.59 0.64) (layers "B.Cu" "B.Paste" "B.Mask") (roundrect_rratio 0.25)
      (net 1 "GND") (pintype "passive"))
  )

  (footprint "kria-k26-devboard-footprints:R_0402_1005Metric" (layer "B.Cu")
    (at 115.685 140.1 180)
    (descr "Resistor SMD 0402")
    (tags "resistor SMD 0402")
    (property "Author" "Antmicro")
    (property "License" "Apache-2.0")
    (property "MPN" "CR0402-FX-1003GLF")
    (property "Manufacturer" "Bourns")
    (property "Sheetfile" "reset.kicad_sch")
    (property "Sheetname" "Reset logic")
    (property "Tolerance" "1%")
    (property "Val" "100k")
    (property "ki_description" "100k resistor in 0402 package with 1% tolerance")
    (attr smd)
    (fp_text reference "R90" (at -3.07 -0.34) (layer "B.SilkS")
        (effects (font (size 0.7 0.7) (thickness 0.15)) (justify left bottom mirror))
    )
    (fp_text value "R_100k_0402" (at 0 -1.4) (layer "B.Fab") hide
        (effects (font (size 0.7 0.7) (thickness 0.15)) (justify left bottom mirror))
    )
    (fp_text user "${REFERENCE}" (at -0.95 -3.168) (layer "B.Fab") hide
        (effects (font (size 0.7 0.7) (thickness 0.15)) (justify left bottom mirror))
    )
    (fp_text user "Author: Antmicro" (at -0.95 -4.169) (layer "B.Fab") hide
        (effects (font (size 0.7 0.7) (thickness 0.15)) (justify left bottom mirror))
    )
    (fp_text user "License: Apache-2.0" (at -0.95 -5.169) (layer "B.Fab") hide
        (effects (font (size 0.7 0.7) (thickness 0.15)) (justify left bottom mirror))
    )
    (fp_rect (start -0.93 0.47) (end 0.93 -0.47)
      (stroke (width 0.05) (type solid)) (fill none) (layer "B.CrtYd"))
    (fp_rect (start -0.5 0.25) (end 0.5 -0.25)
      (stroke (width 0.15) (type solid)) (fill none) (layer "B.Fab"))
    (pad "1" smd roundrect (at -0.485 0 180) (size 0.59 0.64) (layers "B.Cu" "B.Paste" "B.Mask") (roundrect_rratio 0.25)
      (net 1 "GND") (pintype "passive"))
    (pad "2" smd roundrect (at 0.485 0 180) (size 0.59 0.64) (layers "B.Cu" "B.Paste" "B.Mask") (roundrect_rratio 0.25)
      (net 678 "Net-(U33-2A1)") (pintype "passive"))
  )

  (footprint "kria-k26-devboard-footprints:C_0402_1005Metric" (layer "B.Cu")
    (at 107.05 144.9 180)
    (descr "Capacitor SMD 0402")
    (tags "capacitor SMD 0402")
    (property "Author" "Antmicro")
    (property "Dielectric" "X5R")
    (property "License" "Apache-2.0")
    (property "MPN" "GRM155R61H104KE14D")
    (property "Manufacturer" "Murata")
    (property "Sheetfile" "reset.kicad_sch")
    (property "Sheetname" "Reset logic")
    (property "Val" "100n")
    (property "Voltage" "50V")
    (property "ki_description" " ")
    (attr smd)
    (fp_text reference "C137" (at -0.395 -1.31) (layer "B.SilkS")
        (effects (font (size 0.7 0.7) (thickness 0.15)) (justify left bottom mirror))
    )
    (fp_text value "C_100n_0402" (at 0 -1.4) (layer "B.Fab") hide
        (effects (font (size 0.7 0.7) (thickness 0.15)) (justify left bottom mirror))
    )
    (fp_text user "License: Apache-2.0" (at -0.932 -5.17) (layer "B.Fab") hide
        (effects (font (size 0.7 0.7) (thickness 0.15)) (justify left bottom mirror))
    )
    (fp_text user "${REFERENCE}" (at -0.932 -3.168) (layer "B.Fab") hide
        (effects (font (size 0.7 0.7) (thickness 0.15)) (justify left bottom mirror))
    )
    (fp_text user "Author: Antmicro" (at -0.932 -4.17) (layer "B.Fab") hide
        (effects (font (size 0.7 0.7) (thickness 0.15)) (justify left bottom mirror))
    )
    (fp_rect (start -0.94 0.47) (end 0.94 -0.47)
      (stroke (width 0.05) (type solid)) (fill none) (layer "B.CrtYd"))
    (fp_rect (start -0.499 0.249) (end 0.499 -0.249)
      (stroke (width 0.15) (type solid)) (fill none) (layer "B.Fab"))
    (pad "1" smd roundrect (at -0.484 0 180) (size 0.59 0.64) (layers "B.Cu" "B.Paste" "B.Mask") (roundrect_rratio 0.25)
      (net 17 "PS_1V8") (pintype "passive"))
    (pad "2" smd roundrect (at 0.484 0 180) (size 0.59 0.64) (layers "B.Cu" "B.Paste" "B.Mask") (roundrect_rratio 0.25)
      (net 1 "GND") (pintype "passive"))
  )

  (footprint "kria-k26-devboard-footprints:C_0402_1005Metric" (layer "B.Cu")
    (at 101.75 141.9)
    (descr "Capacitor SMD 0402")
    (tags "capacitor SMD 0402")
    (property "Author" "Antmicro")
    (property "Dielectric" "")
    (property "License" "Apache-2.0")
    (property "MPN" "MC0402X473K160CT")
    (property "Manufacturer" "Multicomp")
    (property "Sheetfile" "reset.kicad_sch")
    (property "Sheetname" "Reset logic")
    (property "Val" "47n")
    (property "Voltage" "")
    (property "ki_description" " ")
    (attr smd)
    (fp_text reference "C131" (at 1.35 1.33 180) (layer "B.SilkS")
        (effects (font (size 0.7 0.7) (thickness 0.15)) (justify left bottom mirror))
    )
    (fp_text value "C_47n_0402" (at 0 -1.4 180) (layer "B.Fab") hide
        (effects (font (size 0.7 0.7) (thickness 0.15)) (justify left bottom mirror))
    )
    (fp_text user "Author: Antmicro" (at -0.932 -4.17 180) (layer "B.Fab") hide
        (effects (font (size 0.7 0.7) (thickness 0.15)) (justify left bottom mirror))
    )
    (fp_text user "${REFERENCE}" (at -0.932 -3.168 180) (layer "B.Fab") hide
        (effects (font (size 0.7 0.7) (thickness 0.15)) (justify left bottom mirror))
    )
    (fp_text user "License: Apache-2.0" (at -0.932 -5.17 180) (layer "B.Fab") hide
        (effects (font (size 0.7 0.7) (thickness 0.15)) (justify left bottom mirror))
    )
    (fp_rect (start -0.94 0.47) (end 0.94 -0.47)
      (stroke (width 0.05) (type solid)) (fill none) (layer "B.CrtYd"))
    (fp_rect (start -0.499 0.249) (end 0.499 -0.249)
      (stroke (width 0.15) (type solid)) (fill none) (layer "B.Fab"))
    (pad "1" smd roundrect (at -0.484 0) (size 0.59 0.64) (layers "B.Cu" "B.Paste" "B.Mask") (roundrect_rratio 0.25)
      (net 247 "Net-(U31-CT)") (pintype "passive"))
    (pad "2" smd roundrect (at 0.484 0) (size 0.59 0.64) (layers "B.Cu" "B.Paste" "B.Mask") (roundrect_rratio 0.25)
      (net 1 "GND") (pintype "passive"))
  )

  (footprint "kria-k26-devboard-footprints:R_0402_1005Metric" (layer "B.Cu")
    (at 109.65 139.665 -90)
    (descr "Resistor SMD 0402")
    (tags "resistor SMD 0402")
    (property "Author" "Antmicro")
    (property "License" "Apache-2.0")
    (property "MPN" "CR0402-FX-1003GLF")
    (property "Manufacturer" "Bourns")
    (property "Sheetfile" "reset.kicad_sch")
    (property "Sheetname" "Reset logic")
    (property "Tolerance" "1%")
    (property "Val" "100k")
    (property "ki_description" "100k resistor in 0402 package with 1% tolerance")
    (attr smd)
    (fp_text reference "R89" (at -0.995 0.59 90) (layer "B.SilkS")
        (effects (font (size 0.7 0.7) (thickness 0.15)) (justify left bottom mirror))
    )
    (fp_text value "R_100k_0402" (at 0 -1.4 90) (layer "B.Fab") hide
        (effects (font (size 0.7 0.7) (thickness 0.15)) (justify left bottom mirror))
    )
    (fp_text user "License: Apache-2.0" (at -0.95 -5.169 90) (layer "B.Fab") hide
        (effects (font (size 0.7 0.7) (thickness 0.15)) (justify left bottom mirror))
    )
    (fp_text user "Author: Antmicro" (at -0.95 -4.169 90) (layer "B.Fab") hide
        (effects (font (size 0.7 0.7) (thickness 0.15)) (justify left bottom mirror))
    )
    (fp_text user "${REFERENCE}" (at -0.95 -3.168 90) (layer "B.Fab") hide
        (effects (font (size 0.7 0.7) (thickness 0.15)) (justify left bottom mirror))
    )
    (fp_rect (start -0.93 0.47) (end 0.93 -0.47)
      (stroke (width 0.05) (type solid)) (fill none) (layer "B.CrtYd"))
    (fp_rect (start -0.5 0.25) (end 0.5 -0.25)
      (stroke (width 0.15) (type solid)) (fill none) (layer "B.Fab"))
    (pad "1" smd roundrect (at -0.485 0 270) (size 0.59 0.64) (layers "B.Cu" "B.Paste" "B.Mask") (roundrect_rratio 0.25)
      (net 1 "GND") (pintype "passive"))
    (pad "2" smd roundrect (at 0.485 0 270) (size 0.59 0.64) (layers "B.Cu" "B.Paste" "B.Mask") (roundrect_rratio 0.25)
      (net 677 "Net-(U33-1A2)") (pintype "passive"))
  )

  (footprint "kria-k26-devboard-footprints:R_0402_1005Metric" (layer "B.Cu")
    (at 115.7 143.1 180)
    (descr "Resistor SMD 0402")
    (tags "resistor SMD 0402")
    (property "Author" "Antmicro")
    (property "License" "Apache-2.0")
    (property "MPN" "CR0402-FX-1002GLF")
    (property "Manufacturer" "Bourns")
    (property "Sheetfile" "reset.kicad_sch")
    (property "Sheetname" "Reset logic")
    (property "Tolerance" "1%")
    (property "Val" "10k")
    (property "ki_description" "10k resistor in 0402 package with 1% tolerance")
    (attr smd)
    (fp_text reference "R93" (at -3.07 -0.34) (layer "B.SilkS")
        (effects (font (size 0.7 0.7) (thickness 0.15)) (justify left bottom mirror))
    )
    (fp_text value "R_10k_0402" (at 0 -1.4) (layer "B.Fab") hide
        (effects (font (size 0.7 0.7) (thickness 0.15)) (justify left bottom mirror))
    )
    (fp_text user "Author: Antmicro" (at -0.95 -4.169) (layer "B.Fab") hide
        (effects (font (size 0.7 0.7) (thickness 0.15)) (justify left bottom mirror))
    )
    (fp_text user "License: Apache-2.0" (at -0.95 -5.169) (layer "B.Fab") hide
        (effects (font (size 0.7 0.7) (thickness 0.15)) (justify left bottom mirror))
    )
    (fp_text user "${REFERENCE}" (at -0.95 -3.168) (layer "B.Fab") hide
        (effects (font (size 0.7 0.7) (thickness 0.15)) (justify left bottom mirror))
    )
    (fp_rect (start -0.93 0.47) (end 0.93 -0.47)
      (stroke (width 0.05) (type solid)) (fill none) (layer "B.CrtYd"))
    (fp_rect (start -0.5 0.25) (end 0.5 -0.25)
      (stroke (width 0.15) (type solid)) (fill none) (layer "B.Fab"))
    (pad "1" smd roundrect (at -0.485 0 180) (size 0.59 0.64) (layers "B.Cu" "B.Paste" "B.Mask") (roundrect_rratio 0.25)
      (net 15 "PS_3V3") (pintype "passive"))
    (pad "2" smd roundrect (at 0.485 0 180) (size 0.59 0.64) (layers "B.Cu" "B.Paste" "B.Mask") (roundrect_rratio 0.25)
      (net 221 "/PCIE M2 key E /~{M2_PERST}") (pintype "passive"))
  )

  (footprint "kria-k26-devboard-footprints:R_0402_1005Metric" (layer "B.Cu")
    (at 110.95 144.2 180)
    (descr "Resistor SMD 0402")
    (tags "resistor SMD 0402")
    (property "Author" "Antmicro")
    (property "License" "Apache-2.0")
    (property "MPN" "CR0402-FX-1003GLF")
    (property "Manufacturer" "Bourns")
    (property "Sheetfile" "reset.kicad_sch")
    (property "Sheetname" "Reset logic")
    (property "Tolerance" "1%")
    (property "Val" "100k")
    (property "ki_description" "100k resistor in 0402 package with 1% tolerance")
    (attr smd)
    (fp_text reference "R88" (at -1.12 -1.35) (layer "B.SilkS")
        (effects (font (size 0.7 0.7) (thickness 0.15)) (justify left bottom mirror))
    )
    (fp_text value "R_100k_0402" (at 0 -1.4) (layer "B.Fab") hide
        (effects (font (size 0.7 0.7) (thickness 0.15)) (justify left bottom mirror))
    )
    (fp_text user "License: Apache-2.0" (at -0.95 -5.169) (layer "B.Fab") hide
        (effects (font (size 0.7 0.7) (thickness 0.15)) (justify left bottom mirror))
    )
    (fp_text user "${REFERENCE}" (at -0.95 -3.168) (layer "B.Fab") hide
        (effects (font (size 0.7 0.7) (thickness 0.15)) (justify left bottom mirror))
    )
    (fp_text user "Author: Antmicro" (at -0.95 -4.169) (layer "B.Fab") hide
        (effects (font (size 0.7 0.7) (thickness 0.15)) (justify left bottom mirror))
    )
    (fp_rect (start -0.93 0.47) (end 0.93 -0.47)
      (stroke (width 0.05) (type solid)) (fill none) (layer "B.CrtYd"))
    (fp_rect (start -0.5 0.25) (end 0.5 -0.25)
      (stroke (width 0.15) (type solid)) (fill none) (layer "B.Fab"))
    (pad "1" smd roundrect (at -0.485 0 180) (size 0.59 0.64) (layers "B.Cu" "B.Paste" "B.Mask") (roundrect_rratio 0.25)
      (net 1 "GND") (pintype "passive"))
    (pad "2" smd roundrect (at 0.485 0 180) (size 0.59 0.64) (layers "B.Cu" "B.Paste" "B.Mask") (roundrect_rratio 0.25)
      (net 676 "Net-(U34-A_{1})") (pintype "passive"))
  )

  (footprint "kria-k26-devboard-footprints:C_0402_1005Metric" (layer "B.Cu")
    (at 106.585 141.6 180)
    (descr "Capacitor SMD 0402")
    (tags "capacitor SMD 0402")
    (property "Author" "Antmicro")
    (property "Dielectric" "X5R")
    (property "License" "Apache-2.0")
    (property "MPN" "GRM155R61H104KE14D")
    (property "Manufacturer" "Murata")
    (property "Sheetfile" "reset.kicad_sch")
    (property "Sheetname" "Reset logic")
    (property "Val" "100n")
    (property "Voltage" "50V")
    (property "ki_description" " ")
    (attr smd)
    (fp_text reference "C134" (at -0.585 -1.32) (layer "B.SilkS")
        (effects (font (size 0.7 0.7) (thickness 0.15)) (justify left bottom mirror))
    )
    (fp_text value "C_100n_0402" (at 0 -1.4) (layer "B.Fab") hide
        (effects (font (size 0.7 0.7) (thickness 0.15)) (justify left bottom mirror))
    )
    (fp_text user "${REFERENCE}" (at -0.932 -3.168) (layer "B.Fab") hide
        (effects (font (size 0.7 0.7) (thickness 0.15)) (justify left bottom mirror))
    )
    (fp_text user "Author: Antmicro" (at -0.932 -4.17) (layer "B.Fab") hide
        (effects (font (size 0.7 0.7) (thickness 0.15)) (justify left bottom mirror))
    )
    (fp_text user "License: Apache-2.0" (at -0.932 -5.17) (layer "B.Fab") hide
        (effects (font (size 0.7 0.7) (thickness 0.15)) (justify left bottom mirror))
    )
    (fp_rect (start -0.94 0.47) (end 0.94 -0.47)
      (stroke (width 0.05) (type solid)) (fill none) (layer "B.CrtYd"))
    (fp_rect (start -0.499 0.249) (end 0.499 -0.249)
      (stroke (width 0.15) (type solid)) (fill none) (layer "B.Fab"))
    (pad "1" smd roundrect (at -0.484 0 180) (size 0.59 0.64) (layers "B.Cu" "B.Paste" "B.Mask") (roundrect_rratio 0.25)
      (net 17 "PS_1V8") (pintype "passive"))
    (pad "2" smd roundrect (at 0.484 0 180) (size 0.59 0.64) (layers "B.Cu" "B.Paste" "B.Mask") (roundrect_rratio 0.25)
      (net 1 "GND") (pintype "passive"))
  )

  (footprint "kria-k26-devboard-footprints:R_0402_1005Metric" (layer "B.Cu")
    (at 115.7 142.1 180)
    (descr "Resistor SMD 0402")
    (tags "resistor SMD 0402")
    (property "Author" "Antmicro")
    (property "License" "Apache-2.0")
    (property "MPN" "CR0402-FX-1003GLF")
    (property "Manufacturer" "Bourns")
    (property "Sheetfile" "reset.kicad_sch")
    (property "Sheetname" "Reset logic")
    (property "Tolerance" "1%")
    (property "Val" "100k")
    (property "ki_description" "100k resistor in 0402 package with 1% tolerance")
    (attr smd)
    (fp_text reference "R91" (at -3.07 -0.34) (layer "B.SilkS")
        (effects (font (size 0.7 0.7) (thickness 0.15)) (justify left bottom mirror))
    )
    (fp_text value "R_100k_0402" (at 0 -1.4) (layer "B.Fab") hide
        (effects (font (size 0.7 0.7) (thickness 0.15)) (justify left bottom mirror))
    )
    (fp_text user "Author: Antmicro" (at -0.95 -4.169) (layer "B.Fab") hide
        (effects (font (size 0.7 0.7) (thickness 0.15)) (justify left bottom mirror))
    )
    (fp_text user "${REFERENCE}" (at -0.95 -3.168) (layer "B.Fab") hide
        (effects (font (size 0.7 0.7) (thickness 0.15)) (justify left bottom mirror))
    )
    (fp_text user "License: Apache-2.0" (at -0.95 -5.169) (layer "B.Fab") hide
        (effects (font (size 0.7 0.7) (thickness 0.15)) (justify left bottom mirror))
    )
    (fp_rect (start -0.93 0.47) (end 0.93 -0.47)
      (stroke (width 0.05) (type solid)) (fill none) (layer "B.CrtYd"))
    (fp_rect (start -0.5 0.25) (end 0.5 -0.25)
      (stroke (width 0.15) (type solid)) (fill none) (layer "B.Fab"))
    (pad "1" smd roundrect (at -0.485 0 180) (size 0.59 0.64) (layers "B.Cu" "B.Paste" "B.Mask") (roundrect_rratio 0.25)
      (net 1 "GND") (pintype "passive"))
    (pad "2" smd roundrect (at 0.485 0 180) (size 0.59 0.64) (layers "B.Cu" "B.Paste" "B.Mask") (roundrect_rratio 0.25)
      (net 679 "Net-(U33-2A2)") (pintype "passive"))
  )

  (footprint "kria-k26-devboard-footprints:C_0402_1005Metric" (layer "B.Cu")
    (at 105.75 133.9 -90)
    (descr "Capacitor SMD 0402")
    (tags "capacitor SMD 0402")
    (property "Author" "Antmicro")
    (property "Dielectric" "X5R")
    (property "License" "Apache-2.0")
    (property "MPN" "GRM155R61H104KE14D")
    (property "Manufacturer" "Murata")
    (property "Sheetfile" "i2c.kicad_sch")
    (property "Sheetname" "I2C ")
    (property "Val" "100n")
    (property "Voltage" "50V")
    (property "ki_description" " ")
    (attr smd)
    (fp_text reference "C34" (at 0.85 -0.35 90) (layer "B.SilkS")
        (effects (font (size 0.7 0.7) (thickness 0.15)) (justify left bottom mirror))
    )
    (fp_text value "C_100n_0402" (at 0 -1.4 90) (layer "B.Fab") hide
        (effects (font (size 0.7 0.7) (thickness 0.15)) (justify left bottom mirror))
    )
    (fp_text user "License: Apache-2.0" (at -0.932 -5.17 90) (layer "B.Fab") hide
        (effects (font (size 0.7 0.7) (thickness 0.15)) (justify left bottom mirror))
    )
    (fp_text user "${REFERENCE}" (at -0.932 -3.168 90) (layer "B.Fab") hide
        (effects (font (size 0.7 0.7) (thickness 0.15)) (justify left bottom mirror))
    )
    (fp_text user "Author: Antmicro" (at -0.932 -4.17 90) (layer "B.Fab") hide
        (effects (font (size 0.7 0.7) (thickness 0.15)) (justify left bottom mirror))
    )
    (fp_rect (start -0.94 0.47) (end 0.94 -0.47)
      (stroke (width 0.05) (type solid)) (fill none) (layer "B.CrtYd"))
    (fp_rect (start -0.499 0.249) (end 0.499 -0.249)
      (stroke (width 0.15) (type solid)) (fill none) (layer "B.Fab"))
    (pad "1" smd roundrect (at -0.484 0 270) (size 0.59 0.64) (layers "B.Cu" "B.Paste" "B.Mask") (roundrect_rratio 0.25)
      (net 15 "PS_3V3") (pintype "passive"))
    (pad "2" smd roundrect (at 0.484 0 270) (size 0.59 0.64) (layers "B.Cu" "B.Paste" "B.Mask") (roundrect_rratio 0.25)
      (net 1 "GND") (pintype "passive"))
  )

  (footprint "kria-k26-devboard-footprints:R_0402_1005Metric" (layer "B.Cu")
    (at 101.84 135.29)
    (descr "Resistor SMD 0402")
    (tags "resistor SMD 0402")
    (property "Author" "Antmicro")
    (property "License" "Apache-2.0")
    (property "MPN" "CR0402-FX-2201GLF")
    (property "Manufacturer" "Bourns")
    (property "Sheetfile" "i2c.kicad_sch")
    (property "Sheetname" "I2C ")
    (property "Tolerance" "1%")
    (property "Val" "2k2")
    (property "ki_description" "2k2 resistor in 0402 package with 1% tolerance")
    (attr smd)
    (fp_text reference "R34" (at -0.85 0.52 180) (layer "B.SilkS")
        (effects (font (size 0.7 0.7) (thickness 0.15)) (justify left bottom mirror))
    )
    (fp_text value "R_2k2_0402" (at 0 -1.4 180) (layer "B.Fab") hide
        (effects (font (size 0.7 0.7) (thickness 0.15)) (justify left bottom mirror))
    )
    (fp_text user "License: Apache-2.0" (at -0.95 -5.169 180) (layer "B.Fab") hide
        (effects (font (size 0.7 0.7) (thickness 0.15)) (justify left bottom mirror))
    )
    (fp_text user "Author: Antmicro" (at -0.95 -4.169 180) (layer "B.Fab") hide
        (effects (font (size 0.7 0.7) (thickness 0.15)) (justify left bottom mirror))
    )
    (fp_text user "${REFERENCE}" (at -0.95 -3.168 180) (layer "B.Fab") hide
        (effects (font (size 0.7 0.7) (thickness 0.15)) (justify left bottom mirror))
    )
    (fp_rect (start -0.93 0.47) (end 0.93 -0.47)
      (stroke (width 0.05) (type solid)) (fill none) (layer "B.CrtYd"))
    (fp_rect (start -0.5 0.25) (end 0.5 -0.25)
      (stroke (width 0.15) (type solid)) (fill none) (layer "B.Fab"))
    (pad "1" smd roundrect (at -0.485 0) (size 0.59 0.64) (layers "B.Cu" "B.Paste" "B.Mask") (roundrect_rratio 0.25)
      (net 15 "PS_3V3") (pintype "passive"))
    (pad "2" smd roundrect (at 0.485 0) (size 0.59 0.64) (layers "B.Cu" "B.Paste" "B.Mask") (roundrect_rratio 0.25)
      (net 162 "/I2C /I2C_SCK_3V3") (pintype "passive"))
  )

  (footprint "kria-k26-devboard-footprints:R_0402_1005Metric" (layer "B.Cu")
    (at 101.84 133.39)
    (descr "Resistor SMD 0402")
    (tags "resistor SMD 0402")
    (property "Author" "Antmicro")
    (property "License" "Apache-2.0")
    (property "MPN" "CR0402-FX-2003GLF")
    (property "Manufacturer" "Bourns")
    (property "Sheetfile" "i2c.kicad_sch")
    (property "Sheetname" "I2C ")
    (property "Tolerance" "1%")
    (property "Val" "200k")
    (property "ki_description" "200k resistor in 0402 package with 1% tolerance")
    (attr smd)
    (fp_text reference "R33" (at -0.87 0.49 180) (layer "B.SilkS")
        (effects (font (size 0.7 0.7) (thickness 0.15)) (justify left bottom mirror))
    )
    (fp_text value "R_200k_0402" (at 0 -1.4 180) (layer "B.Fab") hide
        (effects (font (size 0.7 0.7) (thickness 0.15)) (justify left bottom mirror))
    )
    (fp_text user "License: Apache-2.0" (at -0.95 -5.169 180) (layer "B.Fab") hide
        (effects (font (size 0.7 0.7) (thickness 0.15)) (justify left bottom mirror))
    )
    (fp_text user "Author: Antmicro" (at -0.95 -4.169 180) (layer "B.Fab") hide
        (effects (font (size 0.7 0.7) (thickness 0.15)) (justify left bottom mirror))
    )
    (fp_text user "${REFERENCE}" (at -0.95 -3.168 180) (layer "B.Fab") hide
        (effects (font (size 0.7 0.7) (thickness 0.15)) (justify left bottom mirror))
    )
    (fp_rect (start -0.93 0.47) (end 0.93 -0.47)
      (stroke (width 0.05) (type solid)) (fill none) (layer "B.CrtYd"))
    (fp_rect (start -0.5 0.25) (end 0.5 -0.25)
      (stroke (width 0.15) (type solid)) (fill none) (layer "B.Fab"))
    (pad "1" smd roundrect (at -0.485 0) (size 0.59 0.64) (layers "B.Cu" "B.Paste" "B.Mask") (roundrect_rratio 0.25)
      (net 15 "PS_3V3") (pintype "passive"))
    (pad "2" smd roundrect (at 0.485 0) (size 0.59 0.64) (layers "B.Cu" "B.Paste" "B.Mask") (roundrect_rratio 0.25)
      (net 324 "/I2C /Vref2") (pintype "passive"))
  )

  (footprint "kria-k26-devboard-footprints:C_0402_1005Metric" (layer "B.Cu")
    (at 101.84 134.34 180)
    (descr "Capacitor SMD 0402")
    (tags "capacitor SMD 0402")
    (property "Author" "Antmicro")
    (property "Dielectric" "C0G")
    (property "License" "Apache-2.0")
    (property "MPN" "GCM1555C1H101JA16D")
    (property "Manufacturer" "Murata")
    (property "Sheetfile" "i2c.kicad_sch")
    (property "Sheetname" "I2C ")
    (property "Val" "100p")
    (property "Voltage" "50V")
    (property "ki_description" " ")
    (attr smd)
    (fp_text reference "C33" (at 0.86 -0.49) (layer "B.SilkS")
        (effects (font (size 0.7 0.7) (thickness 0.15)) (justify left bottom mirror))
    )
    (fp_text value "C_100p_0402" (at 0 -1.4) (layer "B.Fab") hide
        (effects (font (size 0.7 0.7) (thickness 0.15)) (justify left bottom mirror))
    )
    (fp_text user "License: Apache-2.0" (at -0.932 -5.17) (layer "B.Fab") hide
        (effects (font (size 0.7 0.7) (thickness 0.15)) (justify left bottom mirror))
    )
    (fp_text user "Author: Antmicro" (at -0.932 -4.17) (layer "B.Fab") hide
        (effects (font (size 0.7 0.7) (thickness 0.15)) (justify left bottom mirror))
    )
    (fp_text user "${REFERENCE}" (at -0.932 -3.168) (layer "B.Fab") hide
        (effects (font (size 0.7 0.7) (thickness 0.15)) (justify left bottom mirror))
    )
    (fp_rect (start -0.94 0.47) (end 0.94 -0.47)
      (stroke (width 0.05) (type solid)) (fill none) (layer "B.CrtYd"))
    (fp_rect (start -0.499 0.249) (end 0.499 -0.249)
      (stroke (width 0.15) (type solid)) (fill none) (layer "B.Fab"))
    (pad "1" smd roundrect (at -0.484 0 180) (size 0.59 0.64) (layers "B.Cu" "B.Paste" "B.Mask") (roundrect_rratio 0.25)
      (net 324 "/I2C /Vref2") (pintype "passive"))
    (pad "2" smd roundrect (at 0.484 0 180) (size 0.59 0.64) (layers "B.Cu" "B.Paste" "B.Mask") (roundrect_rratio 0.25)
      (net 1 "GND") (pintype "passive"))
  )

  (footprint "kria-k26-devboard-footprints:R_0402_1005Metric" (layer "B.Cu")
    (at 101.84 136.24)
    (descr "Resistor SMD 0402")
    (tags "resistor SMD 0402")
    (property "Author" "Antmicro")
    (property "License" "Apache-2.0")
    (property "MPN" "CR0402-FX-2201GLF")
    (property "Manufacturer" "Bourns")
    (property "Sheetfile" "i2c.kicad_sch")
    (property "Sheetname" "I2C ")
    (property "Tolerance" "1%")
    (property "Val" "2k2")
    (property "ki_description" "2k2 resistor in 0402 package with 1% tolerance")
    (attr smd)
    (fp_text reference "R35" (at -0.85 0.56 180) (layer "B.SilkS")
        (effects (font (size 0.7 0.7) (thickness 0.15)) (justify left bottom mirror))
    )
    (fp_text value "R_2k2_0402" (at 0 -1.4 180) (layer "B.Fab") hide
        (effects (font (size 0.7 0.7) (thickness 0.15)) (justify left bottom mirror))
    )
    (fp_text user "Author: Antmicro" (at -0.95 -4.169 180) (layer "B.Fab") hide
        (effects (font (size 0.7 0.7) (thickness 0.15)) (justify left bottom mirror))
    )
    (fp_text user "License: Apache-2.0" (at -0.95 -5.169 180) (layer "B.Fab") hide
        (effects (font (size 0.7 0.7) (thickness 0.15)) (justify left bottom mirror))
    )
    (fp_text user "${REFERENCE}" (at -0.95 -3.168 180) (layer "B.Fab") hide
        (effects (font (size 0.7 0.7) (thickness 0.15)) (justify left bottom mirror))
    )
    (fp_rect (start -0.93 0.47) (end 0.93 -0.47)
      (stroke (width 0.05) (type solid)) (fill none) (layer "B.CrtYd"))
    (fp_rect (start -0.5 0.25) (end 0.5 -0.25)
      (stroke (width 0.15) (type solid)) (fill none) (layer "B.Fab"))
    (pad "1" smd roundrect (at -0.485 0) (size 0.59 0.64) (layers "B.Cu" "B.Paste" "B.Mask") (roundrect_rratio 0.25)
      (net 15 "PS_3V3") (pintype "passive"))
    (pad "2" smd roundrect (at 0.485 0) (size 0.59 0.64) (layers "B.Cu" "B.Paste" "B.Mask") (roundrect_rratio 0.25)
      (net 163 "/I2C /I2C_SDA_3V3") (pintype "passive"))
  )

  (footprint "kria-k26-devboard-footprints:C_0402_1005Metric" (layer "B.Cu")
    (at 116.556942 86.4)
    (descr "Capacitor SMD 0402")
    (tags "capacitor SMD 0402")
    (property "Author" "Antmicro")
    (property "Dielectric" "X5R")
    (property "License" "Apache-2.0")
    (property "MPN" "GRM155R61H104KE14D")
    (property "Manufacturer" "Murata")
    (property "Sheetfile" "usb.kicad_sch")
    (property "Sheetname" "USB")
    (property "Val" "100n")
    (property "Voltage" "50V")
    (property "ki_description" " ")
    (attr smd)
    (fp_text reference "C43" (at -0.896942 0.38 180) (layer "B.SilkS")
        (effects (font (size 0.7 0.7) (thickness 0.15)) (justify left bottom mirror))
    )
    (fp_text value "C_100n_0402" (at 0 -1.4 180) (layer "B.Fab") hide
        (effects (font (size 0.7 0.7) (thickness 0.15)) (justify left bottom mirror))
    )
    (fp_text user "License: Apache-2.0" (at -0.932 -5.17 180) (layer "B.Fab") hide
        (effects (font (size 0.7 0.7) (thickness 0.15)) (justify left bottom mirror))
    )
    (fp_text user "Author: Antmicro" (at -0.932 -4.17 180) (layer "B.Fab") hide
        (effects (font (size 0.7 0.7) (thickness 0.15)) (justify left bottom mirror))
    )
    (fp_text user "${REFERENCE}" (at -0.932 -3.168 180) (layer "B.Fab") hide
        (effects (font (size 0.7 0.7) (thickness 0.15)) (justify left bottom mirror))
    )
    (fp_rect (start -0.94 0.47) (end 0.94 -0.47)
      (stroke (width 0.05) (type solid)) (fill none) (layer "B.CrtYd"))
    (fp_rect (start -0.499 0.249) (end 0.499 -0.249)
      (stroke (width 0.15) (type solid)) (fill none) (layer "B.Fab"))
    (pad "1" smd roundrect (at -0.484 0) (size 0.59 0.64) (layers "B.Cu" "B.Paste" "B.Mask") (roundrect_rratio 0.25)
      (net 15 "PS_3V3") (pintype "passive"))
    (pad "2" smd roundrect (at 0.484 0) (size 0.59 0.64) (layers "B.Cu" "B.Paste" "B.Mask") (roundrect_rratio 0.25)
      (net 1 "GND") (pintype "passive"))
  )

  (footprint "kria-k26-devboard-footprints:C_0402_1005Metric" (layer "B.Cu")
    (at 121.7 90 90)
    (descr "Capacitor SMD 0402")
    (tags "capacitor SMD 0402")
    (property "Author" "Antmicro")
    (property "Dielectric" "X5R")
    (property "License" "Apache-2.0")
    (property "MPN" "GRM155R61H104KE14D")
    (property "Manufacturer" "Murata")
    (property "Sheetfile" "usb.kicad_sch")
    (property "Sheetname" "USB")
    (property "Val" "100n")
    (property "Voltage" "50V")
    (property "ki_description" " ")
    (attr smd)
    (fp_text reference "C51" (at -0.84 0.39 270) (layer "B.SilkS")
        (effects (font (size 0.7 0.7) (thickness 0.15)) (justify left bottom mirror))
    )
    (fp_text value "C_100n_0402" (at 0 -1.4 270) (layer "B.Fab") hide
        (effects (font (size 0.7 0.7) (thickness 0.15)) (justify left bottom mirror))
    )
    (fp_text user "License: Apache-2.0" (at -0.932 -5.17 270) (layer "B.Fab") hide
        (effects (font (size 0.7 0.7) (thickness 0.15)) (justify left bottom mirror))
    )
    (fp_text user "${REFERENCE}" (at -0.932 -3.168 270) (layer "B.Fab") hide
        (effects (font (size 0.7 0.7) (thickness 0.15)) (justify left bottom mirror))
    )
    (fp_text user "Author: Antmicro" (at -0.932 -4.17 270) (layer "B.Fab") hide
        (effects (font (size 0.7 0.7) (thickness 0.15)) (justify left bottom mirror))
    )
    (fp_rect (start -0.94 0.47) (end 0.94 -0.47)
      (stroke (width 0.05) (type solid)) (fill none) (layer "B.CrtYd"))
    (fp_rect (start -0.499 0.249) (end 0.499 -0.249)
      (stroke (width 0.15) (type solid)) (fill none) (layer "B.Fab"))
    (pad "1" smd roundrect (at -0.484 0 90) (size 0.59 0.64) (layers "B.Cu" "B.Paste" "B.Mask") (roundrect_rratio 0.25)
      (net 15 "PS_3V3") (pintype "passive"))
    (pad "2" smd roundrect (at 0.484 0 90) (size 0.59 0.64) (layers "B.Cu" "B.Paste" "B.Mask") (roundrect_rratio 0.25)
      (net 1 "GND") (pintype "passive"))
  )

  (footprint "kria-k26-devboard-footprints:C_0402_1005Metric" (layer "B.Cu")
    (at 126.4 90 90)
    (descr "Capacitor SMD 0402")
    (tags "capacitor SMD 0402")
    (property "Author" "Antmicro")
    (property "Dielectric" "X5R")
    (property "License" "Apache-2.0")
    (property "MPN" "GRM155R61H104KE14D")
    (property "Manufacturer" "Murata")
    (property "Sheetfile" "usb.kicad_sch")
    (property "Sheetname" "USB")
    (property "Val" "100n")
    (property "Voltage" "50V")
    (property "ki_description" " ")
    (attr smd)
    (fp_text reference "C59" (at -0.88 0.41 270) (layer "B.SilkS")
        (effects (font (size 0.7 0.7) (thickness 0.15)) (justify left bottom mirror))
    )
    (fp_text value "C_100n_0402" (at 0 -1.4 270) (layer "B.Fab") hide
        (effects (font (size 0.7 0.7) (thickness 0.15)) (justify left bottom mirror))
    )
    (fp_text user "Author: Antmicro" (at -0.932 -4.17 270) (layer "B.Fab") hide
        (effects (font (size 0.7 0.7) (thickness 0.15)) (justify left bottom mirror))
    )
    (fp_text user "License: Apache-2.0" (at -0.932 -5.17 270) (layer "B.Fab") hide
        (effects (font (size 0.7 0.7) (thickness 0.15)) (justify left bottom mirror))
    )
    (fp_text user "${REFERENCE}" (at -0.932 -3.168 270) (layer "B.Fab") hide
        (effects (font (size 0.7 0.7) (thickness 0.15)) (justify left bottom mirror))
    )
    (fp_rect (start -0.94 0.47) (end 0.94 -0.47)
      (stroke (width 0.05) (type solid)) (fill none) (layer "B.CrtYd"))
    (fp_rect (start -0.499 0.249) (end 0.499 -0.249)
      (stroke (width 0.15) (type solid)) (fill none) (layer "B.Fab"))
    (pad "1" smd roundrect (at -0.484 0 90) (size 0.59 0.64) (layers "B.Cu" "B.Paste" "B.Mask") (roundrect_rratio 0.25)
      (net 15 "PS_3V3") (pintype "passive"))
    (pad "2" smd roundrect (at 0.484 0 90) (size 0.59 0.64) (layers "B.Cu" "B.Paste" "B.Mask") (roundrect_rratio 0.25)
      (net 1 "GND") (pintype "passive"))
  )

  (footprint "kria-k26-devboard-footprints:C_0402_1005Metric" (layer "B.Cu")
    (at 124.1 90 90)
    (descr "Capacitor SMD 0402")
    (tags "capacitor SMD 0402")
    (property "Author" "Antmicro")
    (property "Dielectric" "X5R")
    (property "License" "Apache-2.0")
    (property "MPN" "GRM155R61H104KE14D")
    (property "Manufacturer" "Murata")
    (property "Sheetfile" "usb.kicad_sch")
    (property "Sheetname" "USB")
    (property "Val" "100n")
    (property "Voltage" "50V")
    (property "ki_description" " ")
    (attr smd)
    (fp_text reference "C61" (at -0.84 0.39 270) (layer "B.SilkS")
        (effects (font (size 0.7 0.7) (thickness 0.15)) (justify left bottom mirror))
    )
    (fp_text value "C_100n_0402" (at 0 -1.4 270) (layer "B.Fab") hide
        (effects (font (size 0.7 0.7) (thickness 0.15)) (justify left bottom mirror))
    )
    (fp_text user "Author: Antmicro" (at -0.932 -4.17 270) (layer "B.Fab") hide
        (effects (font (size 0.7 0.7) (thickness 0.15)) (justify left bottom mirror))
    )
    (fp_text user "${REFERENCE}" (at -0.932 -3.168 270) (layer "B.Fab") hide
        (effects (font (size 0.7 0.7) (thickness 0.15)) (justify left bottom mirror))
    )
    (fp_text user "License: Apache-2.0" (at -0.932 -5.17 270) (layer "B.Fab") hide
        (effects (font (size 0.7 0.7) (thickness 0.15)) (justify left bottom mirror))
    )
    (fp_rect (start -0.94 0.47) (end 0.94 -0.47)
      (stroke (width 0.05) (type solid)) (fill none) (layer "B.CrtYd"))
    (fp_rect (start -0.499 0.249) (end 0.499 -0.249)
      (stroke (width 0.15) (type solid)) (fill none) (layer "B.Fab"))
    (pad "1" smd roundrect (at -0.484 0 90) (size 0.59 0.64) (layers "B.Cu" "B.Paste" "B.Mask") (roundrect_rratio 0.25)
      (net 18 "PS_1V2") (pintype "passive"))
    (pad "2" smd roundrect (at 0.484 0 90) (size 0.59 0.64) (layers "B.Cu" "B.Paste" "B.Mask") (roundrect_rratio 0.25)
      (net 1 "GND") (pintype "passive"))
  )

  (footprint "kria-k26-devboard-footprints:R_0402_1005Metric" (layer "B.Cu")
    (at 116.556942 88.4 180)
    (descr "Resistor SMD 0402")
    (tags "resistor SMD 0402")
    (property "Author" "Antmicro")
    (property "License" "Apache-2.0")
    (property "MPN" "CR0402-FX-2003GLF")
    (property "Manufacturer" "Bourns")
    (property "Sheetfile" "usb.kicad_sch")
    (property "Sheetname" "USB")
    (property "Tolerance" "1%")
    (property "Val" "200k")
    (property "ki_description" "200k resistor in 0402 package with 1% tolerance")
    (attr smd)
    (fp_text reference "R43" (at 0.926942 -0.38) (layer "B.SilkS")
        (effects (font (size 0.7 0.7) (thickness 0.15)) (justify left bottom mirror))
    )
    (fp_text value "R_200k_0402" (at 0 -1.4) (layer "B.Fab") hide
        (effects (font (size 0.7 0.7) (thickness 0.15)) (justify left bottom mirror))
    )
    (fp_text user "Author: Antmicro" (at -0.95 -4.169) (layer "B.Fab") hide
        (effects (font (size 0.7 0.7) (thickness 0.15)) (justify left bottom mirror))
    )
    (fp_text user "License: Apache-2.0" (at -0.95 -5.169) (layer "B.Fab") hide
        (effects (font (size 0.7 0.7) (thickness 0.15)) (justify left bottom mirror))
    )
    (fp_text user "${REFERENCE}" (at -0.95 -3.168) (layer "B.Fab") hide
        (effects (font (size 0.7 0.7) (thickness 0.15)) (justify left bottom mirror))
    )
    (fp_rect (start -0.93 0.47) (end 0.93 -0.47)
      (stroke (width 0.05) (type solid)) (fill none) (layer "B.CrtYd"))
    (fp_rect (start -0.5 0.25) (end 0.5 -0.25)
      (stroke (width 0.15) (type solid)) (fill none) (layer "B.Fab"))
    (pad "1" smd roundrect (at -0.485 0 180) (size 0.59 0.64) (layers "B.Cu" "B.Paste" "B.Mask") (roundrect_rratio 0.25)
      (net 1 "GND") (pintype "passive"))
    (pad "2" smd roundrect (at 0.485 0 180) (size 0.59 0.64) (layers "B.Cu" "B.Paste" "B.Mask") (roundrect_rratio 0.25)
      (net 646 "Net-(U17-SPI_D1{slash}PF23)") (pintype "passive"))
  )

  (footprint "kria-k26-devboard-footprints:R_0402_1005Metric" (layer "B.Cu")
    (at 116.54 89.4 180)
    (descr "Resistor SMD 0402")
    (tags "resistor SMD 0402")
    (property "Author" "Antmicro")
    (property "License" "Apache-2.0")
    (property "MPN" "CR0402-FX-2003GLF")
    (property "Manufacturer" "Bourns")
    (property "Sheetfile" "usb.kicad_sch")
    (property "Sheetname" "USB")
    (property "Tolerance" "1%")
    (property "Val" "200k")
    (property "ki_description" "200k resistor in 0402 package with 1% tolerance")
    (attr smd)
    (fp_text reference "R45" (at 0.926942 -0.38) (layer "B.SilkS")
        (effects (font (size 0.7 0.7) (thickness 0.15)) (justify left bottom mirror))
    )
    (fp_text value "R_200k_0402" (at 0 -1.4) (layer "B.Fab") hide
        (effects (font (size 0.7 0.7) (thickness 0.15)) (justify left bottom mirror))
    )
    (fp_text user "${REFERENCE}" (at -0.95 -3.168) (layer "B.Fab") hide
        (effects (font (size 0.7 0.7) (thickness 0.15)) (justify left bottom mirror))
    )
    (fp_text user "License: Apache-2.0" (at -0.95 -5.169) (layer "B.Fab") hide
        (effects (font (size 0.7 0.7) (thickness 0.15)) (justify left bottom mirror))
    )
    (fp_text user "Author: Antmicro" (at -0.95 -4.169) (layer "B.Fab") hide
        (effects (font (size 0.7 0.7) (thickness 0.15)) (justify left bottom mirror))
    )
    (fp_rect (start -0.93 0.47) (end 0.93 -0.47)
      (stroke (width 0.05) (type solid)) (fill none) (layer "B.CrtYd"))
    (fp_rect (start -0.5 0.25) (end 0.5 -0.25)
      (stroke (width 0.15) (type solid)) (fill none) (layer "B.Fab"))
    (pad "1" smd roundrect (at -0.485 0 180) (size 0.59 0.64) (layers "B.Cu" "B.Paste" "B.Mask") (roundrect_rratio 0.25)
      (net 1 "GND") (pintype "passive"))
    (pad "2" smd roundrect (at 0.485 0 180) (size 0.59 0.64) (layers "B.Cu" "B.Paste" "B.Mask") (roundrect_rratio 0.25)
      (net 648 "Net-(U17-SPI_D3{slash}PF25)") (pintype "passive"))
  )

  (footprint "kria-k26-devboard-footprints:R_0402_1005Metric" (layer "B.Cu")
    (at 116.606942 84.4 180)
    (descr "Resistor SMD 0402")
    (tags "resistor SMD 0402")
    (property "Author" "Antmicro")
    (property "License" "Apache-2.0")
    (property "MPN" "CR0402-FX-1002GLF")
    (property "Manufacturer" "Bourns")
    (property "Sheetfile" "usb.kicad_sch")
    (property "Sheetname" "USB")
    (property "Tolerance" "1%")
    (property "Val" "10k")
    (property "ki_description" "10k resistor in 0402 package with 1% tolerance")
    (attr smd)
    (fp_text reference "R46" (at 0.896942 -0.34) (layer "B.SilkS")
        (effects (font (size 0.7 0.7) (thickness 0.15)) (justify left bottom mirror))
    )
    (fp_text value "R_10k_0402" (at 0 -1.4) (layer "B.Fab") hide
        (effects (font (size 0.7 0.7) (thickness 0.15)) (justify left bottom mirror))
    )
    (fp_text user "${REFERENCE}" (at -0.95 -3.168) (layer "B.Fab") hide
        (effects (font (size 0.7 0.7) (thickness 0.15)) (justify left bottom mirror))
    )
    (fp_text user "Author: Antmicro" (at -0.95 -4.169) (layer "B.Fab") hide
        (effects (font (size 0.7 0.7) (thickness 0.15)) (justify left bottom mirror))
    )
    (fp_text user "License: Apache-2.0" (at -0.95 -5.169) (layer "B.Fab") hide
        (effects (font (size 0.7 0.7) (thickness 0.15)) (justify left bottom mirror))
    )
    (fp_rect (start -0.93 0.47) (end 0.93 -0.47)
      (stroke (width 0.05) (type solid)) (fill none) (layer "B.CrtYd"))
    (fp_rect (start -0.5 0.25) (end 0.5 -0.25)
      (stroke (width 0.15) (type solid)) (fill none) (layer "B.Fab"))
    (pad "1" smd roundrect (at -0.485 0 180) (size 0.59 0.64) (layers "B.Cu" "B.Paste" "B.Mask") (roundrect_rratio 0.25)
      (net 15 "PS_3V3") (pintype "passive"))
    (pad "2" smd roundrect (at 0.485 0 180) (size 0.59 0.64) (layers "B.Cu" "B.Paste" "B.Mask") (roundrect_rratio 0.25)
      (net 649 "Net-(U17-TEST1)") (pintype "passive"))
  )

  (footprint "kria-k26-devboard-footprints:R_0402_1005Metric" (layer "B.Cu")
    (at 116.606943 85.4 180)
    (descr "Resistor SMD 0402")
    (tags "resistor SMD 0402")
    (property "Author" "Antmicro")
    (property "License" "Apache-2.0")
    (property "MPN" "CR0402-FX-1002GLF")
    (property "Manufacturer" "Bourns")
    (property "Sheetfile" "usb.kicad_sch")
    (property "Sheetname" "USB")
    (property "Tolerance" "1%")
    (property "Val" "10k")
    (property "ki_description" "10k resistor in 0402 package with 1% tolerance")
    (attr smd)
    (fp_text reference "R48" (at 0.906943 -0.37) (layer "B.SilkS")
        (effects (font (size 0.7 0.7) (thickness 0.15)) (justify left bottom mirror))
    )
    (fp_text value "R_10k_0402" (at 0 -1.4) (layer "B.Fab") hide
        (effects (font (size 0.7 0.7) (thickness 0.15)) (justify left bottom mirror))
    )
    (fp_text user "Author: Antmicro" (at -0.95 -4.169) (layer "B.Fab") hide
        (effects (font (size 0.7 0.7) (thickness 0.15)) (justify left bottom mirror))
    )
    (fp_text user "License: Apache-2.0" (at -0.95 -5.169) (layer "B.Fab") hide
        (effects (font (size 0.7 0.7) (thickness 0.15)) (justify left bottom mirror))
    )
    (fp_text user "${REFERENCE}" (at -0.95 -3.168) (layer "B.Fab") hide
        (effects (font (size 0.7 0.7) (thickness 0.15)) (justify left bottom mirror))
    )
    (fp_rect (start -0.93 0.47) (end 0.93 -0.47)
      (stroke (width 0.05) (type solid)) (fill none) (layer "B.CrtYd"))
    (fp_rect (start -0.5 0.25) (end 0.5 -0.25)
      (stroke (width 0.15) (type solid)) (fill none) (layer "B.Fab"))
    (pad "1" smd roundrect (at -0.485 0 180) (size 0.59 0.64) (layers "B.Cu" "B.Paste" "B.Mask") (roundrect_rratio 0.25)
      (net 1 "GND") (pintype "passive"))
    (pad "2" smd roundrect (at 0.485 0 180) (size 0.59 0.64) (layers "B.Cu" "B.Paste" "B.Mask") (roundrect_rratio 0.25)
      (net 651 "Net-(U17-TEST3)") (pintype "passive"))
  )

  (footprint "kria-k26-devboard-footprints:R_0402_1005Metric" (layer "B.Cu")
    (at 127.666942 81.32486)
    (descr "Resistor SMD 0402")
    (tags "resistor SMD 0402")
    (property "Author" "Antmicro")
    (property "License" "Apache-2.0")
    (property "MPN" "CR0402-FX-2003GLF")
    (property "Manufacturer" "Bourns")
    (property "Sheetfile" "usb.kicad_sch")
    (property "Sheetname" "USB")
    (property "Tolerance" "1%")
    (property "Val" "200k")
    (property "ki_description" "200k resistor in 0402 package with 1% tolerance")
    (attr smd)
    (fp_text reference "R49" (at 1.043058 -0.61486 180) (layer "B.SilkS")
        (effects (font (size 0.7 0.7) (thickness 0.15)) (justify left bottom mirror))
    )
    (fp_text value "R_200k_0402" (at 0 -1.4 180) (layer "B.Fab") hide
        (effects (font (size 0.7 0.7) (thickness 0.15)) (justify left bottom mirror))
    )
    (fp_text user "License: Apache-2.0" (at -0.95 -5.169 180) (layer "B.Fab") hide
        (effects (font (size 0.7 0.7) (thickness 0.15)) (justify left bottom mirror))
    )
    (fp_text user "${REFERENCE}" (at -0.95 -3.168 180) (layer "B.Fab") hide
        (effects (font (size 0.7 0.7) (thickness 0.15)) (justify left bottom mirror))
    )
    (fp_text user "Author: Antmicro" (at -0.95 -4.169 180) (layer "B.Fab") hide
        (effects (font (size 0.7 0.7) (thickness 0.15)) (justify left bottom mirror))
    )
    (fp_rect (start -0.93 0.47) (end 0.93 -0.47)
      (stroke (width 0.05) (type solid)) (fill none) (layer "B.CrtYd"))
    (fp_rect (start -0.5 0.25) (end 0.5 -0.25)
      (stroke (width 0.15) (type solid)) (fill none) (layer "B.Fab"))
    (pad "1" smd roundrect (at -0.485 0) (size 0.59 0.64) (layers "B.Cu" "B.Paste" "B.Mask") (roundrect_rratio 0.25)
      (net 1 "GND") (pintype "passive"))
    (pad "2" smd roundrect (at 0.485 0) (size 0.59 0.64) (layers "B.Cu" "B.Paste" "B.Mask") (roundrect_rratio 0.25)
      (net 652 "Net-(U17-CFG_STRAP1)") (pintype "passive"))
  )

  (footprint "kria-k26-devboard-footprints:R_0402_1005Metric" (layer "B.Cu")
    (at 118.2 78.97 90)
    (descr "Resistor SMD 0402")
    (tags "resistor SMD 0402")
    (property "Author" "Antmicro")
    (property "License" "Apache-2.0")
    (property "MPN" "CR0402-FX-2003GLF")
    (property "Manufacturer" "Bourns")
    (property "Sheetfile" "usb.kicad_sch")
    (property "Sheetname" "USB")
    (property "Tolerance" "1%")
    (property "Val" "200k")
    (property "ki_description" "200k resistor in 0402 package with 1% tolerance")
    (attr smd)
    (fp_text reference "R55" (at 3.065 0.38 270) (layer "B.SilkS")
        (effects (font (size 0.7 0.7) (thickness 0.15)) (justify left bottom mirror))
    )
    (fp_text value "R_200k_0402" (at 0 -1.4 270) (layer "B.Fab") hide
        (effects (font (size 0.7 0.7) (thickness 0.15)) (justify left bottom mirror))
    )
    (fp_text user "Author: Antmicro" (at -0.95 -4.169 270) (layer "B.Fab") hide
        (effects (font (size 0.7 0.7) (thickness 0.15)) (justify left bottom mirror))
    )
    (fp_text user "License: Apache-2.0" (at -0.95 -5.169 270) (layer "B.Fab") hide
        (effects (font (size 0.7 0.7) (thickness 0.15)) (justify left bottom mirror))
    )
    (fp_text user "${REFERENCE}" (at -0.95 -3.168 270) (layer "B.Fab") hide
        (effects (font (size 0.7 0.7) (thickness 0.15)) (justify left bottom mirror))
    )
    (fp_rect (start -0.93 0.47) (end 0.93 -0.47)
      (stroke (width 0.05) (type solid)) (fill none) (layer "B.CrtYd"))
    (fp_rect (start -0.5 0.25) (end 0.5 -0.25)
      (stroke (width 0.15) (type solid)) (fill none) (layer "B.Fab"))
    (pad "1" smd roundrect (at -0.485 0 90) (size 0.59 0.64) (layers "B.Cu" "B.Paste" "B.Mask") (roundrect_rratio 0.25)
      (net 1 "GND") (pintype "passive"))
    (pad "2" smd roundrect (at 0.485 0 90) (size 0.59 0.64) (layers "B.Cu" "B.Paste" "B.Mask") (roundrect_rratio 0.25)
      (net 658 "Net-(U17-PF5)") (pintype "passive"))
  )

  (footprint "kria-k26-devboard-footprints:R_0402_1005Metric" (layer "B.Cu")
    (at 117.2 78.97 90)
    (descr "Resistor SMD 0402")
    (tags "resistor SMD 0402")
    (property "Author" "Antmicro")
    (property "License" "Apache-2.0")
    (property "MPN" "CR0402-FX-2003GLF")
    (property "Manufacturer" "Bourns")
    (property "Sheetfile" "usb.kicad_sch")
    (property "Sheetname" "USB")
    (property "Tolerance" "1%")
    (property "Val" "200k")
    (property "ki_description" "200k resistor in 0402 package with 1% tolerance")
    (attr smd)
    (fp_text reference "R57" (at 3.065 0.38 270) (layer "B.SilkS")
        (effects (font (size 0.7 0.7) (thickness 0.15)) (justify left bottom mirror))
    )
    (fp_text value "R_200k_0402" (at 0 -1.4 270) (layer "B.Fab") hide
        (effects (font (size 0.7 0.7) (thickness 0.15)) (justify left bottom mirror))
    )
    (fp_text user "License: Apache-2.0" (at -0.95 -5.169 270) (layer "B.Fab") hide
        (effects (font (size 0.7 0.7) (thickness 0.15)) (justify left bottom mirror))
    )
    (fp_text user "${REFERENCE}" (at -0.95 -3.168 270) (layer "B.Fab") hide
        (effects (font (size 0.7 0.7) (thickness 0.15)) (justify left bottom mirror))
    )
    (fp_text user "Author: Antmicro" (at -0.95 -4.169 270) (layer "B.Fab") hide
        (effects (font (size 0.7 0.7) (thickness 0.15)) (justify left bottom mirror))
    )
    (fp_rect (start -0.93 0.47) (end 0.93 -0.47)
      (stroke (width 0.05) (type solid)) (fill none) (layer "B.CrtYd"))
    (fp_rect (start -0.5 0.25) (end 0.5 -0.25)
      (stroke (width 0.15) (type solid)) (fill none) (layer "B.Fab"))
    (pad "1" smd roundrect (at -0.485 0 90) (size 0.59 0.64) (layers "B.Cu" "B.Paste" "B.Mask") (roundrect_rratio 0.25)
      (net 1 "GND") (pintype "passive"))
    (pad "2" smd roundrect (at 0.485 0 90) (size 0.59 0.64) (layers "B.Cu" "B.Paste" "B.Mask") (roundrect_rratio 0.25)
      (net 660 "Net-(U17-PF7)") (pintype "passive"))
  )

  (footprint "kria-k26-devboard-footprints:R_0402_1005Metric" (layer "B.Cu")
    (at 127.666943 88.55)
    (descr "Resistor SMD 0402")
    (tags "resistor SMD 0402")
    (property "Author" "Antmicro")
    (property "License" "Apache-2.0")
    (property "MPN" "CR0402-FX-2003GLF")
    (property "Manufacturer" "Bourns")
    (property "Sheetfile" "usb.kicad_sch")
    (property "Sheetname" "USB")
    (property "Tolerance" "1%")
    (property "Val" "200k")
    (property "ki_description" "200k resistor in 0402 package with 1% tolerance")
    (attr smd)
    (fp_text reference "R60" (at -0.906943 0.35 180) (layer "B.SilkS")
        (effects (font (size 0.7 0.7) (thickness 0.15)) (justify left bottom mirror))
    )
    (fp_text value "R_200k_0402" (at 0 -1.4 180) (layer "B.Fab") hide
        (effects (font (size 0.7 0.7) (thickness 0.15)) (justify left bottom mirror))
    )
    (fp_text user "Author: Antmicro" (at -0.95 -4.169 180) (layer "B.Fab") hide
        (effects (font (size 0.7 0.7) (thickness 0.15)) (justify left bottom mirror))
    )
    (fp_text user "License: Apache-2.0" (at -0.95 -5.169 180) (layer "B.Fab") hide
        (effects (font (size 0.7 0.7) (thickness 0.15)) (justify left bottom mirror))
    )
    (fp_text user "${REFERENCE}" (at -0.95 -3.168 180) (layer "B.Fab") hide
        (effects (font (size 0.7 0.7) (thickness 0.15)) (justify left bottom mirror))
    )
    (fp_rect (start -0.93 0.47) (end 0.93 -0.47)
      (stroke (width 0.05) (type solid)) (fill none) (layer "B.CrtYd"))
    (fp_rect (start -0.5 0.25) (end 0.5 -0.25)
      (stroke (width 0.15) (type solid)) (fill none) (layer "B.Fab"))
    (pad "1" smd roundrect (at -0.485 0) (size 0.59 0.64) (layers "B.Cu" "B.Paste" "B.Mask") (roundrect_rratio 0.25)
      (net 1 "GND") (pintype "passive"))
    (pad "2" smd roundrect (at 0.485 0) (size 0.59 0.64) (layers "B.Cu" "B.Paste" "B.Mask") (roundrect_rratio 0.25)
      (net 663 "Net-(U17-PF30)") (pintype "passive"))
  )

  (footprint "kria-k26-devboard-footprints:C_0402_1005Metric" (layer "B.Cu")
    (at 96.45 146.95 90)
    (descr "Capacitor SMD 0402")
    (tags "capacitor SMD 0402")
    (property "Author" "Antmicro")
    (property "Dielectric" "X5R")
    (property "License" "Apache-2.0")
    (property "MPN" "GRM155R61H104KE14D")
    (property "Manufacturer" "Murata")
    (property "Sheetfile" "reset.kicad_sch")
    (property "Sheetname" "Reset logic")
    (property "Val" "100n")
    (property "Voltage" "50V")
    (property "ki_description" " ")
    (attr smd)
    (fp_text reference "C135" (at 1.33 1.33 270) (layer "B.SilkS")
        (effects (font (size 0.7 0.7) (thickness 0.15)) (justify left bottom mirror))
    )
    (fp_text value "C_100n_0402" (at 0 -1.4 270) (layer "B.Fab") hide
        (effects (font (size 0.7 0.7) (thickness 0.15)) (justify left bottom mirror))
    )
    (fp_text user "License: Apache-2.0" (at -0.932 -5.17 270) (layer "B.Fab") hide
        (effects (font (size 0.7 0.7) (thickness 0.15)) (justify left bottom mirror))
    )
    (fp_text user "Author: Antmicro" (at -0.932 -4.17 270) (layer "B.Fab") hide
        (effects (font (size 0.7 0.7) (thickness 0.15)) (justify left bottom mirror))
    )
    (fp_text user "${REFERENCE}" (at -0.932 -3.168 270) (layer "B.Fab") hide
        (effects (font (size 0.7 0.7) (thickness 0.15)) (justify left bottom mirror))
    )
    (fp_rect (start -0.94 0.47) (end 0.94 -0.47)
      (stroke (width 0.05) (type solid)) (fill none) (layer "B.CrtYd"))
    (fp_rect (start -0.499 0.249) (end 0.499 -0.249)
      (stroke (width 0.15) (type solid)) (fill none) (layer "B.Fab"))
    (pad "1" smd roundrect (at -0.484 0 90) (size 0.59 0.64) (layers "B.Cu" "B.Paste" "B.Mask") (roundrect_rratio 0.25)
      (net 20 "PL_3V3") (pintype "passive"))
    (pad "2" smd roundrect (at 0.484 0 90) (size 0.59 0.64) (layers "B.Cu" "B.Paste" "B.Mask") (roundrect_rratio 0.25)
      (net 1 "GND") (pintype "passive"))
  )

  (footprint "kria-k26-devboard-footprints:C_0402_1005Metric" (layer "B.Cu")
    (at 96.725 140.575001 -90)
    (descr "Capacitor SMD 0402")
    (tags "capacitor SMD 0402")
    (property "Author" "Antmicro")
    (property "Dielectric" "")
    (property "License" "Apache-2.0")
    (property "MPN" "MC0402X473K160CT")
    (property "Manufacturer" "Multicomp")
    (property "Sheetfile" "reset.kicad_sch")
    (property "Sheetname" "Reset logic")
    (property "Val" "47n")
    (property "Voltage" "")
    (property "ki_description" " ")
    (attr smd)
    (fp_text reference "C130" (at -1.395001 0.605 90) (layer "B.SilkS")
        (effects (font (size 0.7 0.7) (thickness 0.15)) (justify left bottom mirror))
    )
    (fp_text value "C_47n_0402" (at 0 -1.4 90) (layer "B.Fab") hide
        (effects (font (size 0.7 0.7) (thickness 0.15)) (justify left bottom mirror))
    )
    (fp_text user "License: Apache-2.0" (at -0.932 -5.17 90) (layer "B.Fab") hide
        (effects (font (size 0.7 0.7) (thickness 0.15)) (justify left bottom mirror))
    )
    (fp_text user "${REFERENCE}" (at -0.932 -3.168 90) (layer "B.Fab") hide
        (effects (font (size 0.7 0.7) (thickness 0.15)) (justify left bottom mirror))
    )
    (fp_text user "Author: Antmicro" (at -0.932 -4.17 90) (layer "B.Fab") hide
        (effects (font (size 0.7 0.7) (thickness 0.15)) (justify left bottom mirror))
    )
    (fp_rect (start -0.94 0.47) (end 0.94 -0.47)
      (stroke (width 0.05) (type solid)) (fill none) (layer "B.CrtYd"))
    (fp_rect (start -0.499 0.249) (end 0.499 -0.249)
      (stroke (width 0.15) (type solid)) (fill none) (layer "B.Fab"))
    (pad "1" smd roundrect (at -0.484 0 270) (size 0.59 0.64) (layers "B.Cu" "B.Paste" "B.Mask") (roundrect_rratio 0.25)
      (net 246 "Net-(U32-CT)") (pintype "passive"))
    (pad "2" smd roundrect (at 0.484 0 270) (size 0.59 0.64) (layers "B.Cu" "B.Paste" "B.Mask") (roundrect_rratio 0.25)
      (net 1 "GND") (pintype "passive"))
  )

  (footprint "kria-k26-devboard-footprints:R_0402_1005Metric" (layer "B.Cu")
    (at 94.575 146.96 -90)
    (descr "Resistor SMD 0402")
    (tags "resistor SMD 0402")
    (property "Author" "Antmicro")
    (property "Current" "1A")
    (property "DNP" "DNP")
    (property "License" "Apache-2.0")
    (property "MPN" "ERJ2GE0R00X")
    (property "Manufacturer" "Panasonic")
    (property "Sheetfile" "reset.kicad_sch")
    (property "Sheetname" "Reset logic")
    (property "Tolerance" "")
    (property "Val" "0R")
    (property "dnp" "")
    (property "exclude_from_bom" "")
    (property "ki_description" "0R resistor in 0402 package with unspecified tolerance")
    (attr exclude_from_pos_files exclude_from_bom)
    (fp_text reference "R86" (at -1.01 0.585 90) (layer "B.SilkS")
        (effects (font (size 0.7 0.7) (thickness 0.15)) (justify left bottom mirror))
    )
    (fp_text value "R_0R_0402" (at 0 -1.4 90) (layer "B.Fab") hide
        (effects (font (size 0.7 0.7) (thickness 0.15)) (justify left bottom mirror))
    )
    (fp_text user "License: Apache-2.0" (at -0.95 -5.169 90) (layer "B.Fab") hide
        (effects (font (size 0.7 0.7) (thickness 0.15)) (justify left bottom mirror))
    )
    (fp_text user "${REFERENCE}" (at -0.95 -3.168 90) (layer "B.Fab") hide
        (effects (font (size 0.7 0.7) (thickness 0.15)) (justify left bottom mirror))
    )
    (fp_text user "Author: Antmicro" (at -0.95 -4.169 90) (layer "B.Fab") hide
        (effects (font (size 0.7 0.7) (thickness 0.15)) (justify left bottom mirror))
    )
    (fp_rect (start -0.93 0.47) (end 0.93 -0.47)
      (stroke (width 0.05) (type solid)) (fill none) (layer "B.CrtYd"))
    (fp_rect (start -0.5 0.25) (end 0.5 -0.25)
      (stroke (width 0.15) (type solid)) (fill none) (layer "B.Fab"))
    (pad "1" smd roundrect (at -0.485 0 270) (size 0.59 0.64) (layers "B.Cu" "B.Paste" "B.Mask") (roundrect_rratio 0.25)
      (net 129 "/Reset logic/HDA02") (pintype "passive"))
    (pad "2" smd roundrect (at 0.485 0 270) (size 0.59 0.64) (layers "B.Cu" "B.Paste" "B.Mask") (roundrect_rratio 0.25)
      (net 198 "/Camera interface/CAM0_RST") (pintype "passive"))
  )

  (footprint "kria-k26-devboard-footprints:R_0402_1005Metric" (layer "B.Cu")
    (at 116.556942 87.4 180)
    (descr "Resistor SMD 0402")
    (tags "resistor SMD 0402")
    (property "Author" "Antmicro")
    (property "License" "Apache-2.0")
    (property "MPN" "CR0402-FX-2003GLF")
    (property "Manufacturer" "Bourns")
    (property "Sheetfile" "usb.kicad_sch")
    (property "Sheetname" "USB")
    (property "Tolerance" "1%")
    (property "Val" "200k")
    (property "ki_description" "200k resistor in 0402 package with 1% tolerance")
    (attr smd)
    (fp_text reference "R41" (at 0.926942 -0.35) (layer "B.SilkS")
        (effects (font (size 0.7 0.7) (thickness 0.15)) (justify left bottom mirror))
    )
    (fp_text value "R_200k_0402" (at 0 -1.4) (layer "B.Fab") hide
        (effects (font (size 0.7 0.7) (thickness 0.15)) (justify left bottom mirror))
    )
    (fp_text user "Author: Antmicro" (at -0.95 -4.169) (layer "B.Fab") hide
        (effects (font (size 0.7 0.7) (thickness 0.15)) (justify left bottom mirror))
    )
    (fp_text user "${REFERENCE}" (at -0.95 -3.168) (layer "B.Fab") hide
        (effects (font (size 0.7 0.7) (thickness 0.15)) (justify left bottom mirror))
    )
    (fp_text user "License: Apache-2.0" (at -0.95 -5.169) (layer "B.Fab") hide
        (effects (font (size 0.7 0.7) (thickness 0.15)) (justify left bottom mirror))
    )
    (fp_rect (start -0.93 0.47) (end 0.93 -0.47)
      (stroke (width 0.05) (type solid)) (fill none) (layer "B.CrtYd"))
    (fp_rect (start -0.5 0.25) (end 0.5 -0.25)
      (stroke (width 0.15) (type solid)) (fill none) (layer "B.Fab"))
    (pad "1" smd roundrect (at -0.485 0 180) (size 0.59 0.64) (layers "B.Cu" "B.Paste" "B.Mask") (roundrect_rratio 0.25)
      (net 1 "GND") (pintype "passive"))
    (pad "2" smd roundrect (at 0.485 0 180) (size 0.59 0.64) (layers "B.Cu" "B.Paste" "B.Mask") (roundrect_rratio 0.25)
      (net 644 "Net-(U17-SPI_CE_N{slash}CFG_NON_REM{slash}PF20)") (pintype "passive"))
  )

  (footprint "kria-k26-devboard-footprints:C_0402_1005Metric" (layer "B.Cu")
    (at 139.370389 113.357609)
    (descr "Capacitor SMD 0402")
    (tags "capacitor SMD 0402")
    (property "Author" "Antmicro")
    (property "Dielectric" "X5R")
    (property "License" "Apache-2.0")
    (property "MPN" "GRM155R61H104KE14D")
    (property "Manufacturer" "Murata")
    (property "Sheetfile" "debug.kicad_sch")
    (property "Sheetname" "Debug and JTAG")
    (property "Val" "100n")
    (property "Voltage" "50V")
    (property "ki_description" " ")
    (attr smd)
    (fp_text reference "C157" (at 3.799611 0.412391 180) (layer "B.SilkS")
        (effects (font (size 0.7 0.7) (thickness 0.15)) (justify left bottom mirror))
    )
    (fp_text value "C_100n_0402" (at 0 -1.4 180) (layer "B.Fab") hide
        (effects (font (size 0.7 0.7) (thickness 0.15)) (justify left bottom mirror))
    )
    (fp_text user "${REFERENCE}" (at -0.932 -3.168 180) (layer "B.Fab") hide
        (effects (font (size 0.7 0.7) (thickness 0.15)) (justify left bottom mirror))
    )
    (fp_text user "License: Apache-2.0" (at -0.932 -5.17 180) (layer "B.Fab") hide
        (effects (font (size 0.7 0.7) (thickness 0.15)) (justify left bottom mirror))
    )
    (fp_text user "Author: Antmicro" (at -0.932 -4.17 180) (layer "B.Fab") hide
        (effects (font (size 0.7 0.7) (thickness 0.15)) (justify left bottom mirror))
    )
    (fp_rect (start -0.94 0.47) (end 0.94 -0.47)
      (stroke (width 0.05) (type solid)) (fill none) (layer "B.CrtYd"))
    (fp_rect (start -0.499 0.249) (end 0.499 -0.249)
      (stroke (width 0.15) (type solid)) (fill none) (layer "B.Fab"))
    (pad "1" smd roundrect (at -0.484 0) (size 0.59 0.64) (layers "B.Cu" "B.Paste" "B.Mask") (roundrect_rratio 0.25)
      (net 138 "/Debug and JTAG/USB_3V3") (pintype "passive"))
    (pad "2" smd roundrect (at 0.484 0) (size 0.59 0.64) (layers "B.Cu" "B.Paste" "B.Mask") (roundrect_rratio 0.25)
      (net 1 "GND") (pintype "passive"))
  )

  (footprint "kria-k26-devboard-footprints:C_0402_1005Metric" (layer "B.Cu")
    (at 143.84 125.45 180)
    (descr "Capacitor SMD 0402")
    (tags "capacitor SMD 0402")
    (property "Author" "Antmicro")
    (property "Dielectric" "X5R")
    (property "License" "Apache-2.0")
    (property "MPN" "GRM155R61H104KE14D")
    (property "Manufacturer" "Murata")
    (property "Sheetfile" "debug.kicad_sch")
    (property "Sheetname" "Debug and JTAG")
    (property "Val" "100n")
    (property "Voltage" "50V")
    (property "ki_description" " ")
    (attr smd)
    (fp_text reference "C164" (at -3.745313 -0.316087) (layer "B.SilkS")
        (effects (font (size 0.7 0.7) (thickness 0.15)) (justify left bottom mirror))
    )
    (fp_text value "C_100n_0402" (at 0 -1.4) (layer "B.Fab") hide
        (effects (font (size 0.7 0.7) (thickness 0.15)) (justify left bottom mirror))
    )
    (fp_text user "License: Apache-2.0" (at -0.932 -5.17) (layer "B.Fab") hide
        (effects (font (size 0.7 0.7) (thickness 0.15)) (justify left bottom mirror))
    )
    (fp_text user "Author: Antmicro" (at -0.932 -4.17) (layer "B.Fab") hide
        (effects (font (size 0.7 0.7) (thickness 0.15)) (justify left bottom mirror))
    )
    (fp_text user "${REFERENCE}" (at -0.932 -3.168) (layer "B.Fab") hide
        (effects (font (size 0.7 0.7) (thickness 0.15)) (justify left bottom mirror))
    )
    (fp_rect (start -0.94 0.47) (end 0.94 -0.47)
      (stroke (width 0.05) (type solid)) (fill none) (layer "B.CrtYd"))
    (fp_rect (start -0.499 0.249) (end 0.499 -0.249)
      (stroke (width 0.15) (type solid)) (fill none) (layer "B.Fab"))
    (pad "1" smd roundrect (at -0.484 0 180) (size 0.59 0.64) (layers "B.Cu" "B.Paste" "B.Mask") (roundrect_rratio 0.25)
      (net 138 "/Debug and JTAG/USB_3V3") (pintype "passive"))
    (pad "2" smd roundrect (at 0.484 0 180) (size 0.59 0.64) (layers "B.Cu" "B.Paste" "B.Mask") (roundrect_rratio 0.25)
      (net 1 "GND") (pintype "passive"))
  )

  (footprint "kria-k26-devboard-footprints:C_0402_1005Metric" (layer "B.Cu")
    (at 140.671787 126.524767 180)
    (descr "Capacitor SMD 0402")
    (tags "capacitor SMD 0402")
    (property "Author" "Antmicro")
    (property "Dielectric" "X5R")
    (property "License" "Apache-2.0")
    (property "MPN" "GRM155R61H104KE14D")
    (property "Manufacturer" "Murata")
    (property "Sheetfile" "debug.kicad_sch")
    (property "Sheetname" "Debug and JTAG")
    (property "Val" "100n")
    (property "Voltage" "50V")
    (property "ki_description" " ")
    (attr smd)
    (fp_text reference "C165" (at 0.895609 -0.343402) (layer "B.SilkS")
        (effects (font (size 0.7 0.7) (thickness 0.15)) (justify left bottom mirror))
    )
    (fp_text value "C_100n_0402" (at 0 -1.4) (layer "B.Fab") hide
        (effects (font (size 0.7 0.7) (thickness 0.15)) (justify left bottom mirror))
    )
    (fp_text user "License: Apache-2.0" (at -0.932 -5.17) (layer "B.Fab") hide
        (effects (font (size 0.7 0.7) (thickness 0.15)) (justify left bottom mirror))
    )
    (fp_text user "Author: Antmicro" (at -0.932 -4.17) (layer "B.Fab") hide
        (effects (font (size 0.7 0.7) (thickness 0.15)) (justify left bottom mirror))
    )
    (fp_text user "${REFERENCE}" (at -0.932 -3.168) (layer "B.Fab") hide
        (effects (font (size 0.7 0.7) (thickness 0.15)) (justify left bottom mirror))
    )
    (fp_rect (start -0.94 0.47) (end 0.94 -0.47)
      (stroke (width 0.05) (type solid)) (fill none) (layer "B.CrtYd"))
    (fp_rect (start -0.499 0.249) (end 0.499 -0.249)
      (stroke (width 0.15) (type solid)) (fill none) (layer "B.Fab"))
    (pad "1" smd roundrect (at -0.484 0 180) (size 0.59 0.64) (layers "B.Cu" "B.Paste" "B.Mask") (roundrect_rratio 0.25)
      (net 138 "/Debug and JTAG/USB_3V3") (pintype "passive"))
    (pad "2" smd roundrect (at 0.484 0 180) (size 0.59 0.64) (layers "B.Cu" "B.Paste" "B.Mask") (roundrect_rratio 0.25)
      (net 1 "GND") (pintype "passive"))
  )

  (footprint "kria-k26-devboard-footprints:C_0402_1005Metric" (layer "B.Cu")
    (at 140.665609 125.576598 180)
    (descr "Capacitor SMD 0402")
    (tags "capacitor SMD 0402")
    (property "Author" "Antmicro")
    (property "Dielectric" "X5R")
    (property "License" "Apache-2.0")
    (property "MPN" "GRM155R61H104KE14D")
    (property "Manufacturer" "Murata")
    (property "Sheetfile" "debug.kicad_sch")
    (property "Sheetname" "Debug and JTAG")
    (property "Val" "100n")
    (property "Voltage" "50V")
    (property "ki_description" " ")
    (attr smd)
    (fp_text reference "C167" (at 0.895609 -0.343402) (layer "B.SilkS")
        (effects (font (size 0.7 0.7) (thickness 0.15)) (justify left bottom mirror))
    )
    (fp_text value "C_100n_0402" (at 0 -1.4) (layer "B.Fab") hide
        (effects (font (size 0.7 0.7) (thickness 0.15)) (justify left bottom mirror))
    )
    (fp_text user "License: Apache-2.0" (at -0.932 -5.17) (layer "B.Fab") hide
        (effects (font (size 0.7 0.7) (thickness 0.15)) (justify left bottom mirror))
    )
    (fp_text user "${REFERENCE}" (at -0.932 -3.168) (layer "B.Fab") hide
        (effects (font (size 0.7 0.7) (thickness 0.15)) (justify left bottom mirror))
    )
    (fp_text user "Author: Antmicro" (at -0.932 -4.17) (layer "B.Fab") hide
        (effects (font (size 0.7 0.7) (thickness 0.15)) (justify left bottom mirror))
    )
    (fp_rect (start -0.94 0.47) (end 0.94 -0.47)
      (stroke (width 0.05) (type solid)) (fill none) (layer "B.CrtYd"))
    (fp_rect (start -0.499 0.249) (end 0.499 -0.249)
      (stroke (width 0.15) (type solid)) (fill none) (layer "B.Fab"))
    (pad "1" smd roundrect (at -0.484 0 180) (size 0.59 0.64) (layers "B.Cu" "B.Paste" "B.Mask") (roundrect_rratio 0.25)
      (net 138 "/Debug and JTAG/USB_3V3") (pintype "passive"))
    (pad "2" smd roundrect (at 0.484 0 180) (size 0.59 0.64) (layers "B.Cu" "B.Paste" "B.Mask") (roundrect_rratio 0.25)
      (net 1 "GND") (pintype "passive"))
  )

  (footprint "kria-k26-devboard-footprints:C_0402_1005Metric" (layer "B.Cu")
    (at 143.844687 126.403913 180)
    (descr "Capacitor SMD 0402")
    (tags "capacitor SMD 0402")
    (property "Author" "Antmicro")
    (property "Dielectric" "X5R")
    (property "License" "Apache-2.0")
    (property "MPN" "GRM155R61H104KE14D")
    (property "Manufacturer" "Murata")
    (property "Sheetfile" "debug.kicad_sch")
    (property "Sheetname" "Debug and JTAG")
    (property "Val" "100n")
    (property "Voltage" "50V")
    (property "ki_description" " ")
    (attr smd)
    (fp_text reference "C166" (at -3.745313 -0.316087) (layer "B.SilkS")
        (effects (font (size 0.7 0.7) (thickness 0.15)) (justify left bottom mirror))
    )
    (fp_text value "C_100n_0402" (at 0 -1.4) (layer "B.Fab") hide
        (effects (font (size 0.7 0.7) (thickness 0.15)) (justify left bottom mirror))
    )
    (fp_text user "Author: Antmicro" (at -0.932 -4.17) (layer "B.Fab") hide
        (effects (font (size 0.7 0.7) (thickness 0.15)) (justify left bottom mirror))
    )
    (fp_text user "License: Apache-2.0" (at -0.932 -5.17) (layer "B.Fab") hide
        (effects (font (size 0.7 0.7) (thickness 0.15)) (justify left bottom mirror))
    )
    (fp_text user "${REFERENCE}" (at -0.932 -3.168) (layer "B.Fab") hide
        (effects (font (size 0.7 0.7) (thickness 0.15)) (justify left bottom mirror))
    )
    (fp_rect (start -0.94 0.47) (end 0.94 -0.47)
      (stroke (width 0.05) (type solid)) (fill none) (layer "B.CrtYd"))
    (fp_rect (start -0.499 0.249) (end 0.499 -0.249)
      (stroke (width 0.15) (type solid)) (fill none) (layer "B.Fab"))
    (pad "1" smd roundrect (at -0.484 0 180) (size 0.59 0.64) (layers "B.Cu" "B.Paste" "B.Mask") (roundrect_rratio 0.25)
      (net 17 "PS_1V8") (pintype "passive"))
    (pad "2" smd roundrect (at 0.484 0 180) (size 0.59 0.64) (layers "B.Cu" "B.Paste" "B.Mask") (roundrect_rratio 0.25)
      (net 1 "GND") (pintype "passive"))
  )

  (footprint "kria-k26-devboard-footprints:C_0402_1005Metric" (layer "B.Cu")
    (at 140.471787 130.406137 90)
    (descr "Capacitor SMD 0402")
    (tags "capacitor SMD 0402")
    (property "Author" "Antmicro")
    (property "Dielectric" "X5R")
    (property "License" "Apache-2.0")
    (property "MPN" "GRM155R61H104KE14D")
    (property "Manufacturer" "Murata")
    (property "Sheetfile" "debug.kicad_sch")
    (property "Sheetname" "Debug and JTAG")
    (property "Val" "100n")
    (property "Voltage" "50V")
    (property "ki_description" " ")
    (attr smd)
    (fp_text reference "C170" (at 1.206137 1.398213 270) (layer "B.SilkS")
        (effects (font (size 0.7 0.7) (thickness 0.15)) (justify left bottom mirror))
    )
    (fp_text value "C_100n_0402" (at 0 -1.4 270) (layer "B.Fab") hide
        (effects (font (size 0.7 0.7) (thickness 0.15)) (justify left bottom mirror))
    )
    (fp_text user "${REFERENCE}" (at -0.932 -3.168 270) (layer "B.Fab") hide
        (effects (font (size 0.7 0.7) (thickness 0.15)) (justify left bottom mirror))
    )
    (fp_text user "License: Apache-2.0" (at -0.932 -5.17 270) (layer "B.Fab") hide
        (effects (font (size 0.7 0.7) (thickness 0.15)) (justify left bottom mirror))
    )
    (fp_text user "Author: Antmicro" (at -0.932 -4.17 270) (layer "B.Fab") hide
        (effects (font (size 0.7 0.7) (thickness 0.15)) (justify left bottom mirror))
    )
    (fp_rect (start -0.94 0.47) (end 0.94 -0.47)
      (stroke (width 0.05) (type solid)) (fill none) (layer "B.CrtYd"))
    (fp_rect (start -0.499 0.249) (end 0.499 -0.249)
      (stroke (width 0.15) (type solid)) (fill none) (layer "B.Fab"))
    (pad "1" smd roundrect (at -0.484 0 90) (size 0.59 0.64) (layers "B.Cu" "B.Paste" "B.Mask") (roundrect_rratio 0.25)
      (net 138 "/Debug and JTAG/USB_3V3") (pintype "passive"))
    (pad "2" smd roundrect (at 0.484 0 90) (size 0.59 0.64) (layers "B.Cu" "B.Paste" "B.Mask") (roundrect_rratio 0.25)
      (net 1 "GND") (pintype "passive"))
  )

  (footprint "kria-k26-devboard-footprints:R_0402_1005Metric" (layer "B.Cu")
    (at 118.85 92.7 -90)
    (descr "Resistor SMD 0402")
    (tags "resistor SMD 0402")
    (property "Author" "Antmicro")
    (property "License" "Apache-2.0")
    (property "MPN" "CR0402-FX-4992GLF")
    (property "Manufacturer" "Bourns")
    (property "Sheetfile" "usb.kicad_sch")
    (property "Sheetname" "USB")
    (property "Tolerance" "1%")
    (property "Val" "49k9")
    (property "ki_description" "49k9 resistor in 0402 package with 1% tolerance")
    (attr smd)
    (fp_text reference "R39" (at 0.83 -0.41 90) (layer "B.SilkS")
        (effects (font (size 0.7 0.7) (thickness 0.15)) (justify left bottom mirror))
    )
    (fp_text value "R_49k9_0402" (at 0 -1.4 90) (layer "B.Fab") hide
        (effects (font (size 0.7 0.7) (thickness 0.15)) (justify left bottom mirror))
    )
    (fp_text user "License: Apache-2.0" (at -0.95 -5.169 90) (layer "B.Fab") hide
        (effects (font (size 0.7 0.7) (thickness 0.15)) (justify left bottom mirror))
    )
    (fp_text user "${REFERENCE}" (at -0.95 -3.168 90) (layer "B.Fab") hide
        (effects (font (size 0.7 0.7) (thickness 0.15)) (justify left bottom mirror))
    )
    (fp_text user "Author: Antmicro" (at -0.95 -4.169 90) (layer "B.Fab") hide
        (effects (font (size 0.7 0.7) (thickness 0.15)) (justify left bottom mirror))
    )
    (fp_rect (start -0.93 0.47) (end 0.93 -0.47)
      (stroke (width 0.05) (type solid)) (fill none) (layer "B.CrtYd"))
    (fp_rect (start -0.5 0.25) (end 0.5 -0.25)
      (stroke (width 0.15) (type solid)) (fill none) (layer "B.Fab"))
    (pad "1" smd roundrect (at -0.485 0 270) (size 0.59 0.64) (layers "B.Cu" "B.Paste" "B.Mask") (roundrect_rratio 0.25)
      (net 275 "/USB/VBUS") (pintype "passive"))
    (pad "2" smd roundrect (at 0.485 0 270) (size 0.59 0.64) (layers "B.Cu" "B.Paste" "B.Mask") (roundrect_rratio 0.25)
      (net 1 "GND") (pintype "passive"))
  )

  (footprint "kria-k26-devboard-footprints:R_0402_1005Metric" (layer "B.Cu")
    (at 85.3 123.8 180)
    (descr "Resistor SMD 0402")
    (tags "resistor SMD 0402")
    (property "Author" "Antmicro")
    (property "License" "Apache-2.0")
    (property "MPN" "CR0402-FX-2201GLF")
    (property "Manufacturer" "Bourns")
    (property "Sheetfile" "camera.kicad_sch")
    (property "Sheetname" "Camera interface")
    (property "Tolerance" "1%")
    (property "Val" "2k2")
    (property "ki_description" "2k2 resistor in 0402 package with 1% tolerance")
    (attr smd)
    (fp_text reference "R24" (at -3.05 -0.4) (layer "B.SilkS")
        (effects (font (size 0.7 0.7) (thickness 0.15)) (justify left bottom mirror))
    )
    (fp_text value "R_2k2_0402" (at 0 -1.4) (layer "B.Fab") hide
        (effects (font (size 0.7 0.7) (thickness 0.15)) (justify left bottom mirror))
    )
    (fp_text user "${REFERENCE}" (at -0.95 -3.168) (layer "B.Fab") hide
        (effects (font (size 0.7 0.7) (thickness 0.15)) (justify left bottom mirror))
    )
    (fp_text user "License: Apache-2.0" (at -0.95 -5.169) (layer "B.Fab") hide
        (effects (font (size 0.7 0.7) (thickness 0.15)) (justify left bottom mirror))
    )
    (fp_text user "Author: Antmicro" (at -0.95 -4.169) (layer "B.Fab") hide
        (effects (font (size 0.7 0.7) (thickness 0.15)) (justify left bottom mirror))
    )
    (fp_rect (start -0.93 0.47) (end 0.93 -0.47)
      (stroke (width 0.05) (type solid)) (fill none) (layer "B.CrtYd"))
    (fp_rect (start -0.5 0.25) (end 0.5 -0.25)
      (stroke (width 0.15) (type solid)) (fill none) (layer "B.Fab"))
    (pad "1" smd roundrect (at -0.485 0 180) (size 0.59 0.64) (layers "B.Cu" "B.Paste" "B.Mask") (roundrect_rratio 0.25)
      (net 20 "PL_3V3") (pintype "passive"))
    (pad "2" smd roundrect (at 0.485 0 180) (size 0.59 0.64) (layers "B.Cu" "B.Paste" "B.Mask") (roundrect_rratio 0.25)
      (net 410 "/Camera interface/HDA00_CC") (pintype "passive"))
  )

  (footprint "kria-k26-devboard-footprints:C_0402_1005Metric" (layer "B.Cu")
    (at 144.88 117.8)
    (descr "Capacitor SMD 0402")
    (tags "capacitor SMD 0402")
    (property "Author" "Antmicro")
    (property "Dielectric" "X5R")
    (property "License" "Apache-2.0")
    (property "MPN" "GRM155R61H104KE14D")
    (property "Manufacturer" "Murata")
    (property "Sheetfile" "debug.kicad_sch")
    (property "Sheetname" "Debug and JTAG")
    (property "Val" "100n")
    (property "Voltage" "50V")
    (property "ki_description" " ")
    (attr smd)
    (fp_text reference "C141" (at -0.88 0.38 180) (layer "B.SilkS")
        (effects (font (size 0.7 0.7) (thickness 0.15)) (justify left bottom mirror))
    )
    (fp_text value "C_100n_0402" (at 0 -1.4 180) (layer "B.Fab") hide
        (effects (font (size 0.7 0.7) (thickness 0.15)) (justify left bottom mirror))
    )
    (fp_text user "Author: Antmicro" (at -0.932 -4.17 180) (layer "B.Fab") hide
        (effects (font (size 0.7 0.7) (thickness 0.15)) (justify left bottom mirror))
    )
    (fp_text user "License: Apache-2.0" (at -0.932 -5.17 180) (layer "B.Fab") hide
        (effects (font (size 0.7 0.7) (thickness 0.15)) (justify left bottom mirror))
    )
    (fp_text user "${REFERENCE}" (at -0.932 -3.168 180) (layer "B.Fab") hide
        (effects (font (size 0.7 0.7) (thickness 0.15)) (justify left bottom mirror))
    )
    (fp_rect (start -0.94 0.47) (end 0.94 -0.47)
      (stroke (width 0.05) (type solid)) (fill none) (layer "B.CrtYd"))
    (fp_rect (start -0.499 0.249) (end 0.499 -0.249)
      (stroke (width 0.15) (type solid)) (fill none) (layer "B.Fab"))
    (pad "1" smd roundrect (at -0.484 0) (size 0.59 0.64) (layers "B.Cu" "B.Paste" "B.Mask") (roundrect_rratio 0.25)
      (net 132 "/Debug and JTAG/USB_1V2") (pintype "passive"))
    (pad "2" smd roundrect (at 0.484 0) (size 0.59 0.64) (layers "B.Cu" "B.Paste" "B.Mask") (roundrect_rratio 0.25)
      (net 1 "GND") (pintype "passive"))
  )

  (footprint "kria-k26-devboard-footprints:C_0402_1005Metric" (layer "B.Cu")
    (at 150.5 121.6 90)
    (descr "Capacitor SMD 0402")
    (tags "capacitor SMD 0402")
    (property "Author" "Antmicro")
    (property "Dielectric" "X5R")
    (property "License" "Apache-2.0")
    (property "MPN" "GRM155R61H104KE14D")
    (property "Manufacturer" "Murata")
    (property "Sheetfile" "debug.kicad_sch")
    (property "Sheetname" "Debug and JTAG")
    (property "Val" "100n")
    (property "Voltage" "50V")
    (property "ki_description" " ")
    (attr smd)
    (fp_text reference "C151" (at 1.26 4.35 270) (layer "B.SilkS")
        (effects (font (size 0.7 0.7) (thickness 0.15)) (justify left bottom mirror))
    )
    (fp_text value "C_100n_0402" (at 0 -1.4 270) (layer "B.Fab") hide
        (effects (font (size 0.7 0.7) (thickness 0.15)) (justify left bottom mirror))
    )
    (fp_text user "Author: Antmicro" (at -0.932 -4.17 270) (layer "B.Fab") hide
        (effects (font (size 0.7 0.7) (thickness 0.15)) (justify left bottom mirror))
    )
    (fp_text user "${REFERENCE}" (at -0.932 -3.168 270) (layer "B.Fab") hide
        (effects (font (size 0.7 0.7) (thickness 0.15)) (justify left bottom mirror))
    )
    (fp_text user "License: Apache-2.0" (at -0.932 -5.17 270) (layer "B.Fab") hide
        (effects (font (size 0.7 0.7) (thickness 0.15)) (justify left bottom mirror))
    )
    (fp_rect (start -0.94 0.47) (end 0.94 -0.47)
      (stroke (width 0.05) (type solid)) (fill none) (layer "B.CrtYd"))
    (fp_rect (start -0.499 0.249) (end 0.499 -0.249)
      (stroke (width 0.15) (type solid)) (fill none) (layer "B.Fab"))
    (pad "1" smd roundrect (at -0.484 0 90) (size 0.59 0.64) (layers "B.Cu" "B.Paste" "B.Mask") (roundrect_rratio 0.25)
      (net 132 "/Debug and JTAG/USB_1V2") (pintype "passive"))
    (pad "2" smd roundrect (at 0.484 0 90) (size 0.59 0.64) (layers "B.Cu" "B.Paste" "B.Mask") (roundrect_rratio 0.25)
      (net 1 "GND") (pintype "passive"))
  )

  (footprint "kria-k26-devboard-footprints:C_0402_1005Metric" (layer "B.Cu")
    (at 139.02 122.09 90)
    (descr "Capacitor SMD 0402")
    (tags "capacitor SMD 0402")
    (property "Author" "Antmicro")
    (property "Dielectric" "X5R")
    (property "License" "Apache-2.0")
    (property "MPN" "GRM155R61H104KE14D")
    (property "Manufacturer" "Murata")
    (property "Sheetfile" "debug.kicad_sch")
    (property "Sheetname" "Debug and JTAG")
    (property "Val" "100n")
    (property "Voltage" "50V")
    (property "ki_description" " ")
    (attr smd)
    (fp_text reference "C168" (at 1.24 2.245 270) (layer "B.SilkS")
        (effects (font (size 0.7 0.7) (thickness 0.15)) (justify left bottom mirror))
    )
    (fp_text value "C_100n_0402" (at 0 -1.4 270) (layer "B.Fab") hide
        (effects (font (size 0.7 0.7) (thickness 0.15)) (justify left bottom mirror))
    )
    (fp_text user "License: Apache-2.0" (at -0.932 -5.17 270) (layer "B.Fab") hide
        (effects (font (size 0.7 0.7) (thickness 0.15)) (justify left bottom mirror))
    )
    (fp_text user "Author: Antmicro" (at -0.932 -4.17 270) (layer "B.Fab") hide
        (effects (font (size 0.7 0.7) (thickness 0.15)) (justify left bottom mirror))
    )
    (fp_text user "${REFERENCE}" (at -0.932 -3.168 270) (layer "B.Fab") hide
        (effects (font (size 0.7 0.7) (thickness 0.15)) (justify left bottom mirror))
    )
    (fp_rect (start -0.94 0.47) (end 0.94 -0.47)
      (stroke (width 0.05) (type solid)) (fill none) (layer "B.CrtYd"))
    (fp_rect (start -0.499 0.249) (end 0.499 -0.249)
      (stroke (width 0.15) (type solid)) (fill none) (layer "B.Fab"))
    (pad "1" smd roundrect (at -0.484 0 90) (size 0.59 0.64) (layers "B.Cu" "B.Paste" "B.Mask") (roundrect_rratio 0.25)
      (net 17 "PS_1V8") (pintype "passive"))
    (pad "2" smd roundrect (at 0.484 0 90) (size 0.59 0.64) (layers "B.Cu" "B.Paste" "B.Mask") (roundrect_rratio 0.25)
      (net 1 "GND") (pintype "passive"))
  )

  (footprint "kria-k26-devboard-footprints:C_0402_1005Metric" (layer "B.Cu")
    (at 138.77 117.85 90)
    (descr "Capacitor SMD 0402")
    (tags "capacitor SMD 0402")
    (property "Author" "Antmicro")
    (property "Dielectric" "X5R")
    (property "License" "Apache-2.0")
    (property "MPN" "GRM155R61H104KE14D")
    (property "Manufacturer" "Murata")
    (property "Sheetfile" "debug.kicad_sch")
    (property "Sheetname" "Debug and JTAG")
    (property "Val" "100n")
    (property "Voltage" "50V")
    (property "ki_description" " ")
    (attr smd)
    (fp_text reference "C169" (at 1.47 -1.505 270) (layer "B.SilkS")
        (effects (font (size 0.7 0.7) (thickness 0.15)) (justify left bottom mirror))
    )
    (fp_text value "C_100n_0402" (at 0 -1.4 270) (layer "B.Fab") hide
        (effects (font (size 0.7 0.7) (thickness 0.15)) (justify left bottom mirror))
    )
    (fp_text user "${REFERENCE}" (at -0.932 -3.168 270) (layer "B.Fab") hide
        (effects (font (size 0.7 0.7) (thickness 0.15)) (justify left bottom mirror))
    )
    (fp_text user "Author: Antmicro" (at -0.932 -4.17 270) (layer "B.Fab") hide
        (effects (font (size 0.7 0.7) (thickness 0.15)) (justify left bottom mirror))
    )
    (fp_text user "License: Apache-2.0" (at -0.932 -5.17 270) (layer "B.Fab") hide
        (effects (font (size 0.7 0.7) (thickness 0.15)) (justify left bottom mirror))
    )
    (fp_rect (start -0.94 0.47) (end 0.94 -0.47)
      (stroke (width 0.05) (type solid)) (fill none) (layer "B.CrtYd"))
    (fp_rect (start -0.499 0.249) (end 0.499 -0.249)
      (stroke (width 0.15) (type solid)) (fill none) (layer "B.Fab"))
    (pad "1" smd roundrect (at -0.484 0 90) (size 0.59 0.64) (layers "B.Cu" "B.Paste" "B.Mask") (roundrect_rratio 0.25)
      (net 17 "PS_1V8") (pintype "passive"))
    (pad "2" smd roundrect (at 0.484 0 90) (size 0.59 0.64) (layers "B.Cu" "B.Paste" "B.Mask") (roundrect_rratio 0.25)
      (net 1 "GND") (pintype "passive"))
  )

  (footprint "kria-k26-devboard-footprints:C_0402_1005Metric" (layer "B.Cu")
    (at 139.73 117.85 90)
    (descr "Capacitor SMD 0402")
    (tags "capacitor SMD 0402")
    (property "Author" "Antmicro")
    (property "Dielectric" "X5R")
    (property "License" "Apache-2.0")
    (property "MPN" "GRM155R61H104KE14D")
    (property "Manufacturer" "Murata")
    (property "Sheetfile" "debug.kicad_sch")
    (property "Sheetname" "Debug and JTAG")
    (property "Val" "100n")
    (property "Voltage" "50V")
    (property "ki_description" " ")
    (attr smd)
    (fp_text reference "C163" (at 1.47 -1.505 270) (layer "B.SilkS")
        (effects (font (size 0.7 0.7) (thickness 0.15)) (justify left bottom mirror))
    )
    (fp_text value "C_100n_0402" (at 0 -1.4 270) (layer "B.Fab") hide
        (effects (font (size 0.7 0.7) (thickness 0.15)) (justify left bottom mirror))
    )
    (fp_text user "Author: Antmicro" (at -0.932 -4.17 270) (layer "B.Fab") hide
        (effects (font (size 0.7 0.7) (thickness 0.15)) (justify left bottom mirror))
    )
    (fp_text user "${REFERENCE}" (at -0.932 -3.168 270) (layer "B.Fab") hide
        (effects (font (size 0.7 0.7) (thickness 0.15)) (justify left bottom mirror))
    )
    (fp_text user "License: Apache-2.0" (at -0.932 -5.17 270) (layer "B.Fab") hide
        (effects (font (size 0.7 0.7) (thickness 0.15)) (justify left bottom mirror))
    )
    (fp_rect (start -0.94 0.47) (end 0.94 -0.47)
      (stroke (width 0.05) (type solid)) (fill none) (layer "B.CrtYd"))
    (fp_rect (start -0.499 0.249) (end 0.499 -0.249)
      (stroke (width 0.15) (type solid)) (fill none) (layer "B.Fab"))
    (pad "1" smd roundrect (at -0.484 0 90) (size 0.59 0.64) (layers "B.Cu" "B.Paste" "B.Mask") (roundrect_rratio 0.25)
      (net 138 "/Debug and JTAG/USB_3V3") (pintype "passive"))
    (pad "2" smd roundrect (at 0.484 0 90) (size 0.59 0.64) (layers "B.Cu" "B.Paste" "B.Mask") (roundrect_rratio 0.25)
      (net 1 "GND") (pintype "passive"))
  )

  (footprint "kria-k26-devboard-footprints:C_0402_1005Metric" (layer "B.Cu")
    (at 151.58 119.86 180)
    (descr "Capacitor SMD 0402")
    (tags "capacitor SMD 0402")
    (property "Author" "Antmicro")
    (property "Dielectric" "X5R")
    (property "License" "Apache-2.0")
    (property "MPN" "GRM155R61H104KE14D")
    (property "Manufacturer" "Murata")
    (property "Sheetfile" "debug.kicad_sch")
    (property "Sheetname" "Debug and JTAG")
    (property "Val" "100n")
    (property "Voltage" "50V")
    (property "ki_description" " ")
    (attr smd)
    (fp_text reference "C144" (at -3.69 -0.38) (layer "B.SilkS")
        (effects (font (size 0.7 0.7) (thickness 0.15)) (justify left bottom mirror))
    )
    (fp_text value "C_100n_0402" (at 0 -1.4) (layer "B.Fab") hide
        (effects (font (size 0.7 0.7) (thickness 0.15)) (justify left bottom mirror))
    )
    (fp_text user "License: Apache-2.0" (at -0.932 -5.17) (layer "B.Fab") hide
        (effects (font (size 0.7 0.7) (thickness 0.15)) (justify left bottom mirror))
    )
    (fp_text user "Author: Antmicro" (at -0.932 -4.17) (layer "B.Fab") hide
        (effects (font (size 0.7 0.7) (thickness 0.15)) (justify left bottom mirror))
    )
    (fp_text user "${REFERENCE}" (at -0.932 -3.168) (layer "B.Fab") hide
        (effects (font (size 0.7 0.7) (thickness 0.15)) (justify left bottom mirror))
    )
    (fp_rect (start -0.94 0.47) (end 0.94 -0.47)
      (stroke (width 0.05) (type solid)) (fill none) (layer "B.CrtYd"))
    (fp_rect (start -0.499 0.249) (end 0.499 -0.249)
      (stroke (width 0.15) (type solid)) (fill none) (layer "B.Fab"))
    (pad "1" smd roundrect (at -0.484 0 180) (size 0.59 0.64) (layers "B.Cu" "B.Paste" "B.Mask") (roundrect_rratio 0.25)
      (net 138 "/Debug and JTAG/USB_3V3") (pintype "passive"))
    (pad "2" smd roundrect (at 0.484 0 180) (size 0.59 0.64) (layers "B.Cu" "B.Paste" "B.Mask") (roundrect_rratio 0.25)
      (net 1 "GND") (pintype "passive"))
  )

  (footprint "kria-k26-devboard-footprints:C_0402_1005Metric" (layer "B.Cu")
    (at 151.58 117.86 180)
    (descr "Capacitor SMD 0402")
    (tags "capacitor SMD 0402")
    (property "Author" "Antmicro")
    (property "Dielectric" "X5R")
    (property "License" "Apache-2.0")
    (property "MPN" "GRM155R61H104KE14D")
    (property "Manufacturer" "Murata")
    (property "Sheetfile" "debug.kicad_sch")
    (property "Sheetname" "Debug and JTAG")
    (property "Val" "100n")
    (property "Voltage" "50V")
    (property "ki_description" " ")
    (attr smd)
    (fp_text reference "C145" (at -3.7 -0.37) (layer "B.SilkS")
        (effects (font (size 0.7 0.7) (thickness 0.15)) (justify left bottom mirror))
    )
    (fp_text value "C_100n_0402" (at 0 -1.4) (layer "B.Fab") hide
        (effects (font (size 0.7 0.7) (thickness 0.15)) (justify left bottom mirror))
    )
    (fp_text user "${REFERENCE}" (at -0.932 -3.168) (layer "B.Fab") hide
        (effects (font (size 0.7 0.7) (thickness 0.15)) (justify left bottom mirror))
    )
    (fp_text user "License: Apache-2.0" (at -0.932 -5.17) (layer "B.Fab") hide
        (effects (font (size 0.7 0.7) (thickness 0.15)) (justify left bottom mirror))
    )
    (fp_text user "Author: Antmicro" (at -0.932 -4.17) (layer "B.Fab") hide
        (effects (font (size 0.7 0.7) (thickness 0.15)) (justify left bottom mirror))
    )
    (fp_rect (start -0.94 0.47) (end 0.94 -0.47)
      (stroke (width 0.05) (type solid)) (fill none) (layer "B.CrtYd"))
    (fp_rect (start -0.499 0.249) (end 0.499 -0.249)
      (stroke (width 0.15) (type solid)) (fill none) (layer "B.Fab"))
    (pad "1" smd roundrect (at -0.484 0 180) (size 0.59 0.64) (layers "B.Cu" "B.Paste" "B.Mask") (roundrect_rratio 0.25)
      (net 132 "/Debug and JTAG/USB_1V2") (pintype "passive"))
    (pad "2" smd roundrect (at 0.484 0 180) (size 0.59 0.64) (layers "B.Cu" "B.Paste" "B.Mask") (roundrect_rratio 0.25)
      (net 1 "GND") (pintype "passive"))
  )

  (footprint "kria-k26-devboard-footprints:C_0402_1005Metric" (layer "B.Cu")
    (at 147.5 121.66 90)
    (descr "Capacitor SMD 0402")
    (tags "capacitor SMD 0402")
    (property "Author" "Antmicro")
    (property "Dielectric" "X5R")
    (property "License" "Apache-2.0")
    (property "MPN" "GRM155R61H104KE14D")
    (property "Manufacturer" "Murata")
    (property "Sheetfile" "debug.kicad_sch")
    (property "Sheetname" "Debug and JTAG")
    (property "Val" "100n")
    (property "Voltage" "50V")
    (property "ki_description" " ")
    (attr smd)
    (fp_text reference "C143" (at 1.26 4.35 270) (layer "B.SilkS")
        (effects (font (size 0.7 0.7) (thickness 0.15)) (justify left bottom mirror))
    )
    (fp_text value "C_100n_0402" (at 0 -1.4 270) (layer "B.Fab") hide
        (effects (font (size 0.7 0.7) (thickness 0.15)) (justify left bottom mirror))
    )
    (fp_text user "${REFERENCE}" (at -0.932 -3.168 270) (layer "B.Fab") hide
        (effects (font (size 0.7 0.7) (thickness 0.15)) (justify left bottom mirror))
    )
    (fp_text user "License: Apache-2.0" (at -0.932 -5.17 270) (layer "B.Fab") hide
        (effects (font (size 0.7 0.7) (thickness 0.15)) (justify left bottom mirror))
    )
    (fp_text user "Author: Antmicro" (at -0.932 -4.17 270) (layer "B.Fab") hide
        (effects (font (size 0.7 0.7) (thickness 0.15)) (justify left bottom mirror))
    )
    (fp_rect (start -0.94 0.47) (end 0.94 -0.47)
      (stroke (width 0.05) (type solid)) (fill none) (layer "B.CrtYd"))
    (fp_rect (start -0.499 0.249) (end 0.499 -0.249)
      (stroke (width 0.15) (type solid)) (fill none) (layer "B.Fab"))
    (pad "1" smd roundrect (at -0.484 0 90) (size 0.59 0.64) (layers "B.Cu" "B.Paste" "B.Mask") (roundrect_rratio 0.25)
      (net 132 "/Debug and JTAG/USB_1V2") (pintype "passive"))
    (pad "2" smd roundrect (at 0.484 0 90) (size 0.59 0.64) (layers "B.Cu" "B.Paste" "B.Mask") (roundrect_rratio 0.25)
      (net 1 "GND") (pintype "passive"))
  )

  (footprint "kria-k26-devboard-footprints:C_0402_1005Metric" (layer "B.Cu")
    (at 144.88 118.8)
    (descr "Capacitor SMD 0402")
    (tags "capacitor SMD 0402")
    (property "Author" "Antmicro")
    (property "Dielectric" "X5R")
    (property "License" "Apache-2.0")
    (property "MPN" "GRM155R61H104KE14D")
    (property "Manufacturer" "Murata")
    (property "Sheetfile" "debug.kicad_sch")
    (property "Sheetname" "Debug and JTAG")
    (property "Val" "100n")
    (property "Voltage" "50V")
    (property "ki_description" " ")
    (attr smd)
    (fp_text reference "C140" (at -0.88 0.38 180) (layer "B.SilkS")
        (effects (font (size 0.7 0.7) (thickness 0.15)) (justify left bottom mirror))
    )
    (fp_text value "C_100n_0402" (at 0 -1.4 180) (layer "B.Fab") hide
        (effects (font (size 0.7 0.7) (thickness 0.15)) (justify left bottom mirror))
    )
    (fp_text user "License: Apache-2.0" (at -0.932 -5.17 180) (layer "B.Fab") hide
        (effects (font (size 0.7 0.7) (thickness 0.15)) (justify left bottom mirror))
    )
    (fp_text user "Author: Antmicro" (at -0.932 -4.17 180) (layer "B.Fab") hide
        (effects (font (size 0.7 0.7) (thickness 0.15)) (justify left bottom mirror))
    )
    (fp_text user "${REFERENCE}" (at -0.932 -3.168 180) (layer "B.Fab") hide
        (effects (font (size 0.7 0.7) (thickness 0.15)) (justify left bottom mirror))
    )
    (fp_rect (start -0.94 0.47) (end 0.94 -0.47)
      (stroke (width 0.05) (type solid)) (fill none) (layer "B.CrtYd"))
    (fp_rect (start -0.499 0.249) (end 0.499 -0.249)
      (stroke (width 0.15) (type solid)) (fill none) (layer "B.Fab"))
    (pad "1" smd roundrect (at -0.484 0) (size 0.59 0.64) (layers "B.Cu" "B.Paste" "B.Mask") (roundrect_rratio 0.25)
      (net 138 "/Debug and JTAG/USB_3V3") (pintype "passive"))
    (pad "2" smd roundrect (at 0.484 0) (size 0.59 0.64) (layers "B.Cu" "B.Paste" "B.Mask") (roundrect_rratio 0.25)
      (net 1 "GND") (pintype "passive"))
  )

  (footprint "kria-k26-devboard-footprints:C_0402_1005Metric" (layer "B.Cu")
    (at 139.98 122.09 90)
    (descr "Capacitor SMD 0402")
    (tags "capacitor SMD 0402")
    (property "Author" "Antmicro")
    (property "Dielectric" "X5R")
    (property "License" "Apache-2.0")
    (property "MPN" "GRM155R61H104KE14D")
    (property "Manufacturer" "Murata")
    (property "Sheetfile" "debug.kicad_sch")
    (property "Sheetname" "Debug and JTAG")
    (property "Val" "100n")
    (property "Voltage" "50V")
    (property "ki_description" " ")
    (attr smd)
    (fp_text reference "C162" (at 1.24 2.245 270) (layer "B.SilkS")
        (effects (font (size 0.7 0.7) (thickness 0.15)) (justify left bottom mirror))
    )
    (fp_text value "C_100n_0402" (at 0 -1.4 270) (layer "B.Fab") hide
        (effects (font (size 0.7 0.7) (thickness 0.15)) (justify left bottom mirror))
    )
    (fp_text user "License: Apache-2.0" (at -0.932 -5.17 270) (layer "B.Fab") hide
        (effects (font (size 0.7 0.7) (thickness 0.15)) (justify left bottom mirror))
    )
    (fp_text user "Author: Antmicro" (at -0.932 -4.17 270) (layer "B.Fab") hide
        (effects (font (size 0.7 0.7) (thickness 0.15)) (justify left bottom mirror))
    )
    (fp_text user "${REFERENCE}" (at -0.932 -3.168 270) (layer "B.Fab") hide
        (effects (font (size 0.7 0.7) (thickness 0.15)) (justify left bottom mirror))
    )
    (fp_rect (start -0.94 0.47) (end 0.94 -0.47)
      (stroke (width 0.05) (type solid)) (fill none) (layer "B.CrtYd"))
    (fp_rect (start -0.499 0.249) (end 0.499 -0.249)
      (stroke (width 0.15) (type solid)) (fill none) (layer "B.Fab"))
    (pad "1" smd roundrect (at -0.484 0 90) (size 0.59 0.64) (layers "B.Cu" "B.Paste" "B.Mask") (roundrect_rratio 0.25)
      (net 138 "/Debug and JTAG/USB_3V3") (pintype "passive"))
    (pad "2" smd roundrect (at 0.484 0 90) (size 0.59 0.64) (layers "B.Cu" "B.Paste" "B.Mask") (roundrect_rratio 0.25)
      (net 1 "GND") (pintype "passive"))
  )

  (footprint "kria-k26-devboard-footprints:C_0402_1005Metric" (layer "B.Cu")
    (at 151.685 113.2 180)
    (descr "Capacitor SMD 0402")
    (tags "capacitor SMD 0402")
    (property "Author" "Antmicro")
    (property "Dielectric" "")
    (property "License" "Apache-2.0")
    (property "MPN" "GRM155R61A475MEAAD")
    (property "Manufacturer" "Murata")
    (property "Sheetfile" "debug.kicad_sch")
    (property "Sheetname" "Debug and JTAG")
    (property "Val" "4u7")
    (property "Voltage" "")
    (property "ki_description" " ")
    (attr smd)
    (fp_text reference "C150" (at -3.725 -0.32) (layer "B.SilkS")
        (effects (font (size 0.7 0.7) (thickness 0.15)) (justify left bottom mirror))
    )
    (fp_text value "C_4u7_0402" (at 0 -1.4) (layer "B.Fab") hide
        (effects (font (size 0.7 0.7) (thickness 0.15)) (justify left bottom mirror))
    )
    (fp_text user "Author: Antmicro" (at -0.932 -4.17) (layer "B.Fab") hide
        (effects (font (size 0.7 0.7) (thickness 0.15)) (justify left bottom mirror))
    )
    (fp_text user "License: Apache-2.0" (at -0.932 -5.17) (layer "B.Fab") hide
        (effects (font (size 0.7 0.7) (thickness 0.15)) (justify left bottom mirror))
    )
    (fp_text user "${REFERENCE}" (at -0.932 -3.168) (layer "B.Fab") hide
        (effects (font (size 0.7 0.7) (thickness 0.15)) (justify left bottom mirror))
    )
    (fp_rect (start -0.94 0.47) (end 0.94 -0.47)
      (stroke (width 0.05) (type solid)) (fill none) (layer "B.CrtYd"))
    (fp_rect (start -0.499 0.249) (end 0.499 -0.249)
      (stroke (width 0.15) (type solid)) (fill none) (layer "B.Fab"))
    (pad "1" smd roundrect (at -0.484 0 180) (size 0.59 0.64) (layers "B.Cu" "B.Paste" "B.Mask") (roundrect_rratio 0.25)
      (net 1 "GND") (pintype "passive"))
    (pad "2" smd roundrect (at 0.484 0 180) (size 0.59 0.64) (layers "B.Cu" "B.Paste" "B.Mask") (roundrect_rratio 0.25)
      (net 138 "/Debug and JTAG/USB_3V3") (pintype "passive"))
  )

  (footprint "kria-k26-devboard-footprints:C_0402_1005Metric" (layer "B.Cu")
    (at 145.83 114.935 -90)
    (descr "Capacitor SMD 0402")
    (tags "capacitor SMD 0402")
    (property "Author" "Antmicro")
    (property "Dielectric" "X5R")
    (property "License" "Apache-2.0")
    (property "MPN" "GRM155R61H104KE14D")
    (property "Manufacturer" "Murata")
    (property "Sheetfile" "debug.kicad_sch")
    (property "Sheetname" "Debug and JTAG")
    (property "Val" "100n")
    (property "Voltage" "50V")
    (property "ki_description" " ")
    (attr smd)
    (fp_text reference "C147" (at -1.455 1.46 90) (layer "B.SilkS")
        (effects (font (size 0.7 0.7) (thickness 0.15)) (justify left bottom mirror))
    )
    (fp_text value "C_100n_0402" (at 0 -1.4 90) (layer "B.Fab") hide
        (effects (font (size 0.7 0.7) (thickness 0.15)) (justify left bottom mirror))
    )
    (fp_text user "License: Apache-2.0" (at -0.932 -5.17 90) (layer "B.Fab") hide
        (effects (font (size 0.7 0.7) (thickness 0.15)) (justify left bottom mirror))
    )
    (fp_text user "${REFERENCE}" (at -0.932 -3.168 90) (layer "B.Fab") hide
        (effects (font (size 0.7 0.7) (thickness 0.15)) (justify left bottom mirror))
    )
    (fp_text user "Author: Antmicro" (at -0.932 -4.17 90) (layer "B.Fab") hide
        (effects (font (size 0.7 0.7) (thickness 0.15)) (justify left bottom mirror))
    )
    (fp_rect (start -0.94 0.47) (end 0.94 -0.47)
      (stroke (width 0.05) (type solid)) (fill none) (layer "B.CrtYd"))
    (fp_rect (start -0.499 0.249) (end 0.499 -0.249)
      (stroke (width 0.15) (type solid)) (fill none) (layer "B.Fab"))
    (pad "1" smd roundrect (at -0.484 0 270) (size 0.59 0.64) (layers "B.Cu" "B.Paste" "B.Mask") (roundrect_rratio 0.25)
      (net 132 "/Debug and JTAG/USB_1V2") (pintype "passive"))
    (pad "2" smd roundrect (at 0.484 0 270) (size 0.59 0.64) (layers "B.Cu" "B.Paste" "B.Mask") (roundrect_rratio 0.25)
      (net 1 "GND") (pintype "passive"))
  )

  (footprint "kria-k26-devboard-footprints:C_0402_1005Metric" (layer "B.Cu")
    (at 146.78 114.935 -90)
    (descr "Capacitor SMD 0402")
    (tags "capacitor SMD 0402")
    (property "Author" "Antmicro")
    (property "Dielectric" "X5R")
    (property "License" "Apache-2.0")
    (property "MPN" "GRM155R61H104KE14D")
    (property "Manufacturer" "Murata")
    (property "Sheetfile" "debug.kicad_sch")
    (property "Sheetname" "Debug and JTAG")
    (property "Val" "100n")
    (property "Voltage" "50V")
    (property "ki_description" " ")
    (attr smd)
    (fp_text reference "C148" (at -1.455 1.46 90) (layer "B.SilkS")
        (effects (font (size 0.7 0.7) (thickness 0.15)) (justify left bottom mirror))
    )
    (fp_text value "C_100n_0402" (at 0 -1.4 90) (layer "B.Fab") hide
        (effects (font (size 0.7 0.7) (thickness 0.15)) (justify left bottom mirror))
    )
    (fp_text user "Author: Antmicro" (at -0.932 -4.17 90) (layer "B.Fab") hide
        (effects (font (size 0.7 0.7) (thickness 0.15)) (justify left bottom mirror))
    )
    (fp_text user "${REFERENCE}" (at -0.932 -3.168 90) (layer "B.Fab") hide
        (effects (font (size 0.7 0.7) (thickness 0.15)) (justify left bottom mirror))
    )
    (fp_text user "License: Apache-2.0" (at -0.932 -5.17 90) (layer "B.Fab") hide
        (effects (font (size 0.7 0.7) (thickness 0.15)) (justify left bottom mirror))
    )
    (fp_rect (start -0.94 0.47) (end 0.94 -0.47)
      (stroke (width 0.05) (type solid)) (fill none) (layer "B.CrtYd"))
    (fp_rect (start -0.499 0.249) (end 0.499 -0.249)
      (stroke (width 0.15) (type solid)) (fill none) (layer "B.Fab"))
    (pad "1" smd roundrect (at -0.484 0 270) (size 0.59 0.64) (layers "B.Cu" "B.Paste" "B.Mask") (roundrect_rratio 0.25)
      (net 133 "/Debug and JTAG/VCC_PD") (pintype "passive"))
    (pad "2" smd roundrect (at 0.484 0 270) (size 0.59 0.64) (layers "B.Cu" "B.Paste" "B.Mask") (roundrect_rratio 0.25)
      (net 1 "GND") (pintype "passive"))
  )

  (footprint "kria-k26-devboard-footprints:R_0402_1005Metric" (layer "B.Cu")
    (at 139.6 90.749999 90)
    (descr "Resistor SMD 0402")
    (tags "resistor SMD 0402")
    (property "Author" "Antmicro")
    (property "License" "Apache-2.0")
    (property "MPN" "CR0402-FX-2491GLF")
    (property "Manufacturer" "Bourns")
    (property "Sheetfile" "dc-dc-conventers.kicad_sch")
    (property "Sheetname" "DC/DC conventers")
    (property "Tolerance" "1%")
    (property "Val" "2k49")
    (property "ki_description" "2k49 resistor in 0402 package with 1% tolerance")
    (attr smd)
    (fp_text reference "R139" (at 1.379999 1.34 270) (layer "B.SilkS")
        (effects (font (size 0.7 0.7) (thickness 0.15)) (justify left bottom mirror))
    )
    (fp_text value "R_2k49_0402" (at 0 -1.4 270) (layer "B.Fab") hide
        (effects (font (size 0.7 0.7) (thickness 0.15)) (justify left bottom mirror))
    )
    (fp_text user "Author: Antmicro" (at -0.95 -4.169 270) (layer "B.Fab") hide
        (effects (font (size 0.7 0.7) (thickness 0.15)) (justify left bottom mirror))
    )
    (fp_text user "${REFERENCE}" (at -0.95 -3.168 270) (layer "B.Fab") hide
        (effects (font (size 0.7 0.7) (thickness 0.15)) (justify left bottom mirror))
    )
    (fp_text user "License: Apache-2.0" (at -0.95 -5.169 270) (layer "B.Fab") hide
        (effects (font (size 0.7 0.7) (thickness 0.15)) (justify left bottom mirror))
    )
    (fp_rect (start -0.93 0.47) (end 0.93 -0.47)
      (stroke (width 0.05) (type solid)) (fill none) (layer "B.CrtYd"))
    (fp_rect (start -0.5 0.25) (end 0.5 -0.25)
      (stroke (width 0.15) (type solid)) (fill none) (layer "B.Fab"))
    (pad "1" smd roundrect (at -0.485 0 90) (size 0.59 0.64) (layers "B.Cu" "B.Paste" "B.Mask") (roundrect_rratio 0.25)
      (net 769 "/Power Supply/DC/DC conventers/PS_1V0_OUT") (pintype "passive"))
    (pad "2" smd roundrect (at 0.485 0 90) (size 0.59 0.64) (layers "B.Cu" "B.Paste" "B.Mask") (roundrect_rratio 0.25)
      (net 692 "Net-(U53-FB)") (pintype "passive"))
  )

  (footprint "kria-k26-devboard-footprints:R_0402_1005Metric" (layer "B.Cu")
    (at 148.25 114.945 90)
    (descr "Resistor SMD 0402")
    (tags "resistor SMD 0402")
    (property "Author" "Antmicro")
    (property "License" "Apache-2.0")
    (property "MPN" "CR0402-FX-1202GLF")
    (property "Manufacturer" "Bourns")
    (property "Sheetfile" "debug.kicad_sch")
    (property "Sheetname" "Debug and JTAG")
    (property "Tolerance" "1%")
    (property "Val" "12k")
    (property "ki_description" "12k resistor in 0402 package with 1% tolerance")
    (attr smd)
    (fp_text reference "R102" (at -0.835 0.39 270) (layer "B.SilkS")
        (effects (font (size 0.7 0.7) (thickness 0.15)) (justify left bottom mirror))
    )
    (fp_text value "R_12k_0402" (at 0 -1.4 270) (layer "B.Fab") hide
        (effects (font (size 0.7 0.7) (thickness 0.15)) (justify left bottom mirror))
    )
    (fp_text user "${REFERENCE}" (at -0.95 -3.168 270) (layer "B.Fab") hide
        (effects (font (size 0.7 0.7) (thickness 0.15)) (justify left bottom mirror))
    )
    (fp_text user "License: Apache-2.0" (at -0.95 -5.169 270) (layer "B.Fab") hide
        (effects (font (size 0.7 0.7) (thickness 0.15)) (justify left bottom mirror))
    )
    (fp_text user "Author: Antmicro" (at -0.95 -4.169 270) (layer "B.Fab") hide
        (effects (font (size 0.7 0.7) (thickness 0.15)) (justify left bottom mirror))
    )
    (fp_rect (start -0.93 0.47) (end 0.93 -0.47)
      (stroke (width 0.05) (type solid)) (fill none) (layer "B.CrtYd"))
    (fp_rect (start -0.5 0.25) (end 0.5 -0.25)
      (stroke (width 0.15) (type solid)) (fill none) (layer "B.Fab"))
    (pad "1" smd roundrect (at -0.485 0 90) (size 0.59 0.64) (layers "B.Cu" "B.Paste" "B.Mask") (roundrect_rratio 0.25)
      (net 1 "GND") (pintype "passive"))
    (pad "2" smd roundrect (at 0.485 0 90) (size 0.59 0.64) (layers "B.Cu" "B.Paste" "B.Mask") (roundrect_rratio 0.25)
      (net 680 "Net-(U40-REF)") (pintype "passive"))
  )

  (footprint "kria-k26-devboard-footprints:TSOT23-6" (layer "B.Cu")
    (at 137.05 91.25 90)
    (property "Author" "Antmicro")
    (property "License" "Apache-2.0")
    (property "MPN" "AP62301WU-7")
    (property "Manufacturer" "Diodes Incorporated")
    (property "Sheetfile" "dc-dc-conventers.kicad_sch")
    (property "Sheetname" "DC/DC conventers")
    (property "ki_description" "DC-DC Switching Synchronous Buck Regulator, Adjustable, 4.2V-18Vin, 0.8V-7V/3A out, TSOT-26-6")
    (property "ki_keywords" "SMT, PMIC, IC, VOLTAGE")
    (attr smd)
    (fp_text reference "U53" (at 1.78 0.62) (layer "B.SilkS")
        (effects (font (size 0.7 0.7) (thickness 0.15)) (justify left bottom mirror))
    )
    (fp_text value "AP62301_TSOT" (at -0.005 -2.6 270) (layer "B.Fab") hide
        (effects (font (size 0.7 0.7) (thickness 0.15)) (justify left bottom mirror))
    )
    (fp_text user "Author: Antmicro" (at -1.893 -7.368 270) (layer "B.Fab") hide
        (effects (font (size 0.7 0.7) (thickness 0.15)) (justify left bottom mirror))
    )
    (fp_text user "${REFERENCE}" (at -1.893 -6.168 270) (layer "B.Fab") hide
        (effects (font (size 0.7 0.7) (thickness 0.15)) (justify left bottom mirror))
    )
    (fp_text user "License: Apache-2.0" (at -1.893 -4.967 270) (layer "B.Fab") hide
        (effects (font (size 0.7 0.7) (thickness 0.15)) (justify left bottom mirror))
    )
    (fp_line (start -1.4805 -0.725) (end -1.4795 0.725)
      (stroke (width 0.15) (type solid)) (layer "B.SilkS"))
    (fp_line (start -1.4805 -0.725) (end -1.3905 -0.725)
      (stroke (width 0.15) (type solid)) (layer "B.SilkS"))
    (fp_line (start -1.4795 0.725) (end -1.3905 0.725)
      (stroke (width 0.15) (type solid)) (layer "B.SilkS"))
    (fp_line (start 1.479 -0.73) (end 1.38 -0.73)
      (stroke (width 0.15) (type solid)) (layer "B.SilkS"))
    (fp_line (start 1.48 0.72) (end 1.38 0.72)
      (stroke (width 0.15) (type solid)) (layer "B.SilkS"))
    (fp_line (start 1.48 0.72) (end 1.479 -0.73)
      (stroke (width 0.15) (type solid)) (layer "B.SilkS"))
    (fp_circle (center -1.499 -1.236) (end -1.45 -1.236)
      (stroke (width 0.15) (type solid)) (fill solid) (layer "B.SilkS"))
    (fp_rect (start -1.65 1.61) (end 1.65 -1.61)
      (stroke (width 0.05) (type solid)) (fill none) (layer "B.CrtYd"))
    (fp_line (start -1.527 -0.491) (end -1.527 0.833)
      (stroke (width 0.15) (type solid)) (layer "B.Fab"))
    (fp_line (start -1.527 -0.491) (end -1.102 -0.916)
      (stroke (width 0.15) (type solid)) (layer "B.Fab"))
    (fp_line (start -1.527 0.833) (end 1.523 0.833)
      (stroke (width 0.15) (type solid)) (layer "B.Fab"))
    (fp_line (start -1.102 -0.916) (end 1.523 -0.916)
      (stroke (width 0.15) (type solid)) (layer "B.Fab"))
    (fp_line (start 1.523 0.833) (end 1.523 -0.916)
      (stroke (width 0.15) (type solid)) (layer "B.Fab"))
    (pad "1" smd rect (at -0.952 -1.18 90) (size 0.7 0.8) (layers "B.Cu" "B.Paste" "B.Mask")
      (net 1 "GND") (pinfunction "GND") (pintype "power_in"))
    (pad "2" smd rect (at -0.001 -1.18 90) (size 0.7 0.8) (layers "B.Cu" "B.Paste" "B.Mask")
      (net 256 "/Power Supply/DC/DC conventers/SW_PS_1V0") (pinfunction "SW") (pintype "power_out"))
    (pad "3" smd rect (at 0.947 -1.18 90) (size 0.7 0.8) (layers "B.Cu" "B.Paste" "B.Mask")
      (net 14 "/Power Supply/DC/DC conventers/DC_MAIN_BUS") (pinfunction "VIN") (pintype "power_in"))
    (pad "4" smd rect (at 0.947 1.18 90) (size 0.7 0.8) (layers "B.Cu" "B.Paste" "B.Mask")
      (net 692 "Net-(U53-FB)") (pinfunction "FB") (pintype "input"))
    (pad "5" smd rect (at -0.001 1.18 90) (size 0.7 0.8) (layers "B.Cu" "B.Paste" "B.Mask")
      (net 687 "Net-(U50-EN)") (pinfunction "EN") (pintype "input"))
    (pad "6" smd rect (at -0.952 1.18 90) (size 0.7 0.8) (layers "B.Cu" "B.Paste" "B.Mask")
      (net 323 "Net-(U53-BST)") (pinfunction "BST") (pintype "output"))
  )

  (footprint "kria-k26-devboard-footprints:C_0402_1005Metric" (layer "B.Cu")
    (at 149.479999 114.945 -90)
    (descr "Capacitor SMD 0402")
    (tags "capacitor SMD 0402")
    (property "Author" "Antmicro")
    (property "Dielectric" "X5R")
    (property "License" "Apache-2.0")
    (property "MPN" "GRM155R61H104KE14D")
    (property "Manufacturer" "Murata")
    (property "Sheetfile" "debug.kicad_sch")
    (property "Sheetname" "Debug and JTAG")
    (property "Val" "100n")
    (property "Voltage" "50V")
    (property "ki_description" " ")
    (attr smd)
    (fp_text reference "C152" (at 0.865 -0.350001 90) (layer "B.SilkS")
        (effects (font (size 0.7 0.7) (thickness 0.15)) (justify left bottom mirror))
    )
    (fp_text value "C_100n_0402" (at 0 -1.4 90) (layer "B.Fab") hide
        (effects (font (size 0.7 0.7) (thickness 0.15)) (justify left bottom mirror))
    )
    (fp_text user "Author: Antmicro" (at -0.932 -4.17 90) (layer "B.Fab") hide
        (effects (font (size 0.7 0.7) (thickness 0.15)) (justify left bottom mirror))
    )
    (fp_text user "${REFERENCE}" (at -0.932 -3.168 90) (layer "B.Fab") hide
        (effects (font (size 0.7 0.7) (thickness 0.15)) (justify left bottom mirror))
    )
    (fp_text user "License: Apache-2.0" (at -0.932 -5.17 90) (layer "B.Fab") hide
        (effects (font (size 0.7 0.7) (thickness 0.15)) (justify left bottom mirror))
    )
    (fp_rect (start -0.94 0.47) (end 0.94 -0.47)
      (stroke (width 0.05) (type solid)) (fill none) (layer "B.CrtYd"))
    (fp_rect (start -0.499 0.249) (end 0.499 -0.249)
      (stroke (width 0.15) (type solid)) (fill none) (layer "B.Fab"))
    (pad "1" smd roundrect (at -0.484 0 270) (size 0.59 0.64) (layers "B.Cu" "B.Paste" "B.Mask") (roundrect_rratio 0.25)
      (net 135 "/Debug and JTAG/VCC_USB") (pintype "passive"))
    (pad "2" smd roundrect (at 0.484 0 270) (size 0.59 0.64) (layers "B.Cu" "B.Paste" "B.Mask") (roundrect_rratio 0.25)
      (net 1 "GND") (pintype "passive"))
  )

  (footprint "kria-k26-devboard-footprints:C_0402_1005Metric" (layer "B.Cu")
    (at 149.5 121.6 90)
    (descr "Capacitor SMD 0402")
    (tags "capacitor SMD 0402")
    (property "Author" "Antmicro")
    (property "Dielectric" "X5R")
    (property "License" "Apache-2.0")
    (property "MPN" "GRM155R61H104KE14D")
    (property "Manufacturer" "Murata")
    (property "Sheetfile" "debug.kicad_sch")
    (property "Sheetname" "Debug and JTAG")
    (property "Val" "100n")
    (property "Voltage" "50V")
    (property "ki_description" " ")
    (attr smd)
    (fp_text reference "C149" (at 1.26 4.35 270) (layer "B.SilkS")
        (effects (font (size 0.7 0.7) (thickness 0.15)) (justify left bottom mirror))
    )
    (fp_text value "C_100n_0402" (at 0 -1.4 270) (layer "B.Fab") hide
        (effects (font (size 0.7 0.7) (thickness 0.15)) (justify left bottom mirror))
    )
    (fp_text user "${REFERENCE}" (at -0.932 -3.168 270) (layer "B.Fab") hide
        (effects (font (size 0.7 0.7) (thickness 0.15)) (justify left bottom mirror))
    )
    (fp_text user "Author: Antmicro" (at -0.932 -4.17 270) (layer "B.Fab") hide
        (effects (font (size 0.7 0.7) (thickness 0.15)) (justify left bottom mirror))
    )
    (fp_text user "License: Apache-2.0" (at -0.932 -5.17 270) (layer "B.Fab") hide
        (effects (font (size 0.7 0.7) (thickness 0.15)) (justify left bottom mirror))
    )
    (fp_rect (start -0.94 0.47) (end 0.94 -0.47)
      (stroke (width 0.05) (type solid)) (fill none) (layer "B.CrtYd"))
    (fp_rect (start -0.499 0.249) (end 0.499 -0.249)
      (stroke (width 0.15) (type solid)) (fill none) (layer "B.Fab"))
    (pad "1" smd roundrect (at -0.484 0 90) (size 0.59 0.64) (layers "B.Cu" "B.Paste" "B.Mask") (roundrect_rratio 0.25)
      (net 134 "/Debug and JTAG/VREGIN") (pintype "passive"))
    (pad "2" smd roundrect (at 0.484 0 90) (size 0.59 0.64) (layers "B.Cu" "B.Paste" "B.Mask") (roundrect_rratio 0.25)
      (net 1 "GND") (pintype "passive"))
  )

  (footprint "kria-k26-devboard-footprints:C_0402_1005Metric" (layer "B.Cu")
    (at 148.5 121.66 90)
    (descr "Capacitor SMD 0402")
    (tags "capacitor SMD 0402")
    (property "Author" "Antmicro")
    (property "Dielectric" "X5R")
    (property "License" "Apache-2.0")
    (property "MPN" "GRM155R61H104KE14D")
    (property "Manufacturer" "Murata")
    (property "Sheetfile" "debug.kicad_sch")
    (property "Sheetname" "Debug and JTAG")
    (property "Val" "100n")
    (property "Voltage" "50V")
    (property "ki_description" " ")
    (attr smd)
    (fp_text reference "C142" (at 1.26 4.35 270) (layer "B.SilkS")
        (effects (font (size 0.7 0.7) (thickness 0.15)) (justify left bottom mirror))
    )
    (fp_text value "C_100n_0402" (at 0 -1.4 270) (layer "B.Fab") hide
        (effects (font (size 0.7 0.7) (thickness 0.15)) (justify left bottom mirror))
    )
    (fp_text user "${REFERENCE}" (at -0.932 -3.168 270) (layer "B.Fab") hide
        (effects (font (size 0.7 0.7) (thickness 0.15)) (justify left bottom mirror))
    )
    (fp_text user "Author: Antmicro" (at -0.932 -4.17 270) (layer "B.Fab") hide
        (effects (font (size 0.7 0.7) (thickness 0.15)) (justify left bottom mirror))
    )
    (fp_text user "License: Apache-2.0" (at -0.932 -5.17 270) (layer "B.Fab") hide
        (effects (font (size 0.7 0.7) (thickness 0.15)) (justify left bottom mirror))
    )
    (fp_rect (start -0.94 0.47) (end 0.94 -0.47)
      (stroke (width 0.05) (type solid)) (fill none) (layer "B.CrtYd"))
    (fp_rect (start -0.499 0.249) (end 0.499 -0.249)
      (stroke (width 0.15) (type solid)) (fill none) (layer "B.Fab"))
    (pad "1" smd roundrect (at -0.484 0 90) (size 0.59 0.64) (layers "B.Cu" "B.Paste" "B.Mask") (roundrect_rratio 0.25)
      (net 138 "/Debug and JTAG/USB_3V3") (pintype "passive"))
    (pad "2" smd roundrect (at 0.484 0 90) (size 0.59 0.64) (layers "B.Cu" "B.Paste" "B.Mask") (roundrect_rratio 0.25)
      (net 1 "GND") (pintype "passive"))
  )

  (footprint "kria-k26-devboard-footprints:R_0402_1005Metric" (layer "B.Cu")
    (at 139.95 92.6)
    (descr "Resistor SMD 0402")
    (tags "resistor SMD 0402")
    (property "Author" "Antmicro")
    (property "License" "Apache-2.0")
    (property "MPN" "CR0402-FX-5100GLF")
    (property "Manufacturer" "Bourns")
    (property "Sheetfile" "dc-dc-conventers.kicad_sch")
    (property "Sheetname" "DC/DC conventers")
    (property "Tolerance" "1%")
    (property "Val" "510R")
    (property "ki_description" "510R resistor in 0402 package with 1% tolerance")
    (attr smd)
    (fp_text reference "R141" (at 3.68 0.38 180) (layer "B.SilkS")
        (effects (font (size 0.7 0.7) (thickness 0.15)) (justify left bottom mirror))
    )
    (fp_text value "R_510R_0402" (at 0 -1.4 180) (layer "B.Fab") hide
        (effects (font (size 0.7 0.7) (thickness 0.15)) (justify left bottom mirror))
    )
    (fp_text user "${REFERENCE}" (at -0.95 -3.168 180) (layer "B.Fab") hide
        (effects (font (size 0.7 0.7) (thickness 0.15)) (justify left bottom mirror))
    )
    (fp_text user "Author: Antmicro" (at -0.95 -4.169 180) (layer "B.Fab") hide
        (effects (font (size 0.7 0.7) (thickness 0.15)) (justify left bottom mirror))
    )
    (fp_text user "License: Apache-2.0" (at -0.95 -5.169 180) (layer "B.Fab") hide
        (effects (font (size 0.7 0.7) (thickness 0.15)) (justify left bottom mirror))
    )
    (fp_rect (start -0.93 0.47) (end 0.93 -0.47)
      (stroke (width 0.05) (type solid)) (fill none) (layer "B.CrtYd"))
    (fp_rect (start -0.5 0.25) (end 0.5 -0.25)
      (stroke (width 0.15) (type solid)) (fill none) (layer "B.Fab"))
    (pad "1" smd roundrect (at -0.485 0) (size 0.59 0.64) (layers "B.Cu" "B.Paste" "B.Mask") (roundrect_rratio 0.25)
      (net 190 "Net-(D18-Pad1)") (pintype "passive"))
    (pad "2" smd roundrect (at 0.485 0) (size 0.59 0.64) (layers "B.Cu" "B.Paste" "B.Mask") (roundrect_rratio 0.25)
      (net 766 "/Power Supply/DC/DC conventers/PS_2V5_OUT") (pintype "passive"))
  )

  (footprint "kria-k26-devboard-footprints:C_0603_1608Metric" (layer "B.Cu")
    (at 134.3 90.950002 -90)
    (descr "Capacitor SMD 0603")
    (tags "capacitor 0603")
    (property "Author" "Antmicro")
    (property "Dielectric" "")
    (property "License" "Apache-2.0")
    (property "MPN" "C1608X5R1E106M080AC")
    (property "Manufacturer" "TDK")
    (property "Sheetfile" "dc-dc-conventers.kicad_sch")
    (property "Sheetname" "DC/DC conventers")
    (property "Val" "10u/25V")
    (property "Voltage" "")
    (property "ki_description" " ")
    (attr smd)
    (fp_text reference "C205" (at -1.520002 0.84 90) (layer "B.SilkS")
        (effects (font (size 0.7 0.7) (thickness 0.15)) (justify left bottom mirror))
    )
    (fp_text value "C_10u_25V_0603" (at 0 -1.6 90) (layer "B.Fab") hide
        (effects (font (size 0.7 0.7) (thickness 0.15)) (justify left bottom mirror))
    )
    (fp_text user "Author: Antmicro" (at -1.682 -4.894 90) (layer "B.Fab") hide
        (effects (font (size 0.7 0.7) (thickness 0.15)) (justify left bottom mirror))
    )
    (fp_text user "${REFERENCE}" (at -1.682 -3.895 90) (layer "B.Fab") hide
        (effects (font (size 0.7 0.7) (thickness 0.15)) (justify left bottom mirror))
    )
    (fp_text user "License: Apache-2.0" (at -1.682 -5.895 90) (layer "B.Fab") hide
        (effects (font (size 0.7 0.7) (thickness 0.15)) (justify left bottom mirror))
    )
    (fp_line (start -0.3 -0.3) (end 0.3 -0.3)
      (stroke (width 0.15) (type solid)) (layer "B.SilkS"))
    (fp_line (start -0.3 0.3) (end 0.3 0.3)
      (stroke (width 0.15) (type solid)) (layer "B.SilkS"))
    (fp_rect (start -1.24 0.7) (end 1.24 -0.7)
      (stroke (width 0.05) (type solid)) (fill none) (layer "B.CrtYd"))
    (fp_rect (start -0.8 0.4) (end 0.8 -0.4)
      (stroke (width 0.15) (type solid)) (fill none) (layer "B.Fab"))
    (pad "1" smd roundrect (at -0.7 0 270) (size 0.6 0.8) (layers "B.Cu" "B.Paste" "B.Mask") (roundrect_rratio 0.2)
      (net 14 "/Power Supply/DC/DC conventers/DC_MAIN_BUS") (pintype "passive"))
    (pad "2" smd roundrect (at 0.7 0 270) (size 0.6 0.8) (layers "B.Cu" "B.Paste" "B.Mask") (roundrect_rratio 0.2)
      (net 1 "GND") (pintype "passive"))
  )

  (footprint "kria-k26-devboard-footprints:C_0402_1005Metric" (layer "B.Cu")
    (at 95.49 86.85 -90)
    (descr "Capacitor SMD 0402")
    (tags "capacitor SMD 0402")
    (property "Author" "Antmicro")
    (property "Dielectric" "X5R")
    (property "License" "Apache-2.0")
    (property "MPN" "GRM155R61H104KE14D")
    (property "Manufacturer" "Murata")
    (property "Sheetfile" "dp.kicad_sch")
    (property "Sheetname" "Display Port")
    (property "Val" "100n")
    (property "Voltage" "50V")
    (property "ki_description" " ")
    (attr smd)
    (fp_text reference "C3" (at -0.69 -1.37 90) (layer "B.SilkS")
        (effects (font (size 0.7 0.7) (thickness 0.15)) (justify left bottom mirror))
    )
    (fp_text value "C_100n_0402" (at 0 -1.4 90) (layer "B.Fab") hide
        (effects (font (size 0.7 0.7) (thickness 0.15)) (justify left bottom mirror))
    )
    (fp_text user "${REFERENCE}" (at -0.932 -3.168 90) (layer "B.Fab") hide
        (effects (font (size 0.7 0.7) (thickness 0.15)) (justify left bottom mirror))
    )
    (fp_text user "Author: Antmicro" (at -0.932 -4.17 90) (layer "B.Fab") hide
        (effects (font (size 0.7 0.7) (thickness 0.15)) (justify left bottom mirror))
    )
    (fp_text user "License: Apache-2.0" (at -0.932 -5.17 90) (layer "B.Fab") hide
        (effects (font (size 0.7 0.7) (thickness 0.15)) (justify left bottom mirror))
    )
    (fp_rect (start -0.94 0.47) (end 0.94 -0.47)
      (stroke (width 0.05) (type solid)) (fill none) (layer "B.CrtYd"))
    (fp_rect (start -0.499 0.249) (end 0.499 -0.249)
      (stroke (width 0.15) (type solid)) (fill none) (layer "B.Fab"))
    (pad "1" smd roundrect (at -0.484 0 270) (size 0.59 0.64) (layers "B.Cu" "B.Paste" "B.Mask") (roundrect_rratio 0.25)
      (net 17 "PS_1V8") (pintype "passive"))
    (pad "2" smd roundrect (at 0.484 0 270) (size 0.59 0.64) (layers "B.Cu" "B.Paste" "B.Mask") (roundrect_rratio 0.25)
      (net 1 "GND") (pintype "passive"))
  )

  (footprint "kria-k26-devboard-footprints:TSSOP-14_4.4x5mm_P0.65mm" (layer "B.Cu")
    (at 92.6 79.7 90)
    (descr "TSSOP, 14 Pin (JEDEC MO-153 Var AB-1 https://www.jedec.org/document_search?search_api_views_fulltext=MO-153), generated with kicad-footprint-generator ipc_gullwing_generator.py")
    (tags "TSSOP SO")
    (property "Author" "Antmicro")
    (property "License" "Apache-2.0")
    (property "MPN" "FIN1019MTCX")
    (property "Manufacturer" "ON Semiconductor")
    (property "Sheetfile" "dp.kicad_sch")
    (property "Sheetname" "Display Port")
    (property "ki_description" "3.3V LVDS High Speed Differential Driver/Receiver, 400Mbps, TSSOP-14")
    (property "ki_keywords" "lvds driver reciever")
    (attr smd)
    (fp_text reference "U2" (at 0.5 3.18 270) (layer "B.SilkS")
        (effects (font (size 0.7 0.7) (thickness 0.15)) (justify left mirror))
    )
    (fp_text value "FIN1019MTC" (at -3.8 -4.3 270) (layer "B.Fab") hide
        (effects (font (size 0.7 0.7) (thickness 0.15)) (justify left bottom mirror))
    )
    (fp_text user "." (at -3.7 2.8 270) (layer "B.SilkS")
        (effects (font (size 1 1) (thickness 0.15)) (justify left mirror))
    )
    (fp_text user "Author: Antmicro" (at -3.851 -6.45 270) (layer "B.Fab") hide
        (effects (font (size 0.7 0.7) (thickness 0.15)) (justify left bottom mirror))
    )
    (fp_text user "License: Apache-2.0" (at -3.851 -7.45 270) (layer "B.Fab") hide
        (effects (font (size 0.7 0.7) (thickness 0.15)) (justify left bottom mirror))
    )
    (fp_text user "${REFERENCE}" (at -3.851 -5.45 270) (layer "B.Fab") hide
        (effects (font (size 0.7 0.7) (thickness 0.15)) (justify left bottom mirror))
    )
    (fp_line (start -2.9 2.3) (end -2.3 2.3)
      (stroke (width 0.15) (type solid)) (layer "B.SilkS"))
    (fp_line (start -2.3 -2.6) (end -2.3 -2.3)
      (stroke (width 0.15) (type solid)) (layer "B.SilkS"))
    (fp_line (start -2.3 2.61) (end -2.3 2.3)
      (stroke (width 0.15) (type solid)) (layer "B.SilkS"))
    (fp_line (start -2.3 2.61) (end 2.3 2.605)
      (stroke (width 0.15) (type solid)) (layer "B.SilkS"))
    (fp_line (start 2.3 -2.6) (end -2.3 -2.6)
      (stroke (width 0.15) (type solid)) (layer "B.SilkS"))
    (fp_line (start 2.3 -2.3) (end 2.3 -2.6)
      (stroke (width 0.15) (type solid)) (layer "B.SilkS"))
    (fp_line (start 2.3 2.3) (end 2.3 2.605)
      (stroke (width 0.15) (type solid)) (layer "B.SilkS"))
    (fp_line (start -3.7 -2.6) (end 3.7 -2.6)
      (stroke (width 0.05) (type solid)) (layer "B.CrtYd"))
    (fp_line (start -3.7 2.6) (end -3.7 -2.6)
      (stroke (width 0.05) (type solid)) (layer "B.CrtYd"))
    (fp_line (start 3.7 -2.6) (end 3.7 2.6)
      (stroke (width 0.05) (type solid)) (layer "B.CrtYd"))
    (fp_line (start 3.7 2.6) (end -3.7 2.6)
      (stroke (width 0.05) (type solid)) (layer "B.CrtYd"))
    (fp_line (start -2.202 -2.499) (end -2.202 1.5)
      (stroke (width 0.15) (type solid)) (layer "B.Fab"))
    (fp_line (start -2.202 1.5) (end -1.2 2.5)
      (stroke (width 0.15) (type solid)) (layer "B.Fab"))
    (fp_line (start -1.2 2.5) (end 2.2 2.5)
      (stroke (width 0.15) (type solid)) (layer "B.Fab"))
    (fp_line (start 2.2 -2.499) (end -2.202 -2.499)
      (stroke (width 0.15) (type solid)) (layer "B.Fab"))
    (fp_line (start 2.2 2.5) (end 2.2 -2.499)
      (stroke (width 0.15) (type solid)) (layer "B.Fab"))
    (pad "1" smd roundrect (at -2.863 1.95 90) (size 1.475 0.4) (layers "B.Cu" "B.Paste" "B.Mask") (roundrect_rratio 0.25)
      (net 125 "/Display Port/DP_OE") (pinfunction "DE") (pintype "input"))
    (pad "2" smd roundrect (at -2.863 1.301 90) (size 1.475 0.4) (layers "B.Cu" "B.Paste" "B.Mask") (roundrect_rratio 0.25)
      (net 124 "/Display Port/DP_AUX_OUT") (pinfunction "DI") (pintype "input"))
    (pad "3" smd roundrect (at -2.863 0.652 90) (size 1.475 0.4) (layers "B.Cu" "B.Paste" "B.Mask") (roundrect_rratio 0.25)
      (net 701 "unconnected-(U2-NC-Pad3)") (pinfunction "NC") (pintype "no_connect"))
    (pad "4" smd roundrect (at -2.863 0 90) (size 1.475 0.4) (layers "B.Cu" "B.Paste" "B.Mask") (roundrect_rratio 0.25)
      (net 126 "/Display Port/DP_AUX_IN") (pinfunction "RO") (pintype "output"))
    (pad "5" smd roundrect (at -2.863 -0.65 90) (size 1.475 0.4) (layers "B.Cu" "B.Paste" "B.Mask") (roundrect_rratio 0.25)
      (net 702 "unconnected-(U2-NC-Pad5)") (pinfunction "NC") (pintype "no_connect"))
    (pad "6" smd roundrect (at -2.863 -1.3 90) (size 1.475 0.4) (layers "B.Cu" "B.Paste" "B.Mask") (roundrect_rratio 0.25)
      (net 703 "unconnected-(U2-NC-Pad6)") (pinfunction "NC") (pintype "no_connect"))
    (pad "7" smd roundrect (at -2.863 -1.949 90) (size 1.475 0.4) (layers "B.Cu" "B.Paste" "B.Mask") (roundrect_rratio 0.25)
      (net 1 "GND") (pinfunction "GND") (pintype "power_in"))
    (pad "8" smd roundrect (at 2.862 -1.949 90) (size 1.475 0.4) (layers "B.Cu" "B.Paste" "B.Mask") (roundrect_rratio 0.25)
      (net 125 "/Display Port/DP_OE") (pinfunction "~{RE}") (pintype "input"))
    (pad "9" smd roundrect (at 2.862 -1.3 90) (size 1.475 0.4) (layers "B.Cu" "B.Paste" "B.Mask") (roundrect_rratio 0.25)
      (net 98 "/Display Port/DP_AUX_N") (pinfunction "RI-") (pintype "input"))
    (pad "10" smd roundrect (at 2.862 -0.65 90) (size 1.475 0.4) (layers "B.Cu" "B.Paste" "B.Mask") (roundrect_rratio 0.25)
      (net 96 "/Display Port/DP_AUX_P") (pinfunction "RI+") (pintype "input"))
    (pad "11" smd roundrect (at 2.862 0 90) (size 1.475 0.4) (layers "B.Cu" "B.Paste" "B.Mask") (roundrect_rratio 0.25)
      (net 98 "/Display Port/DP_AUX_N") (pinfunction "DO-") (pintype "output"))
    (pad "12" smd roundrect (at 2.862 0.652 90) (size 1.475 0.4) (layers "B.Cu" "B.Paste" "B.Mask") (roundrect_rratio 0.25)
      (net 96 "/Display Port/DP_AUX_P") (pinfunction "DO+") (pintype "output"))
    (pad "13" smd roundrect (at 2.862 1.301 90) (size 1.475 0.4) (layers "B.Cu" "B.Paste" "B.Mask") (roundrect_rratio 0.25)
      (net 704 "unconnected-(U2-NC-Pad13)") (pinfunction "NC") (pintype "no_connect"))
    (pad "14" smd roundrect (at 2.862 1.95 90) (size 1.475 0.4) (layers "B.Cu" "B.Paste" "B.Mask") (roundrect_rratio 0.25)
      (net 15 "PS_3V3") (pinfunction "VCC") (pintype "power_in"))
  )

  (footprint "kria-k26-devboard-footprints:R_0402_1005Metric" (layer "B.Cu")
    (at 117.9 92.7 90)
    (descr "Resistor SMD 0402")
    (tags "resistor SMD 0402")
    (property "Author" "Antmicro")
    (property "License" "Apache-2.0")
    (property "MPN" "CR0402-FX-1202GLF")
    (property "Manufacturer" "Bourns")
    (property "Sheetfile" "usb.kicad_sch")
    (property "Sheetname" "USB")
    (property "Tolerance" "1%")
    (property "Val" "12k")
    (property "ki_description" "12k resistor in 0402 package with 1% tolerance")
    (attr smd)
    (fp_text reference "R38" (at -0.84 0.33 270) (layer "B.SilkS")
        (effects (font (size 0.7 0.7) (thickness 0.15)) (justify left bottom mirror))
    )
    (fp_text value "R_12k_0402" (at 0 -1.4 270) (layer "B.Fab") hide
        (effects (font (size 0.7 0.7) (thickness 0.15)) (justify left bottom mirror))
    )
    (fp_text user "Author: Antmicro" (at -0.95 -4.169 270) (layer "B.Fab") hide
        (effects (font (size 0.7 0.7) (thickness 0.15)) (justify left bottom mirror))
    )
    (fp_text user "License: Apache-2.0" (at -0.95 -5.169 270) (layer "B.Fab") hide
        (effects (font (size 0.7 0.7) (thickness 0.15)) (justify left bottom mirror))
    )
    (fp_text user "${REFERENCE}" (at -0.95 -3.168 270) (layer "B.Fab") hide
        (effects (font (size 0.7 0.7) (thickness 0.15)) (justify left bottom mirror))
    )
    (fp_rect (start -0.93 0.47) (end 0.93 -0.47)
      (stroke (width 0.05) (type solid)) (fill none) (layer "B.CrtYd"))
    (fp_rect (start -0.5 0.25) (end 0.5 -0.25)
      (stroke (width 0.15) (type solid)) (fill none) (layer "B.Fab"))
    (pad "1" smd roundrect (at -0.485 0 90) (size 0.59 0.64) (layers "B.Cu" "B.Paste" "B.Mask") (roundrect_rratio 0.25)
      (net 15 "PS_3V3") (pintype "passive"))
    (pad "2" smd roundrect (at 0.485 0 90) (size 0.59 0.64) (layers "B.Cu" "B.Paste" "B.Mask") (roundrect_rratio 0.25)
      (net 275 "/USB/VBUS") (pintype "passive"))
  )

  (footprint "kria-k26-devboard-footprints:R_0402_1005Metric" (layer "B.Cu")
    (at 122.2 146.55 -90)
    (descr "Resistor SMD 0402")
    (tags "resistor SMD 0402")
    (property "Author" "Antmicro")
    (property "License" "Apache-2.0")
    (property "MPN" "CR0402-FX-1001GLF")
    (property "Manufacturer" "Bourns")
    (property "Sheetfile" "sd-3-card.kicad_sch")
    (property "Sheetname" "SD 3.0 card")
    (property "Tolerance" "1%")
    (property "Val" "1k")
    (property "ki_description" "1k resistor in 0402 package with 1% tolerance")
    (attr smd)
    (fp_text reference "R17" (at 0.87 -0.41 90) (layer "B.SilkS")
        (effects (font (size 0.7 0.7) (thickness 0.15)) (justify left bottom mirror))
    )
    (fp_text value "R_1k_0402" (at 0 -1.4 90) (layer "B.Fab") hide
        (effects (font (size 0.7 0.7) (thickness 0.15)) (justify left bottom mirror))
    )
    (fp_text user "${REFERENCE}" (at -0.95 -3.168 90) (layer "B.Fab") hide
        (effects (font (size 0.7 0.7) (thickness 0.15)) (justify left bottom mirror))
    )
    (fp_text user "License: Apache-2.0" (at -0.95 -5.169 90) (layer "B.Fab") hide
        (effects (font (size 0.7 0.7) (thickness 0.15)) (justify left bottom mirror))
    )
    (fp_text user "Author: Antmicro" (at -0.95 -4.169 90) (layer "B.Fab") hide
        (effects (font (size 0.7 0.7) (thickness 0.15)) (justify left bottom mirror))
    )
    (fp_rect (start -0.93 0.47) (end 0.93 -0.47)
      (stroke (width 0.05) (type solid)) (fill none) (layer "B.CrtYd"))
    (fp_rect (start -0.5 0.25) (end 0.5 -0.25)
      (stroke (width 0.15) (type solid)) (fill none) (layer "B.Fab"))
    (pad "1" smd roundrect (at -0.485 0 270) (size 0.59 0.64) (layers "B.Cu" "B.Paste" "B.Mask") (roundrect_rratio 0.25)
      (net 415 "Net-(Q1-D)") (pintype "passive"))
    (pad "2" smd roundrect (at 0.485 0 270) (size 0.59 0.64) (layers "B.Cu" "B.Paste" "B.Mask") (roundrect_rratio 0.25)
      (net 131 "Net-(Q2-G)") (pintype "passive"))
  )

  (footprint "kria-k26-devboard-footprints:C_0603_1608Metric" (layer "B.Cu")
    (at 130.45 146.1)
    (descr "Capacitor SMD 0603")
    (tags "capacitor 0603")
    (property "Author" "Antmicro")
    (property "License" "Apache-2.0")
    (property "MPN" "GRM188R61A106KE69D")
    (property "Manufacturer" "Murata")
    (property "Sheetfile" "sd-3-card.kicad_sch")
    (property "Sheetname" "SD 3.0 card")
    (property "Val" "10u")
    (property "Voltage" "")
    (property "ki_description" " ")
    (attr smd)
    (fp_text reference "C20" (at 3.34 0.36 180) (layer "B.SilkS")
        (effects (font (size 0.7 0.7) (thickness 0.15)) (justify left bottom mirror))
    )
    (fp_text value "C_10u_0603" (at 0 -1.6 180) (layer "B.Fab") hide
        (effects (font (size 0.7 0.7) (thickness 0.15)) (justify left bottom mirror))
    )
    (fp_text user "Author: Antmicro" (at -1.682 -4.894 180) (layer "B.Fab") hide
        (effects (font (size 0.7 0.7) (thickness 0.15)) (justify left bottom mirror))
    )
    (fp_text user "${REFERENCE}" (at -1.682 -3.895 180) (layer "B.Fab") hide
        (effects (font (size 0.7 0.7) (thickness 0.15)) (justify left bottom mirror))
    )
    (fp_text user "License: Apache-2.0" (at -1.682 -5.895 180) (layer "B.Fab") hide
        (effects (font (size 0.7 0.7) (thickness 0.15)) (justify left bottom mirror))
    )
    (fp_line (start -0.3 -0.3) (end 0.3 -0.3)
      (stroke (width 0.15) (type solid)) (layer "B.SilkS"))
    (fp_line (start -0.3 0.3) (end 0.3 0.3)
      (stroke (width 0.15) (type solid)) (layer "B.SilkS"))
    (fp_rect (start -1.24 0.7) (end 1.24 -0.7)
      (stroke (width 0.05) (type solid)) (fill none) (layer "B.CrtYd"))
    (fp_rect (start -0.8 0.4) (end 0.8 -0.4)
      (stroke (width 0.15) (type solid)) (fill none) (layer "B.Fab"))
    (pad "1" smd roundrect (at -0.7 0) (size 0.6 0.8) (layers "B.Cu" "B.Paste" "B.Mask") (roundrect_rratio 0.2)
      (net 317 "/SD 3.0 card/SD_VDD") (pintype "passive"))
    (pad "2" smd roundrect (at 0.7 0) (size 0.6 0.8) (layers "B.Cu" "B.Paste" "B.Mask") (roundrect_rratio 0.2)
      (net 1 "GND") (pintype "passive"))
  )

  (footprint "kria-k26-devboard-footprints:C_0402_1005Metric" (layer "B.Cu")
    (at 130.25 147.29)
    (descr "Capacitor SMD 0402")
    (tags "capacitor SMD 0402")
    (property "Author" "Antmicro")
    (property "Dielectric" "X5R")
    (property "License" "Apache-2.0")
    (property "MPN" "GRM155R61H104KE14D")
    (property "Manufacturer" "Murata")
    (property "Sheetfile" "sd-3-card.kicad_sch")
    (property "Sheetname" "SD 3.0 card")
    (property "Val" "100n")
    (property "Voltage" "50V")
    (property "ki_description" " ")
    (attr smd)
    (fp_text reference "C19" (at 3.1 0.53 180) (layer "B.SilkS")
        (effects (font (size 0.7 0.7) (thickness 0.15)) (justify left bottom mirror))
    )
    (fp_text value "C_100n_0402" (at 0 -1.4 180) (layer "B.Fab") hide
        (effects (font (size 0.7 0.7) (thickness 0.15)) (justify left bottom mirror))
    )
    (fp_text user "${REFERENCE}" (at -0.932 -3.168 180) (layer "B.Fab") hide
        (effects (font (size 0.7 0.7) (thickness 0.15)) (justify left bottom mirror))
    )
    (fp_text user "Author: Antmicro" (at -0.932 -4.17 180) (layer "B.Fab") hide
        (effects (font (size 0.7 0.7) (thickness 0.15)) (justify left bottom mirror))
    )
    (fp_text user "License: Apache-2.0" (at -0.932 -5.17 180) (layer "B.Fab") hide
        (effects (font (size 0.7 0.7) (thickness 0.15)) (justify left bottom mirror))
    )
    (fp_rect (start -0.94 0.47) (end 0.94 -0.47)
      (stroke (width 0.05) (type solid)) (fill none) (layer "B.CrtYd"))
    (fp_rect (start -0.499 0.249) (end 0.499 -0.249)
      (stroke (width 0.15) (type solid)) (fill none) (layer "B.Fab"))
    (pad "1" smd roundrect (at -0.484 0) (size 0.59 0.64) (layers "B.Cu" "B.Paste" "B.Mask") (roundrect_rratio 0.25)
      (net 317 "/SD 3.0 card/SD_VDD") (pintype "passive"))
    (pad "2" smd roundrect (at 0.484 0) (size 0.59 0.64) (layers "B.Cu" "B.Paste" "B.Mask") (roundrect_rratio 0.25)
      (net 1 "GND") (pintype "passive"))
  )

  (footprint "kria-k26-devboard-footprints:C_0402_1005Metric" (layer "B.Cu")
    (at 124.1 146.535 -90)
    (descr "Capacitor SMD 0402")
    (tags "capacitor SMD 0402")
    (property "Author" "Antmicro")
    (property "Dielectric" "")
    (property "License" "Apache-2.0")
    (property "MPN" "C1005X5R1E474M050BB")
    (property "Manufacturer" "TDK")
    (property "Sheetfile" "sd-3-card.kicad_sch")
    (property "Sheetname" "SD 3.0 card")
    (property "Val" "470n")
    (property "Voltage" "")
    (property "ki_description" " ")
    (attr smd)
    (fp_text reference "C17" (at 0.871 -0.41 90) (layer "B.SilkS")
        (effects (font (size 0.7 0.7) (thickness 0.15)) (justify left bottom mirror))
    )
    (fp_text value "C_470n_0402" (at 0 -1.4 90) (layer "B.Fab") hide
        (effects (font (size 0.7 0.7) (thickness 0.15)) (justify left bottom mirror))
    )
    (fp_text user "${REFERENCE}" (at -0.932 -3.168 90) (layer "B.Fab") hide
        (effects (font (size 0.7 0.7) (thickness 0.15)) (justify left bottom mirror))
    )
    (fp_text user "Author: Antmicro" (at -0.932 -4.17 90) (layer "B.Fab") hide
        (effects (font (size 0.7 0.7) (thickness 0.15)) (justify left bottom mirror))
    )
    (fp_text user "License: Apache-2.0" (at -0.932 -5.17 90) (layer "B.Fab") hide
        (effects (font (size 0.7 0.7) (thickness 0.15)) (justify left bottom mirror))
    )
    (fp_rect (start -0.94 0.47) (end 0.94 -0.47)
      (stroke (width 0.05) (type solid)) (fill none) (layer "B.CrtYd"))
    (fp_rect (start -0.499 0.249) (end 0.499 -0.249)
      (stroke (width 0.15) (type solid)) (fill none) (layer "B.Fab"))
    (pad "1" smd roundrect (at -0.484 0 270) (size 0.59 0.64) (layers "B.Cu" "B.Paste" "B.Mask") (roundrect_rratio 0.25)
      (net 15 "PS_3V3") (pintype "passive"))
    (pad "2" smd roundrect (at 0.484 0 270) (size 0.59 0.64) (layers "B.Cu" "B.Paste" "B.Mask") (roundrect_rratio 0.25)
      (net 131 "Net-(Q2-G)") (pintype "passive"))
  )

  (footprint "kria-k26-devboard-footprints:R_0402_1005Metric" (layer "B.Cu")
    (at 123.15 146.55 -90)
    (descr "Resistor SMD 0402")
    (tags "resistor SMD 0402")
    (property "Author" "Antmicro")
    (property "License" "Apache-2.0")
    (property "MPN" "CR0402-FX-1002GLF")
    (property "Manufacturer" "Bourns")
    (property "Sheetfile" "sd-3-card.kicad_sch")
    (property "Sheetname" "SD 3.0 card")
    (property "Tolerance" "1%")
    (property "Val" "10k")
    (property "ki_description" "10k resistor in 0402 package with 1% tolerance")
    (attr smd)
    (fp_text reference "R16" (at 0.87 -0.41 90) (layer "B.SilkS")
        (effects (font (size 0.7 0.7) (thickness 0.15)) (justify left bottom mirror))
    )
    (fp_text value "R_10k_0402" (at 0 -1.4 90) (layer "B.Fab") hide
        (effects (font (size 0.7 0.7) (thickness 0.15)) (justify left bottom mirror))
    )
    (fp_text user "${REFERENCE}" (at -0.95 -3.168 90) (layer "B.Fab") hide
        (effects (font (size 0.7 0.7) (thickness 0.15)) (justify left bottom mirror))
    )
    (fp_text user "Author: Antmicro" (at -0.95 -4.169 90) (layer "B.Fab") hide
        (effects (font (size 0.7 0.7) (thickness 0.15)) (justify left bottom mirror))
    )
    (fp_text user "License: Apache-2.0" (at -0.95 -5.169 90) (layer "B.Fab") hide
        (effects (font (size 0.7 0.7) (thickness 0.15)) (justify left bottom mirror))
    )
    (fp_rect (start -0.93 0.47) (end 0.93 -0.47)
      (stroke (width 0.05) (type solid)) (fill none) (layer "B.CrtYd"))
    (fp_rect (start -0.5 0.25) (end 0.5 -0.25)
      (stroke (width 0.15) (type solid)) (fill none) (layer "B.Fab"))
    (pad "1" smd roundrect (at -0.485 0 270) (size 0.59 0.64) (layers "B.Cu" "B.Paste" "B.Mask") (roundrect_rratio 0.25)
      (net 15 "PS_3V3") (pintype "passive"))
    (pad "2" smd roundrect (at 0.485 0 270) (size 0.59 0.64) (layers "B.Cu" "B.Paste" "B.Mask") (roundrect_rratio 0.25)
      (net 131 "Net-(Q2-G)") (pintype "passive"))
  )

  (footprint "kria-k26-devboard-footprints:C_0402_1005Metric" (layer "B.Cu")
    (at 125.05 146.55 90)
    (descr "Capacitor SMD 0402")
    (tags "capacitor SMD 0402")
    (property "Author" "Antmicro")
    (property "Dielectric" "")
    (property "License" "Apache-2.0")
    (property "MPN" "C1005X5R1E474M050BB")
    (property "Manufacturer" "TDK")
    (property "Sheetfile" "sd-3-card.kicad_sch")
    (property "Sheetname" "SD 3.0 card")
    (property "Val" "470n")
    (property "Voltage" "")
    (property "ki_description" " ")
    (attr smd)
    (fp_text reference "C18" (at -0.87 0.42 270) (layer "B.SilkS")
        (effects (font (size 0.7 0.7) (thickness 0.15)) (justify left bottom mirror))
    )
    (fp_text value "C_470n_0402" (at 0 -1.4 270) (layer "B.Fab") hide
        (effects (font (size 0.7 0.7) (thickness 0.15)) (justify left bottom mirror))
    )
    (fp_text user "${REFERENCE}" (at -0.932 -3.168 270) (layer "B.Fab") hide
        (effects (font (size 0.7 0.7) (thickness 0.15)) (justify left bottom mirror))
    )
    (fp_text user "License: Apache-2.0" (at -0.932 -5.17 270) (layer "B.Fab") hide
        (effects (font (size 0.7 0.7) (thickness 0.15)) (justify left bottom mirror))
    )
    (fp_text user "Author: Antmicro" (at -0.932 -4.17 270) (layer "B.Fab") hide
        (effects (font (size 0.7 0.7) (thickness 0.15)) (justify left bottom mirror))
    )
    (fp_rect (start -0.94 0.47) (end 0.94 -0.47)
      (stroke (width 0.05) (type solid)) (fill none) (layer "B.CrtYd"))
    (fp_rect (start -0.499 0.249) (end 0.499 -0.249)
      (stroke (width 0.15) (type solid)) (fill none) (layer "B.Fab"))
    (pad "1" smd roundrect (at -0.484 0 90) (size 0.59 0.64) (layers "B.Cu" "B.Paste" "B.Mask") (roundrect_rratio 0.25)
      (net 131 "Net-(Q2-G)") (pintype "passive"))
    (pad "2" smd roundrect (at 0.484 0 90) (size 0.59 0.64) (layers "B.Cu" "B.Paste" "B.Mask") (roundrect_rratio 0.25)
      (net 317 "/SD 3.0 card/SD_VDD") (pintype "passive"))
  )

  (footprint "kria-k26-devboard-footprints:C_0402_1005Metric" (layer "B.Cu")
    (at 130.025 75.105 -90)
    (descr "Capacitor SMD 0402")
    (tags "capacitor SMD 0402")
    (property "Author" "Antmicro")
    (property "Dielectric" "X5R")
    (property "License" "Apache-2.0")
    (property "MPN" "GRM155R61H104KE14D")
    (property "Manufacturer" "Murata")
    (property "Sheetfile" "usb.kicad_sch")
    (property "Sheetname" "USB")
    (property "Val" "100n")
    (property "Voltage" "50V")
    (property "ki_description" " ")
    (attr smd)
    (fp_text reference "C66" (at 0.845 -0.385 90) (layer "B.SilkS")
        (effects (font (size 0.7 0.7) (thickness 0.15)) (justify left bottom mirror))
    )
    (fp_text value "C_100n_0402" (at 0 -1.4 90) (layer "B.Fab") hide
        (effects (font (size 0.7 0.7) (thickness 0.15)) (justify left bottom mirror))
    )
    (fp_text user "${REFERENCE}" (at -0.932 -3.168 90) (layer "B.Fab") hide
        (effects (font (size 0.7 0.7) (thickness 0.15)) (justify left bottom mirror))
    )
    (fp_text user "Author: Antmicro" (at -0.932 -4.17 90) (layer "B.Fab") hide
        (effects (font (size 0.7 0.7) (thickness 0.15)) (justify left bottom mirror))
    )
    (fp_text user "License: Apache-2.0" (at -0.932 -5.17 90) (layer "B.Fab") hide
        (effects (font (size 0.7 0.7) (thickness 0.15)) (justify left bottom mirror))
    )
    (fp_rect (start -0.94 0.47) (end 0.94 -0.47)
      (stroke (width 0.05) (type solid)) (fill none) (layer "B.CrtYd"))
    (fp_rect (start -0.499 0.249) (end 0.499 -0.249)
      (stroke (width 0.15) (type solid)) (fill none) (layer "B.Fab"))
    (pad "1" smd roundrect (at -0.484 0 270) (size 0.59 0.64) (layers "B.Cu" "B.Paste" "B.Mask") (roundrect_rratio 0.25)
      (net 278 "/USB/USB1_TX_C_N") (pintype "passive"))
    (pad "2" smd roundrect (at 0.484 0 270) (size 0.59 0.64) (layers "B.Cu" "B.Paste" "B.Mask") (roundrect_rratio 0.25)
      (net 60 "/USB/USB1_TX_N") (pintype "passive"))
  )

  (footprint "kria-k26-devboard-footprints:C_0402_1005Metric" (layer "B.Cu")
    (at 130.975 75.105 -90)
    (descr "Capacitor SMD 0402")
    (tags "capacitor SMD 0402")
    (property "Author" "Antmicro")
    (property "Dielectric" "X5R")
    (property "License" "Apache-2.0")
    (property "MPN" "GRM155R61H104KE14D")
    (property "Manufacturer" "Murata")
    (property "Sheetfile" "usb.kicad_sch")
    (property "Sheetname" "USB")
    (property "Val" "100n")
    (property "Voltage" "50V")
    (property "ki_description" " ")
    (attr smd)
    (fp_text reference "C67" (at 0.845 -0.385 90) (layer "B.SilkS")
        (effects (font (size 0.7 0.7) (thickness 0.15)) (justify left bottom mirror))
    )
    (fp_text value "C_100n_0402" (at 0 -1.4 90) (layer "B.Fab") hide
        (effects (font (size 0.7 0.7) (thickness 0.15)) (justify left bottom mirror))
    )
    (fp_text user "${REFERENCE}" (at -0.932 -3.168 90) (layer "B.Fab") hide
        (effects (font (size 0.7 0.7) (thickness 0.15)) (justify left bottom mirror))
    )
    (fp_text user "License: Apache-2.0" (at -0.932 -5.17 90) (layer "B.Fab") hide
        (effects (font (size 0.7 0.7) (thickness 0.15)) (justify left bottom mirror))
    )
    (fp_text user "Author: Antmicro" (at -0.932 -4.17 90) (layer "B.Fab") hide
        (effects (font (size 0.7 0.7) (thickness 0.15)) (justify left bottom mirror))
    )
    (fp_rect (start -0.94 0.47) (end 0.94 -0.47)
      (stroke (width 0.05) (type solid)) (fill none) (layer "B.CrtYd"))
    (fp_rect (start -0.499 0.249) (end 0.499 -0.249)
      (stroke (width 0.15) (type solid)) (fill none) (layer "B.Fab"))
    (pad "1" smd roundrect (at -0.484 0 270) (size 0.59 0.64) (layers "B.Cu" "B.Paste" "B.Mask") (roundrect_rratio 0.25)
      (net 279 "/USB/USB1_TX_C_P") (pintype "passive"))
    (pad "2" smd roundrect (at 0.484 0 270) (size 0.59 0.64) (layers "B.Cu" "B.Paste" "B.Mask") (roundrect_rratio 0.25)
      (net 61 "/USB/USB1_TX_P") (pintype "passive"))
  )

  (footprint "kria-k26-devboard-footprints:C_0402_1005Metric" (layer "B.Cu")
    (at 92.45 129.675)
    (descr "Capacitor SMD 0402")
    (tags "capacitor SMD 0402")
    (property "Author" "Antmicro")
    (property "Dielectric" "")
    (property "License" "Apache-2.0")
    (property "MPN" "GRM155R61A475MEAAD")
    (property "Manufacturer" "Murata")
    (property "Sheetfile" "k26_som.kicad_sch")
    (property "Sheetname" "Xilinx K26 SOM")
    (property "Val" "4u7")
    (property "Voltage" "")
    (property "ki_description" " ")
    (attr smd)
    (fp_text reference "C127" (at 3.8 0.355 180) (layer "B.SilkS")
        (effects (font (size 0.7 0.7) (thickness 0.15)) (justify left bottom mirror))
    )
    (fp_text value "C_4u7_0402" (at 0 -1.4 180) (layer "B.Fab") hide
        (effects (font (size 0.7 0.7) (thickness 0.15)) (justify left bottom mirror))
    )
    (fp_text user "License: Apache-2.0" (at -0.932 -5.17 180) (layer "B.Fab") hide
        (effects (font (size 0.7 0.7) (thickness 0.15)) (justify left bottom mirror))
    )
    (fp_text user "Author: Antmicro" (at -0.932 -4.17 180) (layer "B.Fab") hide
        (effects (font (size 0.7 0.7) (thickness 0.15)) (justify left bottom mirror))
    )
    (fp_text user "${REFERENCE}" (at -0.932 -3.168 180) (layer "B.Fab") hide
        (effects (font (size 0.7 0.7) (thickness 0.15)) (justify left bottom mirror))
    )
    (fp_rect (start -0.94 0.47) (end 0.94 -0.47)
      (stroke (width 0.05) (type solid)) (fill none) (layer "B.CrtYd"))
    (fp_rect (start -0.499 0.249) (end 0.499 -0.249)
      (stroke (width 0.15) (type solid)) (fill none) (layer "B.Fab"))
    (pad "1" smd roundrect (at -0.484 0) (size 0.59 0.64) (layers "B.Cu" "B.Paste" "B.Mask") (roundrect_rratio 0.25)
      (net 20 "PL_3V3") (pintype "passive"))
    (pad "2" smd roundrect (at 0.484 0) (size 0.59 0.64) (layers "B.Cu" "B.Paste" "B.Mask") (roundrect_rratio 0.25)
      (net 1 "GND") (pintype "passive"))
  )

  (footprint "kria-k26-devboard-footprints:C_0402_1005Metric" (layer "B.Cu")
    (at 138.31 93.85 -90)
    (descr "Capacitor SMD 0402")
    (tags "capacitor SMD 0402")
    (property "Author" "Antmicro")
    (property "Dielectric" "X5R")
    (property "License" "Apache-2.0")
    (property "MPN" "GRM155R61H104KE14D")
    (property "Manufacturer" "Murata")
    (property "Sheetfile" "dc-dc-conventers.kicad_sch")
    (property "Sheetname" "DC/DC conventers")
    (property "Val" "100n")
    (property "Voltage" "50V")
    (property "ki_description" " ")
    (attr smd)
    (fp_text reference "C210" (at 3.158 -0.365 -90) (layer "B.SilkS")
        (effects (font (size 0.7 0.7) (thickness 0.15)) (justify left bottom mirror))
    )
    (fp_text value "C_100n_0402" (at 0 -1.4 90) (layer "B.Fab") hide
        (effects (font (size 0.7 0.7) (thickness 0.15)) (justify left bottom mirror))
    )
    (fp_text user "Author: Antmicro" (at -0.932 -4.17 90) (layer "B.Fab") hide
        (effects (font (size 0.7 0.7) (thickness 0.15)) (justify left bottom mirror))
    )
    (fp_text user "${REFERENCE}" (at -0.932 -3.168 90) (layer "B.Fab") hide
        (effects (font (size 0.7 0.7) (thickness 0.15)) (justify left bottom mirror))
    )
    (fp_text user "License: Apache-2.0" (at -0.932 -5.17 90) (layer "B.Fab") hide
        (effects (font (size 0.7 0.7) (thickness 0.15)) (justify left bottom mirror))
    )
    (fp_rect (start -0.94 0.47) (end 0.94 -0.47)
      (stroke (width 0.05) (type solid)) (fill none) (layer "B.CrtYd"))
    (fp_rect (start -0.499 0.249) (end 0.499 -0.249)
      (stroke (width 0.15) (type solid)) (fill none) (layer "B.Fab"))
    (pad "1" smd roundrect (at -0.484 0 270) (size 0.59 0.64) (layers "B.Cu" "B.Paste" "B.Mask") (roundrect_rratio 0.25)
      (net 323 "Net-(U53-BST)") (pintype "passive"))
    (pad "2" smd roundrect (at 0.484 0 270) (size 0.59 0.64) (layers "B.Cu" "B.Paste" "B.Mask") (roundrect_rratio 0.25)
      (net 256 "/Power Supply/DC/DC conventers/SW_PS_1V0") (pintype "passive"))
  )

  (footprint "kria-k26-devboard-footprints:C_0402_1005Metric" (layer "B.Cu")
    (at 142.889035 94.404089 -90)
    (descr "Capacitor SMD 0402")
    (tags "capacitor SMD 0402")
    (property "Author" "Antmicro")
    (property "Dielectric" "X7R")
    (property "License" "Apache-2.0")
    (property "MPN" "GRM155R71H103KA88D")
    (property "Manufacturer" "Murata")
    (property "Sheetfile" "eth.kicad_sch")
    (property "Sheetname" "Ethernet")
    (property "Val" "10n")
    (property "Voltage" "50V")
    (property "ki_description" " ")
    (attr smd)
    (fp_text reference "C113" (at 0.945911 -0.360965 90) (layer "B.SilkS")
        (effects (font (size 0.7 0.7) (thickness 0.15)) (justify left bottom mirror))
    )
    (fp_text value "C_10n_0402" (at 0 -1.4 90) (layer "B.Fab") hide
        (effects (font (size 0.7 0.7) (thickness 0.15)) (justify left bottom mirror))
    )
    (fp_text user "License: Apache-2.0" (at -0.932 -5.17 90) (layer "B.Fab") hide
        (effects (font (size 0.7 0.7) (thickness 0.15)) (justify left bottom mirror))
    )
    (fp_text user "${REFERENCE}" (at -0.932 -3.168 90) (layer "B.Fab") hide
        (effects (font (size 0.7 0.7) (thickness 0.15)) (justify left bottom mirror))
    )
    (fp_text user "Author: Antmicro" (at -0.932 -4.17 90) (layer "B.Fab") hide
        (effects (font (size 0.7 0.7) (thickness 0.15)) (justify left bottom mirror))
    )
    (fp_rect (start -0.94 0.47) (end 0.94 -0.47)
      (stroke (width 0.05) (type solid)) (fill none) (layer "B.CrtYd"))
    (fp_rect (start -0.499 0.249) (end 0.499 -0.249)
      (stroke (width 0.15) (type solid)) (fill none) (layer "B.Fab"))
    (pad "1" smd roundrect (at -0.484 0 270) (size 0.59 0.64) (layers "B.Cu" "B.Paste" "B.Mask") (roundrect_rratio 0.25)
      (net 19 "PS_1V0") (pintype "passive"))
    (pad "2" smd roundrect (at 0.484 0 270) (size 0.59 0.64) (layers "B.Cu" "B.Paste" "B.Mask") (roundrect_rratio 0.25)
      (net 1 "GND") (pintype "passive"))
  )

  (footprint "kria-k26-devboard-footprints:C_0603_1608Metric" (layer "B.Cu")
    (at 141.654035 94.669089 90)
    (descr "Capacitor SMD 0603")
    (tags "capacitor 0603")
    (property "Author" "Antmicro")
    (property "License" "Apache-2.0")
    (property "MPN" "GRM188R61A106KE69D")
    (property "Manufacturer" "Murata")
    (property "Sheetfile" "eth.kicad_sch")
    (property "Sheetname" "Ethernet")
    (property "Val" "10u")
    (property "Voltage" "")
    (property "ki_description" " ")
    (attr smd)
    (fp_text reference "C114" (at -1.220911 0.445965 270) (layer "B.SilkS")
        (effects (font (size 0.7 0.7) (thickness 0.15)) (justify left bottom mirror))
    )
    (fp_text value "C_10u_0603" (at 0 -1.6 270) (layer "B.Fab") hide
        (effects (font (size 0.7 0.7) (thickness 0.15)) (justify left bottom mirror))
    )
    (fp_text user "Author: Antmicro" (at -1.682 -4.894 270) (layer "B.Fab") hide
        (effects (font (size 0.7 0.7) (thickness 0.15)) (justify left bottom mirror))
    )
    (fp_text user "License: Apache-2.0" (at -1.682 -5.895 270) (layer "B.Fab") hide
        (effects (font (size 0.7 0.7) (thickness 0.15)) (justify left bottom mirror))
    )
    (fp_text user "${REFERENCE}" (at -1.682 -3.895 270) (layer "B.Fab") hide
        (effects (font (size 0.7 0.7) (thickness 0.15)) (justify left bottom mirror))
    )
    (fp_line (start -0.3 -0.3) (end 0.3 -0.3)
      (stroke (width 0.15) (type solid)) (layer "B.SilkS"))
    (fp_line (start -0.3 0.3) (end 0.3 0.3)
      (stroke (width 0.15) (type solid)) (layer "B.SilkS"))
    (fp_rect (start -1.24 0.7) (end 1.24 -0.7)
      (stroke (width 0.05) (type solid)) (fill none) (layer "B.CrtYd"))
    (fp_rect (start -0.8 0.4) (end 0.8 -0.4)
      (stroke (width 0.15) (type solid)) (fill none) (layer "B.Fab"))
    (pad "1" smd roundrect (at -0.7 0 90) (size 0.6 0.8) (layers "B.Cu" "B.Paste" "B.Mask") (roundrect_rratio 0.2)
      (net 1 "GND") (pintype "passive"))
    (pad "2" smd roundrect (at 0.7 0 90) (size 0.6 0.8) (layers "B.Cu" "B.Paste" "B.Mask") (roundrect_rratio 0.2)
      (net 19 "PS_1V0") (pintype "passive"))
  )

  (footprint "kria-k26-devboard-footprints:C_0402_1005Metric" (layer "B.Cu")
    (at 127.66 86.12 180)
    (descr "Capacitor SMD 0402")
    (tags "capacitor SMD 0402")
    (property "Author" "Antmicro")
    (property "Dielectric" "X5R")
    (property "License" "Apache-2.0")
    (property "MPN" "GRM155R61H104KE14D")
    (property "Manufacturer" "Murata")
    (property "Sheetfile" "usb.kicad_sch")
    (property "Sheetname" "USB")
    (property "Val" "100n")
    (property "Voltage" "50V")
    (property "ki_description" " ")
    (attr smd)
    (fp_text reference "C44" (at 0.901 -0.38) (layer "B.SilkS")
        (effects (font (size 0.7 0.7) (thickness 0.15)) (justify left bottom mirror))
    )
    (fp_text value "C_100n_0402" (at 0 -1.4) (layer "B.Fab") hide
        (effects (font (size 0.7 0.7) (thickness 0.15)) (justify left bottom mirror))
    )
    (fp_text user "${REFERENCE}" (at -0.932 -3.168) (layer "B.Fab") hide
        (effects (font (size 0.7 0.7) (thickness 0.15)) (justify left bottom mirror))
    )
    (fp_text user "Author: Antmicro" (at -0.932 -4.17) (layer "B.Fab") hide
        (effects (font (size 0.7 0.7) (thickness 0.15)) (justify left bottom mirror))
    )
    (fp_text user "License: Apache-2.0" (at -0.932 -5.17) (layer "B.Fab") hide
        (effects (font (size 0.7 0.7) (thickness 0.15)) (justify left bottom mirror))
    )
    (fp_rect (start -0.94 0.47) (end 0.94 -0.47)
      (stroke (width 0.05) (type solid)) (fill none) (layer "B.CrtYd"))
    (fp_rect (start -0.499 0.249) (end 0.499 -0.249)
      (stroke (width 0.15) (type solid)) (fill none) (layer "B.Fab"))
    (pad "1" smd roundrect (at -0.484 0 180) (size 0.59 0.64) (layers "B.Cu" "B.Paste" "B.Mask") (roundrect_rratio 0.25)
      (net 18 "PS_1V2") (pintype "passive"))
    (pad "2" smd roundrect (at 0.484 0 180) (size 0.59 0.64) (layers "B.Cu" "B.Paste" "B.Mask") (roundrect_rratio 0.25)
      (net 1 "GND") (pintype "passive"))
  )

  (footprint "kria-k26-devboard-footprints:C_0402_1005Metric" (layer "B.Cu")
    (at 116.606942 83.4)
    (descr "Capacitor SMD 0402")
    (tags "capacitor SMD 0402")
    (property "Author" "Antmicro")
    (property "Dielectric" "X5R")
    (property "License" "Apache-2.0")
    (property "MPN" "GRM155R61H104KE14D")
    (property "Manufacturer" "Murata")
    (property "Sheetfile" "usb.kicad_sch")
    (property "Sheetname" "USB")
    (property "Val" "100n")
    (property "Voltage" "50V")
    (property "ki_description" " ")
    (attr smd)
    (fp_text reference "C62" (at -0.896942 0.34 180) (layer "B.SilkS")
        (effects (font (size 0.7 0.7) (thickness 0.15)) (justify left bottom mirror))
    )
    (fp_text value "C_100n_0402" (at 0 -1.4 180) (layer "B.Fab") hide
        (effects (font (size 0.7 0.7) (thickness 0.15)) (justify left bottom mirror))
    )
    (fp_text user "License: Apache-2.0" (at -0.932 -5.17 180) (layer "B.Fab") hide
        (effects (font (size 0.7 0.7) (thickness 0.15)) (justify left bottom mirror))
    )
    (fp_text user "${REFERENCE}" (at -0.932 -3.168 180) (layer "B.Fab") hide
        (effects (font (size 0.7 0.7) (thickness 0.15)) (justify left bottom mirror))
    )
    (fp_text user "Author: Antmicro" (at -0.932 -4.17 180) (layer "B.Fab") hide
        (effects (font (size 0.7 0.7) (thickness 0.15)) (justify left bottom mirror))
    )
    (fp_rect (start -0.94 0.47) (end 0.94 -0.47)
      (stroke (width 0.05) (type solid)) (fill none) (layer "B.CrtYd"))
    (fp_rect (start -0.499 0.249) (end 0.499 -0.249)
      (stroke (width 0.15) (type solid)) (fill none) (layer "B.Fab"))
    (pad "1" smd roundrect (at -0.484 0) (size 0.59 0.64) (layers "B.Cu" "B.Paste" "B.Mask") (roundrect_rratio 0.25)
      (net 15 "PS_3V3") (pintype "passive"))
    (pad "2" smd roundrect (at 0.484 0) (size 0.59 0.64) (layers "B.Cu" "B.Paste" "B.Mask") (roundrect_rratio 0.25)
      (net 1 "GND") (pintype "passive"))
  )

  (footprint "kria-k26-devboard-footprints:C_0402_1005Metric" (layer "B.Cu")
    (at 127.666942 82.524862 180)
    (descr "Capacitor SMD 0402")
    (tags "capacitor SMD 0402")
    (property "Author" "Antmicro")
    (property "Dielectric" "X5R")
    (property "License" "Apache-2.0")
    (property "MPN" "GRM155R61H104KE14D")
    (property "Manufacturer" "Murata")
    (property "Sheetfile" "usb.kicad_sch")
    (property "Sheetname" "USB")
    (property "Val" "100n")
    (property "Voltage" "50V")
    (property "ki_description" " ")
    (attr smd)
    (fp_text reference "C48" (at 0.866942 -0.365138) (layer "B.SilkS")
        (effects (font (size 0.7 0.7) (thickness 0.15)) (justify left bottom mirror))
    )
    (fp_text value "C_100n_0402" (at 0 -1.4) (layer "B.Fab") hide
        (effects (font (size 0.7 0.7) (thickness 0.15)) (justify left bottom mirror))
    )
    (fp_text user "License: Apache-2.0" (at -0.932 -5.17) (layer "B.Fab") hide
        (effects (font (size 0.7 0.7) (thickness 0.15)) (justify left bottom mirror))
    )
    (fp_text user "${REFERENCE}" (at -0.932 -3.168) (layer "B.Fab") hide
        (effects (font (size 0.7 0.7) (thickness 0.15)) (justify left bottom mirror))
    )
    (fp_text user "Author: Antmicro" (at -0.932 -4.17) (layer "B.Fab") hide
        (effects (font (size 0.7 0.7) (thickness 0.15)) (justify left bottom mirror))
    )
    (fp_rect (start -0.94 0.47) (end 0.94 -0.47)
      (stroke (width 0.05) (type solid)) (fill none) (layer "B.CrtYd"))
    (fp_rect (start -0.499 0.249) (end 0.499 -0.249)
      (stroke (width 0.15) (type solid)) (fill none) (layer "B.Fab"))
    (pad "1" smd roundrect (at -0.484 0 180) (size 0.59 0.64) (layers "B.Cu" "B.Paste" "B.Mask") (roundrect_rratio 0.25)
      (net 18 "PS_1V2") (pintype "passive"))
    (pad "2" smd roundrect (at 0.484 0 180) (size 0.59 0.64) (layers "B.Cu" "B.Paste" "B.Mask") (roundrect_rratio 0.25)
      (net 1 "GND") (pintype "passive"))
  )

  (footprint "kria-k26-devboard-footprints:C_0402_1005Metric" (layer "B.Cu")
    (at 116.656942 80.5)
    (descr "Capacitor SMD 0402")
    (tags "capacitor SMD 0402")
    (property "Author" "Antmicro")
    (property "Dielectric" "X5R")
    (property "License" "Apache-2.0")
    (property "MPN" "GRM155R61H104KE14D")
    (property "Manufacturer" "Murata")
    (property "Sheetfile" "usb.kicad_sch")
    (property "Sheetname" "USB")
    (property "Val" "100n")
    (property "Voltage" "50V")
    (property "ki_description" " ")
    (attr smd)
    (fp_text reference "C58" (at -0.916942 0.43 180) (layer "B.SilkS")
        (effects (font (size 0.7 0.7) (thickness 0.15)) (justify left bottom mirror))
    )
    (fp_text value "C_100n_0402" (at 0 -1.4 180) (layer "B.Fab") hide
        (effects (font (size 0.7 0.7) (thickness 0.15)) (justify left bottom mirror))
    )
    (fp_text user "License: Apache-2.0" (at -0.932 -5.17 180) (layer "B.Fab") hide
        (effects (font (size 0.7 0.7) (thickness 0.15)) (justify left bottom mirror))
    )
    (fp_text user "Author: Antmicro" (at -0.932 -4.17 180) (layer "B.Fab") hide
        (effects (font (size 0.7 0.7) (thickness 0.15)) (justify left bottom mirror))
    )
    (fp_text user "${REFERENCE}" (at -0.932 -3.168 180) (layer "B.Fab") hide
        (effects (font (size 0.7 0.7) (thickness 0.15)) (justify left bottom mirror))
    )
    (fp_rect (start -0.94 0.47) (end 0.94 -0.47)
      (stroke (width 0.05) (type solid)) (fill none) (layer "B.CrtYd"))
    (fp_rect (start -0.499 0.249) (end 0.499 -0.249)
      (stroke (width 0.15) (type solid)) (fill none) (layer "B.Fab"))
    (pad "1" smd roundrect (at -0.484 0) (size 0.59 0.64) (layers "B.Cu" "B.Paste" "B.Mask") (roundrect_rratio 0.25)
      (net 15 "PS_3V3") (pintype "passive"))
    (pad "2" smd roundrect (at 0.484 0) (size 0.59 0.64) (layers "B.Cu" "B.Paste" "B.Mask") (roundrect_rratio 0.25)
      (net 1 "GND") (pintype "passive"))
  )

  (footprint "kria-k26-devboard-footprints:C_0402_1005Metric" (layer "B.Cu")
    (at 120.7 90 90)
    (descr "Capacitor SMD 0402")
    (tags "capacitor SMD 0402")
    (property "Author" "Antmicro")
    (property "Dielectric" "X5R")
    (property "License" "Apache-2.0")
    (property "MPN" "GRM155R61H104KE14D")
    (property "Manufacturer" "Murata")
    (property "Sheetfile" "usb.kicad_sch")
    (property "Sheetname" "USB")
    (property "Val" "100n")
    (property "Voltage" "50V")
    (property "ki_description" " ")
    (attr smd)
    (fp_text reference "C57" (at -0.84 0.39 270) (layer "B.SilkS")
        (effects (font (size 0.7 0.7) (thickness 0.15)) (justify left bottom mirror))
    )
    (fp_text value "C_100n_0402" (at 0 -1.4 270) (layer "B.Fab") hide
        (effects (font (size 0.7 0.7) (thickness 0.15)) (justify left bottom mirror))
    )
    (fp_text user "${REFERENCE}" (at -0.932 -3.168 270) (layer "B.Fab") hide
        (effects (font (size 0.7 0.7) (thickness 0.15)) (justify left bottom mirror))
    )
    (fp_text user "License: Apache-2.0" (at -0.932 -5.17 270) (layer "B.Fab") hide
        (effects (font (size 0.7 0.7) (thickness 0.15)) (justify left bottom mirror))
    )
    (fp_text user "Author: Antmicro" (at -0.932 -4.17 270) (layer "B.Fab") hide
        (effects (font (size 0.7 0.7) (thickness 0.15)) (justify left bottom mirror))
    )
    (fp_rect (start -0.94 0.47) (end 0.94 -0.47)
      (stroke (width 0.05) (type solid)) (fill none) (layer "B.CrtYd"))
    (fp_rect (start -0.499 0.249) (end 0.499 -0.249)
      (stroke (width 0.15) (type solid)) (fill none) (layer "B.Fab"))
    (pad "1" smd roundrect (at -0.484 0 90) (size 0.59 0.64) (layers "B.Cu" "B.Paste" "B.Mask") (roundrect_rratio 0.25)
      (net 18 "PS_1V2") (pintype "passive"))
    (pad "2" smd roundrect (at 0.484 0 90) (size 0.59 0.64) (layers "B.Cu" "B.Paste" "B.Mask") (roundrect_rratio 0.25)
      (net 1 "GND") (pintype "passive"))
  )

  (footprint "kria-k26-devboard-footprints:C_0402_1005Metric" (layer "B.Cu")
    (at 117.95 90.35 90)
    (descr "Capacitor SMD 0402")
    (tags "capacitor SMD 0402")
    (property "Author" "Antmicro")
    (property "Dielectric" "X5R")
    (property "License" "Apache-2.0")
    (property "MPN" "GRM155R61H104KE14D")
    (property "Manufacturer" "Murata")
    (property "Sheetfile" "usb.kicad_sch")
    (property "Sheetname" "USB")
    (property "Val" "100n")
    (property "Voltage" "50V")
    (property "ki_description" " ")
    (attr smd)
    (fp_text reference "C49" (at 0.5 -1.52 270) (layer "B.SilkS")
        (effects (font (size 0.7 0.7) (thickness 0.15)) (justify left bottom mirror))
    )
    (fp_text value "C_100n_0402" (at 0 -1.4 270) (layer "B.Fab") hide
        (effects (font (size 0.7 0.7) (thickness 0.15)) (justify left bottom mirror))
    )
    (fp_text user "Author: Antmicro" (at -0.932 -4.17 270) (layer "B.Fab") hide
        (effects (font (size 0.7 0.7) (thickness 0.15)) (justify left bottom mirror))
    )
    (fp_text user "${REFERENCE}" (at -0.932 -3.168 270) (layer "B.Fab") hide
        (effects (font (size 0.7 0.7) (thickness 0.15)) (justify left bottom mirror))
    )
    (fp_text user "License: Apache-2.0" (at -0.932 -5.17 270) (layer "B.Fab") hide
        (effects (font (size 0.7 0.7) (thickness 0.15)) (justify left bottom mirror))
    )
    (fp_rect (start -0.94 0.47) (end 0.94 -0.47)
      (stroke (width 0.05) (type solid)) (fill none) (layer "B.CrtYd"))
    (fp_rect (start -0.499 0.249) (end 0.499 -0.249)
      (stroke (width 0.15) (type solid)) (fill none) (layer "B.Fab"))
    (pad "1" smd roundrect (at -0.484 0 90) (size 0.59 0.64) (layers "B.Cu" "B.Paste" "B.Mask") (roundrect_rratio 0.25)
      (net 18 "PS_1V2") (pintype "passive"))
    (pad "2" smd roundrect (at 0.484 0 90) (size 0.59 0.64) (layers "B.Cu" "B.Paste" "B.Mask") (roundrect_rratio 0.25)
      (net 1 "GND") (pintype "passive"))
  )

  (footprint "kria-k26-devboard-footprints:C_0402_1005Metric" (layer "B.Cu")
    (at 124.906941 80.8 -90)
    (descr "Capacitor SMD 0402")
    (tags "capacitor SMD 0402")
    (property "Author" "Antmicro")
    (property "Dielectric" "X5R")
    (property "License" "Apache-2.0")
    (property "MPN" "GRM155R61H104KE14D")
    (property "Manufacturer" "Murata")
    (property "Sheetfile" "usb.kicad_sch")
    (property "Sheetname" "USB")
    (property "Val" "100n")
    (property "Voltage" "50V")
    (property "ki_description" " ")
    (attr smd)
    (fp_text reference "C60" (at -3.05 -0.443059 90) (layer "B.SilkS")
        (effects (font (size 0.7 0.7) (thickness 0.15)) (justify left bottom mirror))
    )
    (fp_text value "C_100n_0402" (at 0 -1.4 90) (layer "B.Fab") hide
        (effects (font (size 0.7 0.7) (thickness 0.15)) (justify left bottom mirror))
    )
    (fp_text user "License: Apache-2.0" (at -0.932 -5.17 90) (layer "B.Fab") hide
        (effects (font (size 0.7 0.7) (thickness 0.15)) (justify left bottom mirror))
    )
    (fp_text user "${REFERENCE}" (at -0.932 -3.168 90) (layer "B.Fab") hide
        (effects (font (size 0.7 0.7) (thickness 0.15)) (justify left bottom mirror))
    )
    (fp_text user "Author: Antmicro" (at -0.932 -4.17 90) (layer "B.Fab") hide
        (effects (font (size 0.7 0.7) (thickness 0.15)) (justify left bottom mirror))
    )
    (fp_rect (start -0.94 0.47) (end 0.94 -0.47)
      (stroke (width 0.05) (type solid)) (fill none) (layer "B.CrtYd"))
    (fp_rect (start -0.499 0.249) (end 0.499 -0.249)
      (stroke (width 0.15) (type solid)) (fill none) (layer "B.Fab"))
    (pad "1" smd roundrect (at -0.484 0 270) (size 0.59 0.64) (layers "B.Cu" "B.Paste" "B.Mask") (roundrect_rratio 0.25)
      (net 18 "PS_1V2") (pintype "passive"))
    (pad "2" smd roundrect (at 0.484 0 270) (size 0.59 0.64) (layers "B.Cu" "B.Paste" "B.Mask") (roundrect_rratio 0.25)
      (net 1 "GND") (pintype "passive"))
  )

  (footprint "kria-k26-devboard-footprints:C_0402_1005Metric" (layer "B.Cu")
    (at 122.125 80.8 -90)
    (descr "Capacitor SMD 0402")
    (tags "capacitor SMD 0402")
    (property "Author" "Antmicro")
    (property "Dielectric" "X5R")
    (property "License" "Apache-2.0")
    (property "MPN" "GRM155R61H104KE14D")
    (property "Manufacturer" "Murata")
    (property "Sheetfile" "usb.kicad_sch")
    (property "Sheetname" "USB")
    (property "Val" "100n")
    (property "Voltage" "50V")
    (property "ki_description" " ")
    (attr smd)
    (fp_text reference "C41" (at -3.04 -0.385 90) (layer "B.SilkS")
        (effects (font (size 0.7 0.7) (thickness 0.15)) (justify left bottom mirror))
    )
    (fp_text value "C_100n_0402" (at 0 -1.4 90) (layer "B.Fab") hide
        (effects (font (size 0.7 0.7) (thickness 0.15)) (justify left bottom mirror))
    )
    (fp_text user "Author: Antmicro" (at -0.932 -4.17 90) (layer "B.Fab") hide
        (effects (font (size 0.7 0.7) (thickness 0.15)) (justify left bottom mirror))
    )
    (fp_text user "${REFERENCE}" (at -0.932 -3.168 90) (layer "B.Fab") hide
        (effects (font (size 0.7 0.7) (thickness 0.15)) (justify left bottom mirror))
    )
    (fp_text user "License: Apache-2.0" (at -0.932 -5.17 90) (layer "B.Fab") hide
        (effects (font (size 0.7 0.7) (thickness 0.15)) (justify left bottom mirror))
    )
    (fp_rect (start -0.94 0.47) (end 0.94 -0.47)
      (stroke (width 0.05) (type solid)) (fill none) (layer "B.CrtYd"))
    (fp_rect (start -0.499 0.249) (end 0.499 -0.249)
      (stroke (width 0.15) (type solid)) (fill none) (layer "B.Fab"))
    (pad "1" smd roundrect (at -0.484 0 270) (size 0.59 0.64) (layers "B.Cu" "B.Paste" "B.Mask") (roundrect_rratio 0.25)
      (net 18 "PS_1V2") (pintype "passive"))
    (pad "2" smd roundrect (at 0.484 0 270) (size 0.59 0.64) (layers "B.Cu" "B.Paste" "B.Mask") (roundrect_rratio 0.25)
      (net 1 "GND") (pintype "passive"))
  )

  (footprint "kria-k26-devboard-footprints:C_0402_1005Metric" (layer "B.Cu")
    (at 95.1 75.5)
    (descr "Capacitor SMD 0402")
    (tags "capacitor SMD 0402")
    (property "Author" "Antmicro")
    (property "Dielectric" "X5R")
    (property "License" "Apache-2.0")
    (property "MPN" "GRM155R61H104KE14D")
    (property "Manufacturer" "Murata")
    (property "Sheetfile" "dp.kicad_sch")
    (property "Sheetname" "Display Port")
    (property "Val" "100n")
    (property "Voltage" "50V")
    (property "ki_description" " ")
    (attr smd)
    (fp_text reference "C5" (at 0.8 -0.55 180) (layer "B.SilkS")
        (effects (font (size 0.7 0.7) (thickness 0.15)) (justify left bottom mirror))
    )
    (fp_text value "C_100n_0402" (at 0 -1.4 180) (layer "B.Fab") hide
        (effects (font (size 0.7 0.7) (thickness 0.15)) (justify left bottom mirror))
    )
    (fp_text user "License: Apache-2.0" (at -0.932 -5.17 180) (layer "B.Fab") hide
        (effects (font (size 0.7 0.7) (thickness 0.15)) (justify left bottom mirror))
    )
    (fp_text user "${REFERENCE}" (at -0.932 -3.168 180) (layer "B.Fab") hide
        (effects (font (size 0.7 0.7) (thickness 0.15)) (justify left bottom mirror))
    )
    (fp_text user "Author: Antmicro" (at -0.932 -4.17 180) (layer "B.Fab") hide
        (effects (font (size 0.7 0.7) (thickness 0.15)) (justify left bottom mirror))
    )
    (fp_rect (start -0.94 0.47) (end 0.94 -0.47)
      (stroke (width 0.05) (type solid)) (fill none) (layer "B.CrtYd"))
    (fp_rect (start -0.499 0.249) (end 0.499 -0.249)
      (stroke (width 0.15) (type solid)) (fill none) (layer "B.Fab"))
    (pad "1" smd roundrect (at -0.484 0) (size 0.59 0.64) (layers "B.Cu" "B.Paste" "B.Mask") (roundrect_rratio 0.25)
      (net 15 "PS_3V3") (pintype "passive"))
    (pad "2" smd roundrect (at 0.484 0) (size 0.59 0.64) (layers "B.Cu" "B.Paste" "B.Mask") (roundrect_rratio 0.25)
      (net 1 "GND") (pintype "passive"))
  )

  (footprint "kria-k26-devboard-footprints:C_0402_1005Metric" (layer "B.Cu")
    (at 131.35 63.741421 90)
    (descr "Capacitor SMD 0402")
    (tags "capacitor SMD 0402")
    (property "Author" "Antmicro")
    (property "Dielectric" "X5R")
    (property "License" "Apache-2.0")
    (property "MPN" "GRM155R61H104KE14D")
    (property "Manufacturer" "Murata")
    (property "Sheetfile" "usb.kicad_sch")
    (property "Sheetname" "USB")
    (property "Val" "100n")
    (property "Voltage" "50V")
    (property "ki_description" " ")
    (attr smd)
    (fp_text reference "C75" (at 3.781421 0.36 270) (layer "B.SilkS")
        (effects (font (size 0.7 0.7) (thickness 0.15)) (justify left bottom mirror))
    )
    (fp_text value "C_100n_0402" (at 0 -1.4 270) (layer "B.Fab") hide
        (effects (font (size 0.7 0.7) (thickness 0.15)) (justify left bottom mirror))
    )
    (fp_text user "License: Apache-2.0" (at -0.932 -5.17 270) (layer "B.Fab") hide
        (effects (font (size 0.7 0.7) (thickness 0.15)) (justify left bottom mirror))
    )
    (fp_text user "Author: Antmicro" (at -0.932 -4.17 270) (layer "B.Fab") hide
        (effects (font (size 0.7 0.7) (thickness 0.15)) (justify left bottom mirror))
    )
    (fp_text user "${REFERENCE}" (at -0.932 -3.168 270) (layer "B.Fab") hide
        (effects (font (size 0.7 0.7) (thickness 0.15)) (justify left bottom mirror))
    )
    (fp_rect (start -0.94 0.47) (end 0.94 -0.47)
      (stroke (width 0.05) (type solid)) (fill none) (layer "B.CrtYd"))
    (fp_rect (start -0.499 0.249) (end 0.499 -0.249)
      (stroke (width 0.15) (type solid)) (fill none) (layer "B.Fab"))
    (pad "1" smd roundrect (at -0.484 0 90) (size 0.59 0.64) (layers "B.Cu" "B.Paste" "B.Mask") (roundrect_rratio 0.25)
      (net 64 "/USB/USB1_VBUS") (pintype "passive"))
    (pad "2" smd roundrect (at 0.484 0 90) (size 0.59 0.64) (layers "B.Cu" "B.Paste" "B.Mask") (roundrect_rratio 0.25)
      (net 1 "GND") (pintype "passive"))
  )

  (footprint "kria-k26-devboard-footprints:C_0402_1005Metric" (layer "B.Cu")
    (at 111.95 63.8 90)
    (descr "Capacitor SMD 0402")
    (tags "capacitor SMD 0402")
    (property "Author" "Antmicro")
    (property "Dielectric" "")
    (property "License" "Apache-2.0")
    (property "MPN" "CC0402MRX5R5BB106")
    (property "Manufacturer" "Yaego")
    (property "Sheetfile" "usb.kicad_sch")
    (property "Sheetname" "USB")
    (property "Val" "10u")
    (property "Voltage" "")
    (property "ki_description" " ")
    (attr smd)
    (fp_text reference "C81" (at 3.13 0.41 270) (layer "B.SilkS")
        (effects (font (size 0.7 0.7) (thickness 0.15)) (justify left bottom mirror))
    )
    (fp_text value "C_10u_0402" (at 0 -1.4 270) (layer "B.Fab") hide
        (effects (font (size 0.7 0.7) (thickness 0.15)) (justify left bottom mirror))
    )
    (fp_text user "Author: Antmicro" (at -0.932 -4.17 270) (layer "B.Fab") hide
        (effects (font (size 0.7 0.7) (thickness 0.15)) (justify left bottom mirror))
    )
    (fp_text user "License: Apache-2.0" (at -0.932 -5.17 270) (layer "B.Fab") hide
        (effects (font (size 0.7 0.7) (thickness 0.15)) (justify left bottom mirror))
    )
    (fp_text user "${REFERENCE}" (at -0.932 -3.168 270) (layer "B.Fab") hide
        (effects (font (size 0.7 0.7) (thickness 0.15)) (justify left bottom mirror))
    )
    (fp_rect (start -0.94 0.47) (end 0.94 -0.47)
      (stroke (width 0.05) (type solid)) (fill none) (layer "B.CrtYd"))
    (fp_rect (start -0.499 0.249) (end 0.499 -0.249)
      (stroke (width 0.15) (type solid)) (fill none) (layer "B.Fab"))
    (pad "1" smd roundrect (at -0.484 0 90) (size 0.59 0.64) (layers "B.Cu" "B.Paste" "B.Mask") (roundrect_rratio 0.25)
      (net 86 "/USB/USB3_VBUS") (pintype "passive"))
    (pad "2" smd roundrect (at 0.484 0 90) (size 0.59 0.64) (layers "B.Cu" "B.Paste" "B.Mask") (roundrect_rratio 0.25)
      (net 1 "GND") (pintype "passive"))
  )

  (footprint "kria-k26-devboard-footprints:C_0402_1005Metric" (layer "B.Cu")
    (at 137.75 67.55)
    (descr "Capacitor SMD 0402")
    (tags "capacitor SMD 0402")
    (property "Author" "Antmicro")
    (property "Dielectric" "X5R")
    (property "License" "Apache-2.0")
    (property "MPN" "GRM155R61H104KE14D")
    (property "Manufacturer" "Murata")
    (property "Sheetfile" "usb.kicad_sch")
    (property "Sheetname" "USB")
    (property "Val" "100n")
    (property "Voltage" "50V")
    (property "ki_description" " ")
    (attr smd)
    (fp_text reference "C74" (at 3.04 0.35 180) (layer "B.SilkS")
        (effects (font (size 0.7 0.7) (thickness 0.15)) (justify left bottom mirror))
    )
    (fp_text value "C_100n_0402" (at 0 -1.4 180) (layer "B.Fab") hide
        (effects (font (size 0.7 0.7) (thickness 0.15)) (justify left bottom mirror))
    )
    (fp_text user "Author: Antmicro" (at -0.932 -4.17 180) (layer "B.Fab") hide
        (effects (font (size 0.7 0.7) (thickness 0.15)) (justify left bottom mirror))
    )
    (fp_text user "License: Apache-2.0" (at -0.932 -5.17 180) (layer "B.Fab") hide
        (effects (font (size 0.7 0.7) (thickness 0.15)) (justify left bottom mirror))
    )
    (fp_text user "${REFERENCE}" (at -0.932 -3.168 180) (layer "B.Fab") hide
        (effects (font (size 0.7 0.7) (thickness 0.15)) (justify left bottom mirror))
    )
    (fp_rect (start -0.94 0.47) (end 0.94 -0.47)
      (stroke (width 0.05) (type solid)) (fill none) (layer "B.CrtYd"))
    (fp_rect (start -0.499 0.249) (end 0.499 -0.249)
      (stroke (width 0.15) (type solid)) (fill none) (layer "B.Fab"))
    (pad "1" smd roundrect (at -0.484 0) (size 0.59 0.64) (layers "B.Cu" "B.Paste" "B.Mask") (roundrect_rratio 0.25)
      (net 85 "/USB/USB2_VBUS") (pintype "passive"))
    (pad "2" smd roundrect (at 0.484 0) (size 0.59 0.64) (layers "B.Cu" "B.Paste" "B.Mask") (roundrect_rratio 0.25)
      (net 1 "GND") (pintype "passive"))
  )

  (footprint "kria-k26-devboard-footprints:C_0402_1005Metric" (layer "B.Cu")
    (at 118.35 65.55)
    (descr "Capacitor SMD 0402")
    (tags "capacitor SMD 0402")
    (property "Author" "Antmicro")
    (property "Dielectric" "")
    (property "License" "Apache-2.0")
    (property "MPN" "CC0402MRX5R5BB106")
    (property "Manufacturer" "Yaego")
    (property "Sheetfile" "usb.kicad_sch")
    (property "Sheetname" "USB")
    (property "Val" "10u")
    (property "Voltage" "")
    (property "ki_description" " ")
    (attr smd)
    (fp_text reference "C82" (at 3.04 0.32 180) (layer "B.SilkS")
        (effects (font (size 0.7 0.7) (thickness 0.15)) (justify left bottom mirror))
    )
    (fp_text value "C_10u_0402" (at 0 -1.4 180) (layer "B.Fab") hide
        (effects (font (size 0.7 0.7) (thickness 0.15)) (justify left bottom mirror))
    )
    (fp_text user "License: Apache-2.0" (at -0.932 -5.17 180) (layer "B.Fab") hide
        (effects (font (size 0.7 0.7) (thickness 0.15)) (justify left bottom mirror))
    )
    (fp_text user "Author: Antmicro" (at -0.932 -4.17 180) (layer "B.Fab") hide
        (effects (font (size 0.7 0.7) (thickness 0.15)) (justify left bottom mirror))
    )
    (fp_text user "${REFERENCE}" (at -0.932 -3.168 180) (layer "B.Fab") hide
        (effects (font (size 0.7 0.7) (thickness 0.15)) (justify left bottom mirror))
    )
    (fp_rect (start -0.94 0.47) (end 0.94 -0.47)
      (stroke (width 0.05) (type solid)) (fill none) (layer "B.CrtYd"))
    (fp_rect (start -0.499 0.249) (end 0.499 -0.249)
      (stroke (width 0.15) (type solid)) (fill none) (layer "B.Fab"))
    (pad "1" smd roundrect (at -0.484 0) (size 0.59 0.64) (layers "B.Cu" "B.Paste" "B.Mask") (roundrect_rratio 0.25)
      (net 87 "/USB/USB4_VBUS") (pintype "passive"))
    (pad "2" smd roundrect (at 0.484 0) (size 0.59 0.64) (layers "B.Cu" "B.Paste" "B.Mask") (roundrect_rratio 0.25)
      (net 1 "GND") (pintype "passive"))
  )

  (footprint "kria-k26-devboard-footprints:C_0402_1005Metric" (layer "B.Cu")
    (at 112.95 63.8 90)
    (descr "Capacitor SMD 0402")
    (tags "capacitor SMD 0402")
    (property "Author" "Antmicro")
    (property "Dielectric" "X5R")
    (property "License" "Apache-2.0")
    (property "MPN" "GRM155R61H104KE14D")
    (property "Manufacturer" "Murata")
    (property "Sheetfile" "usb.kicad_sch")
    (property "Sheetname" "USB")
    (property "Val" "100n")
    (property "Voltage" "50V")
    (property "ki_description" " ")
    (attr smd)
    (fp_text reference "C87" (at 3.13 0.41 270) (layer "B.SilkS")
        (effects (font (size 0.7 0.7) (thickness 0.15)) (justify left bottom mirror))
    )
    (fp_text value "C_100n_0402" (at 0 -1.4 270) (layer "B.Fab") hide
        (effects (font (size 0.7 0.7) (thickness 0.15)) (justify left bottom mirror))
    )
    (fp_text user "License: Apache-2.0" (at -0.932 -5.17 270) (layer "B.Fab") hide
        (effects (font (size 0.7 0.7) (thickness 0.15)) (justify left bottom mirror))
    )
    (fp_text user "Author: Antmicro" (at -0.932 -4.17 270) (layer "B.Fab") hide
        (effects (font (size 0.7 0.7) (thickness 0.15)) (justify left bottom mirror))
    )
    (fp_text user "${REFERENCE}" (at -0.932 -3.168 270) (layer "B.Fab") hide
        (effects (font (size 0.7 0.7) (thickness 0.15)) (justify left bottom mirror))
    )
    (fp_rect (start -0.94 0.47) (end 0.94 -0.47)
      (stroke (width 0.05) (type solid)) (fill none) (layer "B.CrtYd"))
    (fp_rect (start -0.499 0.249) (end 0.499 -0.249)
      (stroke (width 0.15) (type solid)) (fill none) (layer "B.Fab"))
    (pad "1" smd roundrect (at -0.484 0 90) (size 0.59 0.64) (layers "B.Cu" "B.Paste" "B.Mask") (roundrect_rratio 0.25)
      (net 86 "/USB/USB3_VBUS") (pintype "passive"))
    (pad "2" smd roundrect (at 0.484 0 90) (size 0.59 0.64) (layers "B.Cu" "B.Paste" "B.Mask") (roundrect_rratio 0.25)
      (net 1 "GND") (pintype "passive"))
  )

  (footprint "kria-k26-devboard-footprints:C_0402_1005Metric" (layer "B.Cu")
    (at 137.75 66.55)
    (descr "Capacitor SMD 0402")
    (tags "capacitor SMD 0402")
    (property "Author" "Antmicro")
    (property "Dielectric" "")
    (property "License" "Apache-2.0")
    (property "MPN" "CC0402MRX5R5BB106")
    (property "Manufacturer" "Yaego")
    (property "Sheetfile" "usb.kicad_sch")
    (property "Sheetname" "USB")
    (property "Val" "10u")
    (property "Voltage" "")
    (property "ki_description" " ")
    (attr smd)
    (fp_text reference "C70" (at 3.04 0.35 180) (layer "B.SilkS")
        (effects (font (size 0.7 0.7) (thickness 0.15)) (justify left bottom mirror))
    )
    (fp_text value "C_10u_0402" (at 0 -1.4 180) (layer "B.Fab") hide
        (effects (font (size 0.7 0.7) (thickness 0.15)) (justify left bottom mirror))
    )
    (fp_text user "License: Apache-2.0" (at -0.932 -5.17 180) (layer "B.Fab") hide
        (effects (font (size 0.7 0.7) (thickness 0.15)) (justify left bottom mirror))
    )
    (fp_text user "${REFERENCE}" (at -0.932 -3.168 180) (layer "B.Fab") hide
        (effects (font (size 0.7 0.7) (thickness 0.15)) (justify left bottom mirror))
    )
    (fp_text user "Author: Antmicro" (at -0.932 -4.17 180) (layer "B.Fab") hide
        (effects (font (size 0.7 0.7) (thickness 0.15)) (justify left bottom mirror))
    )
    (fp_rect (start -0.94 0.47) (end 0.94 -0.47)
      (stroke (width 0.05) (type solid)) (fill none) (layer "B.CrtYd"))
    (fp_rect (start -0.499 0.249) (end 0.499 -0.249)
      (stroke (width 0.15) (type solid)) (fill none) (layer "B.Fab"))
    (pad "1" smd roundrect (at -0.484 0) (size 0.59 0.64) (layers "B.Cu" "B.Paste" "B.Mask") (roundrect_rratio 0.25)
      (net 85 "/USB/USB2_VBUS") (pintype "passive"))
    (pad "2" smd roundrect (at 0.484 0) (size 0.59 0.64) (layers "B.Cu" "B.Paste" "B.Mask") (roundrect_rratio 0.25)
      (net 1 "GND") (pintype "passive"))
  )

  (footprint "kria-k26-devboard-footprints:C_0402_1005Metric" (layer "B.Cu")
    (at 118.35 66.550001)
    (descr "Capacitor SMD 0402")
    (tags "capacitor SMD 0402")
    (property "Author" "Antmicro")
    (property "Dielectric" "")
    (property "License" "Apache-2.0")
    (property "MPN" "CC0402MRX5R5BB106")
    (property "Manufacturer" "Yaego")
    (property "Sheetfile" "usb.kicad_sch")
    (property "Sheetname" "USB")
    (property "Val" "10u")
    (property "Voltage" "")
    (property "ki_description" " ")
    (attr smd)
    (fp_text reference "C85" (at 3.04 0.32 180) (layer "B.SilkS")
        (effects (font (size 0.7 0.7) (thickness 0.15)) (justify left bottom mirror))
    )
    (fp_text value "C_10u_0402" (at 0 -1.4 180) (layer "B.Fab") hide
        (effects (font (size 0.7 0.7) (thickness 0.15)) (justify left bottom mirror))
    )
    (fp_text user "${REFERENCE}" (at -0.932 -3.168 180) (layer "B.Fab") hide
        (effects (font (size 0.7 0.7) (thickness 0.15)) (justify left bottom mirror))
    )
    (fp_text user "Author: Antmicro" (at -0.932 -4.17 180) (layer "B.Fab") hide
        (effects (font (size 0.7 0.7) (thickness 0.15)) (justify left bottom mirror))
    )
    (fp_text user "License: Apache-2.0" (at -0.932 -5.17 180) (layer "B.Fab") hide
        (effects (font (size 0.7 0.7) (thickness 0.15)) (justify left bottom mirror))
    )
    (fp_rect (start -0.94 0.47) (end 0.94 -0.47)
      (stroke (width 0.05) (type solid)) (fill none) (layer "B.CrtYd"))
    (fp_rect (start -0.499 0.249) (end 0.499 -0.249)
      (stroke (width 0.15) (type solid)) (fill none) (layer "B.Fab"))
    (pad "1" smd roundrect (at -0.484 0) (size 0.59 0.64) (layers "B.Cu" "B.Paste" "B.Mask") (roundrect_rratio 0.25)
      (net 87 "/USB/USB4_VBUS") (pintype "passive"))
    (pad "2" smd roundrect (at 0.484 0) (size 0.59 0.64) (layers "B.Cu" "B.Paste" "B.Mask") (roundrect_rratio 0.25)
      (net 1 "GND") (pintype "passive"))
  )

  (footprint "kria-k26-devboard-footprints:C_0402_1005Metric" (layer "B.Cu")
    (at 113.95 63.8 90)
    (descr "Capacitor SMD 0402")
    (tags "capacitor SMD 0402")
    (property "Author" "Antmicro")
    (property "Dielectric" "")
    (property "License" "Apache-2.0")
    (property "MPN" "CC0402MRX5R5BB106")
    (property "Manufacturer" "Yaego")
    (property "Sheetfile" "usb.kicad_sch")
    (property "Sheetname" "USB")
    (property "Val" "10u")
    (property "Voltage" "")
    (property "ki_description" " ")
    (attr smd)
    (fp_text reference "C84" (at 3.13 0.41 270) (layer "B.SilkS")
        (effects (font (size 0.7 0.7) (thickness 0.15)) (justify left bottom mirror))
    )
    (fp_text value "C_10u_0402" (at 0 -1.4 270) (layer "B.Fab") hide
        (effects (font (size 0.7 0.7) (thickness 0.15)) (justify left bottom mirror))
    )
    (fp_text user "Author: Antmicro" (at -0.932 -4.17 270) (layer "B.Fab") hide
        (effects (font (size 0.7 0.7) (thickness 0.15)) (justify left bottom mirror))
    )
    (fp_text user "${REFERENCE}" (at -0.932 -3.168 270) (layer "B.Fab") hide
        (effects (font (size 0.7 0.7) (thickness 0.15)) (justify left bottom mirror))
    )
    (fp_text user "License: Apache-2.0" (at -0.932 -5.17 270) (layer "B.Fab") hide
        (effects (font (size 0.7 0.7) (thickness 0.15)) (justify left bottom mirror))
    )
    (fp_rect (start -0.94 0.47) (end 0.94 -0.47)
      (stroke (width 0.05) (type solid)) (fill none) (layer "B.CrtYd"))
    (fp_rect (start -0.499 0.249) (end 0.499 -0.249)
      (stroke (width 0.15) (type solid)) (fill none) (layer "B.Fab"))
    (pad "1" smd roundrect (at -0.484 0 90) (size 0.59 0.64) (layers "B.Cu" "B.Paste" "B.Mask") (roundrect_rratio 0.25)
      (net 86 "/USB/USB3_VBUS") (pintype "passive"))
    (pad "2" smd roundrect (at 0.484 0 90) (size 0.59 0.64) (layers "B.Cu" "B.Paste" "B.Mask") (roundrect_rratio 0.25)
      (net 1 "GND") (pintype "passive"))
  )

  (footprint "kria-k26-devboard-footprints:C_0402_1005Metric" (layer "B.Cu")
    (at 132.375736 63.741421 90)
    (descr "Capacitor SMD 0402")
    (tags "capacitor SMD 0402")
    (property "Author" "Antmicro")
    (property "Dielectric" "")
    (property "License" "Apache-2.0")
    (property "MPN" "CC0402MRX5R5BB106")
    (property "Manufacturer" "Yaego")
    (property "Sheetfile" "usb.kicad_sch")
    (property "Sheetname" "USB")
    (property "Val" "10u")
    (property "Voltage" "")
    (property "ki_description" " ")
    (attr smd)
    (fp_text reference "C72" (at 3.781421 0.36 270) (layer "B.SilkS")
        (effects (font (size 0.7 0.7) (thickness 0.15)) (justify left bottom mirror))
    )
    (fp_text value "C_10u_0402" (at 0 -1.4 270) (layer "B.Fab") hide
        (effects (font (size 0.7 0.7) (thickness 0.15)) (justify left bottom mirror))
    )
    (fp_text user "Author: Antmicro" (at -0.932 -4.17 270) (layer "B.Fab") hide
        (effects (font (size 0.7 0.7) (thickness 0.15)) (justify left bottom mirror))
    )
    (fp_text user "License: Apache-2.0" (at -0.932 -5.17 270) (layer "B.Fab") hide
        (effects (font (size 0.7 0.7) (thickness 0.15)) (justify left bottom mirror))
    )
    (fp_text user "${REFERENCE}" (at -0.932 -3.168 270) (layer "B.Fab") hide
        (effects (font (size 0.7 0.7) (thickness 0.15)) (justify left bottom mirror))
    )
    (fp_rect (start -0.94 0.47) (end 0.94 -0.47)
      (stroke (width 0.05) (type solid)) (fill none) (layer "B.CrtYd"))
    (fp_rect (start -0.499 0.249) (end 0.499 -0.249)
      (stroke (width 0.15) (type solid)) (fill none) (layer "B.Fab"))
    (pad "1" smd roundrect (at -0.484 0 90) (size 0.59 0.64) (layers "B.Cu" "B.Paste" "B.Mask") (roundrect_rratio 0.25)
      (net 64 "/USB/USB1_VBUS") (pintype "passive"))
    (pad "2" smd roundrect (at 0.484 0 90) (size 0.59 0.64) (layers "B.Cu" "B.Paste" "B.Mask") (roundrect_rratio 0.25)
      (net 1 "GND") (pintype "passive"))
  )

  (footprint "kria-k26-devboard-footprints:C_0402_1005Metric" (layer "B.Cu")
    (at 99.4 71.1 -90)
    (descr "Capacitor SMD 0402")
    (tags "capacitor SMD 0402")
    (property "Author" "Antmicro")
    (property "Dielectric" "X5R")
    (property "License" "Apache-2.0")
    (property "MPN" "GRM155R61H104KE14D")
    (property "Manufacturer" "Murata")
    (property "Sheetfile" "kria-k26-devboard.kicad_sch")
    (property "Sheetname" "")
    (property "Val" "100n")
    (property "Voltage" "50V")
    (property "ki_description" " ")
    (attr smd)
    (fp_text reference "C2" (at 0.91 -0.41 90) (layer "B.SilkS")
        (effects (font (size 0.7 0.7) (thickness 0.15)) (justify left bottom mirror))
    )
    (fp_text value "C_100n_0402" (at 0 -1.4 90) (layer "B.Fab") hide
        (effects (font (size 0.7 0.7) (thickness 0.15)) (justify left bottom mirror))
    )
    (fp_text user "${REFERENCE}" (at -0.932 -3.168 90) (layer "B.Fab") hide
        (effects (font (size 0.7 0.7) (thickness 0.15)) (justify left bottom mirror))
    )
    (fp_text user "Author: Antmicro" (at -0.932 -4.17 90) (layer "B.Fab") hide
        (effects (font (size 0.7 0.7) (thickness 0.15)) (justify left bottom mirror))
    )
    (fp_text user "License: Apache-2.0" (at -0.932 -5.17 90) (layer "B.Fab") hide
        (effects (font (size 0.7 0.7) (thickness 0.15)) (justify left bottom mirror))
    )
    (fp_rect (start -0.94 0.47) (end 0.94 -0.47)
      (stroke (width 0.05) (type solid)) (fill none) (layer "B.CrtYd"))
    (fp_rect (start -0.499 0.249) (end 0.499 -0.249)
      (stroke (width 0.15) (type solid)) (fill none) (layer "B.Fab"))
    (pad "1" smd roundrect (at -0.484 0 270) (size 0.59 0.64) (layers "B.Cu" "B.Paste" "B.Mask") (roundrect_rratio 0.25)
      (net 319 "SH_UP") (pintype "passive"))
    (pad "2" smd roundrect (at 0.484 0 270) (size 0.59 0.64) (layers "B.Cu" "B.Paste" "B.Mask") (roundrect_rratio 0.25)
      (net 1 "GND") (pintype "passive"))
  )

  (footprint "kria-k26-devboard-footprints:R_0402_1005Metric" (layer "B.Cu")
    (at 150.929289 146.887868)
    (descr "Resistor SMD 0402")
    (tags "resistor SMD 0402")
    (property "Author" "Antmicro")
    (property "License" "Apache-2.0")
    (property "MPN" "CR0402-FX-3300GLF")
    (property "Manufacturer" "Bourns")
    (property "Sheetfile" "kria-k26-devboard.kicad_sch")
    (property "Sheetname" "")
    (property "Tolerance" "1%")
    (property "Val" "330R")
    (property "ki_description" "330R resistor in 0402 package with 1% tolerance")
    (attr smd)
    (fp_text reference "R1" (at 2.360711 0.342132 180) (layer "B.SilkS")
        (effects (font (size 0.7 0.7) (thickness 0.15)) (justify left bottom mirror))
    )
    (fp_text value "R_330R_0402" (at 0 -1.4 180) (layer "B.Fab") hide
        (effects (font (size 0.7 0.7) (thickness 0.15)) (justify left bottom mirror))
    )
    (fp_text user "${REFERENCE}" (at -0.95 -3.168 180) (layer "B.Fab") hide
        (effects (font (size 0.7 0.7) (thickness 0.15)) (justify left bottom mirror))
    )
    (fp_text user "Author: Antmicro" (at -0.95 -4.169 180) (layer "B.Fab") hide
        (effects (font (size 0.7 0.7) (thickness 0.15)) (justify left bottom mirror))
    )
    (fp_text user "License: Apache-2.0" (at -0.95 -5.169 180) (layer "B.Fab") hide
        (effects (font (size 0.7 0.7) (thickness 0.15)) (justify left bottom mirror))
    )
    (fp_rect (start -0.93 0.47) (end 0.93 -0.47)
      (stroke (width 0.05) (type solid)) (fill none) (layer "B.CrtYd"))
    (fp_rect (start -0.5 0.25) (end 0.5 -0.25)
      (stroke (width 0.15) (type solid)) (fill none) (layer "B.Fab"))
    (pad "1" smd roundrect (at -0.485 0) (size 0.59 0.64) (layers "B.Cu" "B.Paste" "B.Mask") (roundrect_rratio 0.25)
      (net 318 "SH_DOWN") (pintype "passive"))
    (pad "2" smd roundrect (at 0.485 0) (size 0.59 0.64) (layers "B.Cu" "B.Paste" "B.Mask") (roundrect_rratio 0.25)
      (net 1 "GND") (pintype "passive"))
  )

  (footprint "kria-k26-devboard-footprints:R_0402_1005Metric" (layer "B.Cu")
    (at 100.35 71.1 -90)
    (descr "Resistor SMD 0402")
    (tags "resistor SMD 0402")
    (property "Author" "Antmicro")
    (property "License" "Apache-2.0")
    (property "MPN" "CR0402-FX-3300GLF")
    (property "Manufacturer" "Bourns")
    (property "Sheetfile" "kria-k26-devboard.kicad_sch")
    (property "Sheetname" "")
    (property "Tolerance" "1%")
    (property "Val" "330R")
    (property "ki_description" "330R resistor in 0402 package with 1% tolerance")
    (attr smd)
    (fp_text reference "R2" (at 0.909 -0.41 90) (layer "B.SilkS")
        (effects (font (size 0.7 0.7) (thickness 0.15)) (justify left bottom mirror))
    )
    (fp_text value "R_330R_0402" (at 0 -1.4 90) (layer "B.Fab") hide
        (effects (font (size 0.7 0.7) (thickness 0.15)) (justify left bottom mirror))
    )
    (fp_text user "${REFERENCE}" (at -0.95 -3.168 90) (layer "B.Fab") hide
        (effects (font (size 0.7 0.7) (thickness 0.15)) (justify left bottom mirror))
    )
    (fp_text user "License: Apache-2.0" (at -0.95 -5.169 90) (layer "B.Fab") hide
        (effects (font (size 0.7 0.7) (thickness 0.15)) (justify left bottom mirror))
    )
    (fp_text user "Author: Antmicro" (at -0.95 -4.169 90) (layer "B.Fab") hide
        (effects (font (size 0.7 0.7) (thickness 0.15)) (justify left bottom mirror))
    )
    (fp_rect (start -0.93 0.47) (end 0.93 -0.47)
      (stroke (width 0.05) (type solid)) (fill none) (layer "B.CrtYd"))
    (fp_rect (start -0.5 0.25) (end 0.5 -0.25)
      (stroke (width 0.15) (type solid)) (fill none) (layer "B.Fab"))
    (pad "1" smd roundrect (at -0.485 0 270) (size 0.59 0.64) (layers "B.Cu" "B.Paste" "B.Mask") (roundrect_rratio 0.25)
      (net 319 "SH_UP") (pintype "passive"))
    (pad "2" smd roundrect (at 0.485 0 270) (size 0.59 0.64) (layers "B.Cu" "B.Paste" "B.Mask") (roundrect_rratio 0.25)
      (net 1 "GND") (pintype "passive"))
  )

  (footprint "kria-k26-devboard-footprints:C_0402_1005Metric" (layer "B.Cu")
    (at 137.75 65.55)
    (descr "Capacitor SMD 0402")
    (tags "capacitor SMD 0402")
    (property "Author" "Antmicro")
    (property "Dielectric" "")
    (property "License" "Apache-2.0")
    (property "MPN" "CC0402MRX5R5BB106")
    (property "Manufacturer" "Yaego")
    (property "Sheetfile" "usb.kicad_sch")
    (property "Sheetname" "USB")
    (property "Val" "10u")
    (property "Voltage" "")
    (property "ki_description" " ")
    (attr smd)
    (fp_text reference "C71" (at 3.04 0.35 180) (layer "B.SilkS")
        (effects (font (size 0.7 0.7) (thickness 0.15)) (justify left bottom mirror))
    )
    (fp_text value "C_10u_0402" (at 0 -1.4 180) (layer "B.Fab") hide
        (effects (font (size 0.7 0.7) (thickness 0.15)) (justify left bottom mirror))
    )
    (fp_text user "License: Apache-2.0" (at -0.932 -5.17 180) (layer "B.Fab") hide
        (effects (font (size 0.7 0.7) (thickness 0.15)) (justify left bottom mirror))
    )
    (fp_text user "Author: Antmicro" (at -0.932 -4.17 180) (layer "B.Fab") hide
        (effects (font (size 0.7 0.7) (thickness 0.15)) (justify left bottom mirror))
    )
    (fp_text user "${REFERENCE}" (at -0.932 -3.168 180) (layer "B.Fab") hide
        (effects (font (size 0.7 0.7) (thickness 0.15)) (justify left bottom mirror))
    )
    (fp_rect (start -0.94 0.47) (end 0.94 -0.47)
      (stroke (width 0.05) (type solid)) (fill none) (layer "B.CrtYd"))
    (fp_rect (start -0.499 0.249) (end 0.499 -0.249)
      (stroke (width 0.15) (type solid)) (fill none) (layer "B.Fab"))
    (pad "1" smd roundrect (at -0.484 0) (size 0.59 0.64) (layers "B.Cu" "B.Paste" "B.Mask") (roundrect_rratio 0.25)
      (net 85 "/USB/USB2_VBUS") (pintype "passive"))
    (pad "2" smd roundrect (at 0.484 0) (size 0.59 0.64) (layers "B.Cu" "B.Paste" "B.Mask") (roundrect_rratio 0.25)
      (net 1 "GND") (pintype "passive"))
  )

  (footprint "kria-k26-devboard-footprints:R_0402_1005Metric" (layer "B.Cu")
    (at 85.3 122.85 180)
    (descr "Resistor SMD 0402")
    (tags "resistor SMD 0402")
    (property "Author" "Antmicro")
    (property "License" "Apache-2.0")
    (property "MPN" "CR0402-FX-2201GLF")
    (property "Manufacturer" "Bourns")
    (property "Sheetfile" "camera.kicad_sch")
    (property "Sheetname" "Camera interface")
    (property "Tolerance" "1%")
    (property "Val" "2k2")
    (property "ki_description" "2k2 resistor in 0402 package with 1% tolerance")
    (attr smd)
    (fp_text reference "R23" (at -3.04 -0.38) (layer "B.SilkS")
        (effects (font (size 0.7 0.7) (thickness 0.15)) (justify left bottom mirror))
    )
    (fp_text value "R_2k2_0402" (at 0 -1.4) (layer "B.Fab") hide
        (effects (font (size 0.7 0.7) (thickness 0.15)) (justify left bottom mirror))
    )
    (fp_text user "License: Apache-2.0" (at -0.95 -5.169) (layer "B.Fab") hide
        (effects (font (size 0.7 0.7) (thickness 0.15)) (justify left bottom mirror))
    )
    (fp_text user "Author: Antmicro" (at -0.95 -4.169) (layer "B.Fab") hide
        (effects (font (size 0.7 0.7) (thickness 0.15)) (justify left bottom mirror))
    )
    (fp_text user "${REFERENCE}" (at -0.95 -3.168) (layer "B.Fab") hide
        (effects (font (size 0.7 0.7) (thickness 0.15)) (justify left bottom mirror))
    )
    (fp_rect (start -0.93 0.47) (end 0.93 -0.47)
      (stroke (width 0.05) (type solid)) (fill none) (layer "B.CrtYd"))
    (fp_rect (start -0.5 0.25) (end 0.5 -0.25)
      (stroke (width 0.15) (type solid)) (fill none) (layer "B.Fab"))
    (pad "1" smd roundrect (at -0.485 0 180) (size 0.59 0.64) (layers "B.Cu" "B.Paste" "B.Mask") (roundrect_rratio 0.25)
      (net 20 "PL_3V3") (pintype "passive"))
    (pad "2" smd roundrect (at 0.485 0 180) (size 0.59 0.64) (layers "B.Cu" "B.Paste" "B.Mask") (roundrect_rratio 0.25)
      (net 225 "/Camera interface/HDA01") (pintype "passive"))
  )

  (footprint "kria-k26-devboard-footprints:C_0402_1005Metric" (layer "B.Cu")
    (at 85.31 121.89)
    (descr "Capacitor SMD 0402")
    (tags "capacitor SMD 0402")
    (property "Author" "Antmicro")
    (property "Dielectric" "X5R")
    (property "License" "Apache-2.0")
    (property "MPN" "GRM155R61H104KE14D")
    (property "Manufacturer" "Murata")
    (property "Sheetfile" "camera.kicad_sch")
    (property "Sheetname" "Camera interface")
    (property "Val" "100n")
    (property "Voltage" "50V")
    (property "ki_description" " ")
    (attr smd)
    (fp_text reference "C29" (at 3.06 0.36 180) (layer "B.SilkS")
        (effects (font (size 0.7 0.7) (thickness 0.15)) (justify left bottom mirror))
    )
    (fp_text value "C_100n_0402" (at 0 -1.4 180) (layer "B.Fab") hide
        (effects (font (size 0.7 0.7) (thickness 0.15)) (justify left bottom mirror))
    )
    (fp_text user "License: Apache-2.0" (at -0.932 -5.17 180) (layer "B.Fab") hide
        (effects (font (size 0.7 0.7) (thickness 0.15)) (justify left bottom mirror))
    )
    (fp_text user "${REFERENCE}" (at -0.932 -3.168 180) (layer "B.Fab") hide
        (effects (font (size 0.7 0.7) (thickness 0.15)) (justify left bottom mirror))
    )
    (fp_text user "Author: Antmicro" (at -0.932 -4.17 180) (layer "B.Fab") hide
        (effects (font (size 0.7 0.7) (thickness 0.15)) (justify left bottom mirror))
    )
    (fp_rect (start -0.94 0.47) (end 0.94 -0.47)
      (stroke (width 0.05) (type solid)) (fill none) (layer "B.CrtYd"))
    (fp_rect (start -0.499 0.249) (end 0.499 -0.249)
      (stroke (width 0.15) (type solid)) (fill none) (layer "B.Fab"))
    (pad "1" smd roundrect (at -0.484 0) (size 0.59 0.64) (layers "B.Cu" "B.Paste" "B.Mask") (roundrect_rratio 0.25)
      (net 20 "PL_3V3") (pintype "passive"))
    (pad "2" smd roundrect (at 0.484 0) (size 0.59 0.64) (layers "B.Cu" "B.Paste" "B.Mask") (roundrect_rratio 0.25)
      (net 1 "GND") (pintype "passive"))
  )

  (footprint "kria-k26-devboard-footprints:C_0402_1005Metric" (layer "B.Cu")
    (at 149.45 85.762385 -90)
    (descr "Capacitor SMD 0402")
    (tags "capacitor SMD 0402")
    (property "Author" "Antmicro")
    (property "Dielectric" "X5R")
    (property "License" "Apache-2.0")
    (property "MPN" "GRM155R61H104KE14D")
    (property "Manufacturer" "Murata")
    (property "Sheetfile" "eth.kicad_sch")
    (property "Sheetname" "Ethernet")
    (property "Val" "100n")
    (property "Voltage" "50V")
    (property "ki_description" " ")
    (attr smd)
    (fp_text reference "C105" (at -3.712385 -0.37 90) (layer "B.SilkS")
        (effects (font (size 0.7 0.7) (thickness 0.15)) (justify left bottom mirror))
    )
    (fp_text value "C_100n_0402" (at 0 -1.4 90) (layer "B.Fab") hide
        (effects (font (size 0.7 0.7) (thickness 0.15)) (justify left bottom mirror))
    )
    (fp_text user "${REFERENCE}" (at -0.932 -3.168 90) (layer "B.Fab") hide
        (effects (font (size 0.7 0.7) (thickness 0.15)) (justify left bottom mirror))
    )
    (fp_text user "Author: Antmicro" (at -0.932 -4.17 90) (layer "B.Fab") hide
        (effects (font (size 0.7 0.7) (thickness 0.15)) (justify left bottom mirror))
    )
    (fp_text user "License: Apache-2.0" (at -0.932 -5.17 90) (layer "B.Fab") hide
        (effects (font (size 0.7 0.7) (thickness 0.15)) (justify left bottom mirror))
    )
    (fp_rect (start -0.94 0.47) (end 0.94 -0.47)
      (stroke (width 0.05) (type solid)) (fill none) (layer "B.CrtYd"))
    (fp_rect (start -0.499 0.249) (end 0.499 -0.249)
      (stroke (width 0.15) (type solid)) (fill none) (layer "B.Fab"))
    (pad "1" smd roundrect (at -0.484 0 270) (size 0.59 0.64) (layers "B.Cu" "B.Paste" "B.Mask") (roundrect_rratio 0.25)
      (net 19 "PS_1V0") (pintype "passive"))
    (pad "2" smd roundrect (at 0.484 0 270) (size 0.59 0.64) (layers "B.Cu" "B.Paste" "B.Mask") (roundrect_rratio 0.25)
      (net 1 "GND") (pintype "passive"))
  )

  (footprint "kria-k26-devboard-footprints:C_0603_1608Metric" (layer "B.Cu")
    (at 155.3 85.4)
    (descr "Capacitor SMD 0603")
    (tags "capacitor 0603")
    (property "Author" "Antmicro")
    (property "License" "Apache-2.0")
    (property "MPN" "GRM188R61A106KE69D")
    (property "Manufacturer" "Murata")
    (property "Sheetfile" "eth.kicad_sch")
    (property "Sheetname" "Ethernet")
    (property "Val" "10u")
    (property "Voltage" "")
    (property "ki_description" " ")
    (attr smd)
    (fp_text reference "C90" (at 3.349 0.44 180) (layer "B.SilkS")
        (effects (font (size 0.7 0.7) (thickness 0.15)) (justify left bottom mirror))
    )
    (fp_text value "C_10u_0603" (at 0 -1.6 180) (layer "B.Fab") hide
        (effects (font (size 0.7 0.7) (thickness 0.15)) (justify left bottom mirror))
    )
    (fp_text user "Author: Antmicro" (at -1.682 -4.894 180) (layer "B.Fab") hide
        (effects (font (size 0.7 0.7) (thickness 0.15)) (justify left bottom mirror))
    )
    (fp_text user "${REFERENCE}" (at -1.682 -3.895 180) (layer "B.Fab") hide
        (effects (font (size 0.7 0.7) (thickness 0.15)) (justify left bottom mirror))
    )
    (fp_text user "License: Apache-2.0" (at -1.682 -5.895 180) (layer "B.Fab") hide
        (effects (font (size 0.7 0.7) (thickness 0.15)) (justify left bottom mirror))
    )
    (fp_line (start -0.3 -0.3) (end 0.3 -0.3)
      (stroke (width 0.15) (type solid)) (layer "B.SilkS"))
    (fp_line (start -0.3 0.3) (end 0.3 0.3)
      (stroke (width 0.15) (type solid)) (layer "B.SilkS"))
    (fp_rect (start -1.24 0.7) (end 1.24 -0.7)
      (stroke (width 0.05) (type solid)) (fill none) (layer "B.CrtYd"))
    (fp_rect (start -0.8 0.4) (end 0.8 -0.4)
      (stroke (width 0.15) (type solid)) (fill none) (layer "B.Fab"))
    (pad "1" smd roundrect (at -0.7 0) (size 0.6 0.8) (layers "B.Cu" "B.Paste" "B.Mask") (roundrect_rratio 0.2)
      (net 17 "PS_1V8") (pintype "passive"))
    (pad "2" smd roundrect (at 0.7 0) (size 0.6 0.8) (layers "B.Cu" "B.Paste" "B.Mask") (roundrect_rratio 0.2)
      (net 1 "GND") (pintype "passive"))
  )

  (footprint "kria-k26-devboard-footprints:R_0402_1005Metric" (layer "B.Cu")
    (at 150.9 93.7)
    (descr "Resistor SMD 0402")
    (tags "resistor SMD 0402")
    (property "Author" "Antmicro")
    (property "License" "Apache-2.0")
    (property "MPN" "CR0402-FX-2491GLF")
    (property "Manufacturer" "Bourns")
    (property "Sheetfile" "eth.kicad_sch")
    (property "Sheetname" "Ethernet")
    (property "Tolerance" "1%")
    (property "Val" "2k49")
    (property "ki_description" "2k49 resistor in 0402 package with 1% tolerance")
    (attr smd)
    (fp_text reference "R68" (at 2.97 0.4 180) (layer "B.SilkS")
        (effects (font (size 0.7 0.7) (thickness 0.15)) (justify left bottom mirror))
    )
    (fp_text value "R_2k49_0402" (at 0 -1.4 180) (layer "B.Fab") hide
        (effects (font (size 0.7 0.7) (thickness 0.15)) (justify left bottom mirror))
    )
    (fp_text user "Author: Antmicro" (at -0.95 -4.169 180) (layer "B.Fab") hide
        (effects (font (size 0.7 0.7) (thickness 0.15)) (justify left bottom mirror))
    )
    (fp_text user "${REFERENCE}" (at -0.95 -3.168 180) (layer "B.Fab") hide
        (effects (font (size 0.7 0.7) (thickness 0.15)) (justify left bottom mirror))
    )
    (fp_text user "License: Apache-2.0" (at -0.95 -5.169 180) (layer "B.Fab") hide
        (effects (font (size 0.7 0.7) (thickness 0.15)) (justify left bottom mirror))
    )
    (fp_rect (start -0.93 0.47) (end 0.93 -0.47)
      (stroke (width 0.05) (type solid)) (fill none) (layer "B.CrtYd"))
    (fp_rect (start -0.5 0.25) (end 0.5 -0.25)
      (stroke (width 0.15) (type solid)) (fill none) (layer "B.Fab"))
    (pad "1" smd roundrect (at -0.485 0) (size 0.59 0.64) (layers "B.Cu" "B.Paste" "B.Mask") (roundrect_rratio 0.25)
      (net 30 "/Ethernet/MIO71") (pintype "passive"))
    (pad "2" smd roundrect (at 0.485 0) (size 0.59 0.64) (layers "B.Cu" "B.Paste" "B.Mask") (roundrect_rratio 0.25)
      (net 1 "GND") (pintype "passive"))
  )

  (footprint "kria-k26-devboard-footprints:R_0402_1005Metric" (layer "B.Cu")
    (at 150.885 92.75 180)
    (descr "Resistor SMD 0402")
    (tags "resistor SMD 0402")
    (property "Author" "Antmicro")
    (property "License" "Apache-2.0")
    (property "MPN" "CR0402-FX-1002GLF")
    (property "Manufacturer" "Bourns")
    (property "Sheetfile" "eth.kicad_sch")
    (property "Sheetname" "Ethernet")
    (property "Tolerance" "1%")
    (property "Val" "10k")
    (property "ki_description" "10k resistor in 0402 package with 1% tolerance")
    (attr smd)
    (fp_text reference "R67" (at -2.965 -0.36) (layer "B.SilkS")
        (effects (font (size 0.7 0.7) (thickness 0.15)) (justify left bottom mirror))
    )
    (fp_text value "R_10k_0402" (at 0 -1.4) (layer "B.Fab") hide
        (effects (font (size 0.7 0.7) (thickness 0.15)) (justify left bottom mirror))
    )
    (fp_text user "License: Apache-2.0" (at -0.95 -5.169) (layer "B.Fab") hide
        (effects (font (size 0.7 0.7) (thickness 0.15)) (justify left bottom mirror))
    )
    (fp_text user "${REFERENCE}" (at -0.95 -3.168) (layer "B.Fab") hide
        (effects (font (size 0.7 0.7) (thickness 0.15)) (justify left bottom mirror))
    )
    (fp_text user "Author: Antmicro" (at -0.95 -4.169) (layer "B.Fab") hide
        (effects (font (size 0.7 0.7) (thickness 0.15)) (justify left bottom mirror))
    )
    (fp_rect (start -0.93 0.47) (end 0.93 -0.47)
      (stroke (width 0.05) (type solid)) (fill none) (layer "B.CrtYd"))
    (fp_rect (start -0.5 0.25) (end 0.5 -0.25)
      (stroke (width 0.15) (type solid)) (fill none) (layer "B.Fab"))
    (pad "1" smd roundrect (at -0.485 0 180) (size 0.59 0.64) (layers "B.Cu" "B.Paste" "B.Mask") (roundrect_rratio 0.25)
      (net 17 "PS_1V8") (pintype "passive"))
    (pad "2" smd roundrect (at 0.485 0 180) (size 0.59 0.64) (layers "B.Cu" "B.Paste" "B.Mask") (roundrect_rratio 0.25)
      (net 30 "/Ethernet/MIO71") (pintype "passive"))
  )

  (footprint "kria-k26-devboard-footprints:C_0402_1005Metric" (layer "B.Cu")
    (at 149.245911 91.614035 90)
    (descr "Capacitor SMD 0402")
    (tags "capacitor SMD 0402")
    (property "Author" "Antmicro")
    (property "Dielectric" "")
    (property "License" "Apache-2.0")
    (property "MPN" "C1005X6S1A105K050BC")
    (property "Manufacturer" "TDK")
    (property "Sheetfile" "eth.kicad_sch")
    (property "Sheetname" "Ethernet")
    (property "Val" "1u")
    (property "Voltage" "")
    (property "ki_description" " ")
    (attr smd)
    (fp_text reference "C111" (at -0.895965 0.42 270) (layer "B.SilkS")
        (effects (font (size 0.7 0.7) (thickness 0.15)) (justify left bottom mirror))
    )
    (fp_text value "C_1u_0402" (at 0 -1.4 270) (layer "B.Fab") hide
        (effects (font (size 0.7 0.7) (thickness 0.15)) (justify left bottom mirror))
    )
    (fp_text user "${REFERENCE}" (at -0.932 -3.168 270) (layer "B.Fab") hide
        (effects (font (size 0.7 0.7) (thickness 0.15)) (justify left bottom mirror))
    )
    (fp_text user "License: Apache-2.0" (at -0.932 -5.17 270) (layer "B.Fab") hide
        (effects (font (size 0.7 0.7) (thickness 0.15)) (justify left bottom mirror))
    )
    (fp_text user "Author: Antmicro" (at -0.932 -4.17 270) (layer "B.Fab") hide
        (effects (font (size 0.7 0.7) (thickness 0.15)) (justify left bottom mirror))
    )
    (fp_rect (start -0.94 0.47) (end 0.94 -0.47)
      (stroke (width 0.05) (type solid)) (fill none) (layer "B.CrtYd"))
    (fp_rect (start -0.499 0.249) (end 0.499 -0.249)
      (stroke (width 0.15) (type solid)) (fill none) (layer "B.Fab"))
    (pad "1" smd roundrect (at -0.484 0 90) (size 0.59 0.64) (layers "B.Cu" "B.Paste" "B.Mask") (roundrect_rratio 0.25)
      (net 19 "PS_1V0") (pintype "passive"))
    (pad "2" smd roundrect (at 0.484 0 90) (size 0.59 0.64) (layers "B.Cu" "B.Paste" "B.Mask") (roundrect_rratio 0.25)
      (net 1 "GND") (pintype "passive"))
  )

  (footprint "kria-k26-devboard-footprints:C_0402_1005Metric" (layer "B.Cu")
    (at 148.45 85.762385 -90)
    (descr "Capacitor SMD 0402")
    (tags "capacitor SMD 0402")
    (property "Author" "Antmicro")
    (property "Dielectric" "")
    (property "License" "Apache-2.0")
    (property "MPN" "C1005X6S1A105K050BC")
    (property "Manufacturer" "TDK")
    (property "Sheetfile" "eth.kicad_sch")
    (property "Sheetname" "Ethernet")
    (property "Val" "1u")
    (property "Voltage" "")
    (property "ki_description" " ")
    (attr smd)
    (fp_text reference "C109" (at -3.712385 -0.37 90) (layer "B.SilkS")
        (effects (font (size 0.7 0.7) (thickness 0.15)) (justify left bottom mirror))
    )
    (fp_text value "C_1u_0402" (at 0 -1.4 90) (layer "B.Fab") hide
        (effects (font (size 0.7 0.7) (thickness 0.15)) (justify left bottom mirror))
    )
    (fp_text user "${REFERENCE}" (at -0.932 -3.168 90) (layer "B.Fab") hide
        (effects (font (size 0.7 0.7) (thickness 0.15)) (justify left bottom mirror))
    )
    (fp_text user "Author: Antmicro" (at -0.932 -4.17 90) (layer "B.Fab") hide
        (effects (font (size 0.7 0.7) (thickness 0.15)) (justify left bottom mirror))
    )
    (fp_text user "License: Apache-2.0" (at -0.932 -5.17 90) (layer "B.Fab") hide
        (effects (font (size 0.7 0.7) (thickness 0.15)) (justify left bottom mirror))
    )
    (fp_rect (start -0.94 0.47) (end 0.94 -0.47)
      (stroke (width 0.05) (type solid)) (fill none) (layer "B.CrtYd"))
    (fp_rect (start -0.499 0.249) (end 0.499 -0.249)
      (stroke (width 0.15) (type solid)) (fill none) (layer "B.Fab"))
    (pad "1" smd roundrect (at -0.484 0 270) (size 0.59 0.64) (layers "B.Cu" "B.Paste" "B.Mask") (roundrect_rratio 0.25)
      (net 19 "PS_1V0") (pintype "passive"))
    (pad "2" smd roundrect (at 0.484 0 270) (size 0.59 0.64) (layers "B.Cu" "B.Paste" "B.Mask") (roundrect_rratio 0.25)
      (net 1 "GND") (pintype "passive"))
  )

  (footprint "kria-k26-devboard-footprints:C_0603_1608Metric" (layer "B.Cu")
    (at 145.26 80.470911 90)
    (descr "Capacitor SMD 0603")
    (tags "capacitor 0603")
    (property "Author" "Antmicro")
    (property "License" "Apache-2.0")
    (property "MPN" "GRM188R61A106KE69D")
    (property "Manufacturer" "Murata")
    (property "Sheetfile" "eth.kicad_sch")
    (property "Sheetname" "Ethernet")
    (property "Val" "10u")
    (property "Voltage" "")
    (property "ki_description" " ")
    (attr smd)
    (fp_text reference "C91" (at 0.870911 2.36 270) (layer "B.SilkS")
        (effects (font (size 0.7 0.7) (thickness 0.15)) (justify left bottom mirror))
    )
    (fp_text value "C_10u_0603" (at 0 -1.6 270) (layer "B.Fab") hide
        (effects (font (size 0.7 0.7) (thickness 0.15)) (justify left bottom mirror))
    )
    (fp_text user "License: Apache-2.0" (at -1.682 -5.895 270) (layer "B.Fab") hide
        (effects (font (size 0.7 0.7) (thickness 0.15)) (justify left bottom mirror))
    )
    (fp_text user "${REFERENCE}" (at -1.682 -3.895 270) (layer "B.Fab") hide
        (effects (font (size 0.7 0.7) (thickness 0.15)) (justify left bottom mirror))
    )
    (fp_text user "Author: Antmicro" (at -1.682 -4.894 270) (layer "B.Fab") hide
        (effects (font (size 0.7 0.7) (thickness 0.15)) (justify left bottom mirror))
    )
    (fp_line (start -0.3 -0.3) (end 0.3 -0.3)
      (stroke (width 0.15) (type solid)) (layer "B.SilkS"))
    (fp_line (start -0.3 0.3) (end 0.3 0.3)
      (stroke (width 0.15) (type solid)) (layer "B.SilkS"))
    (fp_rect (start -1.24 0.7) (end 1.24 -0.7)
      (stroke (width 0.05) (type solid)) (fill none) (layer "B.CrtYd"))
    (fp_rect (start -0.8 0.4) (end 0.8 -0.4)
      (stroke (width 0.15) (type solid)) (fill none) (layer "B.Fab"))
    (pad "1" smd roundrect (at -0.7 0 90) (size 0.6 0.8) (layers "B.Cu" "B.Paste" "B.Mask") (roundrect_rratio 0.2)
      (net 16 "PS_2V5") (pintype "passive"))
    (pad "2" smd roundrect (at 0.7 0 90) (size 0.6 0.8) (layers "B.Cu" "B.Paste" "B.Mask") (roundrect_rratio 0.2)
      (net 1 "GND") (pintype "passive"))
  )

  (footprint "kria-k26-devboard-footprints:C_0402_1005Metric" (layer "B.Cu")
    (at 155.1 86.65)
    (descr "Capacitor SMD 0402")
    (tags "capacitor SMD 0402")
    (property "Author" "Antmicro")
    (property "Dielectric" "X7R")
    (property "License" "Apache-2.0")
    (property "MPN" "GRM155R71H103KA88D")
    (property "Manufacturer" "Murata")
    (property "Sheetfile" "eth.kicad_sch")
    (property "Sheetname" "Ethernet")
    (property "Val" "10n")
    (property "Voltage" "50V")
    (property "ki_description" " ")
    (attr smd)
    (fp_text reference "C92" (at 3.1 0.35 180) (layer "B.SilkS")
        (effects (font (size 0.7 0.7) (thickness 0.15)) (justify left bottom mirror))
    )
    (fp_text value "C_10n_0402" (at 0 -1.4 180) (layer "B.Fab") hide
        (effects (font (size 0.7 0.7) (thickness 0.15)) (justify left bottom mirror))
    )
    (fp_text user "${REFERENCE}" (at -0.932 -3.168 180) (layer "B.Fab") hide
        (effects (font (size 0.7 0.7) (thickness 0.15)) (justify left bottom mirror))
    )
    (fp_text user "License: Apache-2.0" (at -0.932 -5.17 180) (layer "B.Fab") hide
        (effects (font (size 0.7 0.7) (thickness 0.15)) (justify left bottom mirror))
    )
    (fp_text user "Author: Antmicro" (at -0.932 -4.17 180) (layer "B.Fab") hide
        (effects (font (size 0.7 0.7) (thickness 0.15)) (justify left bottom mirror))
    )
    (fp_rect (start -0.94 0.47) (end 0.94 -0.47)
      (stroke (width 0.05) (type solid)) (fill none) (layer "B.CrtYd"))
    (fp_rect (start -0.499 0.249) (end 0.499 -0.249)
      (stroke (width 0.15) (type solid)) (fill none) (layer "B.Fab"))
    (pad "1" smd roundrect (at -0.484 0) (size 0.59 0.64) (layers "B.Cu" "B.Paste" "B.Mask") (roundrect_rratio 0.25)
      (net 17 "PS_1V8") (pintype "passive"))
    (pad "2" smd roundrect (at 0.484 0) (size 0.59 0.64) (layers "B.Cu" "B.Paste" "B.Mask") (roundrect_rratio 0.25)
      (net 1 "GND") (pintype "passive"))
  )

  (footprint "kria-k26-devboard-footprints:C_0402_1005Metric" (layer "B.Cu")
    (at 151.45 85.762385 -90)
    (descr "Capacitor SMD 0402")
    (tags "capacitor SMD 0402")
    (property "Author" "Antmicro")
    (property "Dielectric" "X5R")
    (property "License" "Apache-2.0")
    (property "MPN" "GRM155R61H104KE14D")
    (property "Manufacturer" "Murata")
    (property "Sheetfile" "eth.kicad_sch")
    (property "Sheetname" "Ethernet")
    (property "Val" "100n")
    (property "Voltage" "50V")
    (property "ki_description" " ")
    (attr smd)
    (fp_text reference "C103" (at -3.712385 -0.37 90) (layer "B.SilkS")
        (effects (font (size 0.7 0.7) (thickness 0.15)) (justify left bottom mirror))
    )
    (fp_text value "C_100n_0402" (at 0 -1.4 90) (layer "B.Fab") hide
        (effects (font (size 0.7 0.7) (thickness 0.15)) (justify left bottom mirror))
    )
    (fp_text user "License: Apache-2.0" (at -0.932 -5.17 90) (layer "B.Fab") hide
        (effects (font (size 0.7 0.7) (thickness 0.15)) (justify left bottom mirror))
    )
    (fp_text user "${REFERENCE}" (at -0.932 -3.168 90) (layer "B.Fab") hide
        (effects (font (size 0.7 0.7) (thickness 0.15)) (justify left bottom mirror))
    )
    (fp_text user "Author: Antmicro" (at -0.932 -4.17 90) (layer "B.Fab") hide
        (effects (font (size 0.7 0.7) (thickness 0.15)) (justify left bottom mirror))
    )
    (fp_rect (start -0.94 0.47) (end 0.94 -0.47)
      (stroke (width 0.05) (type solid)) (fill none) (layer "B.CrtYd"))
    (fp_rect (start -0.499 0.249) (end 0.499 -0.249)
      (stroke (width 0.15) (type solid)) (fill none) (layer "B.Fab"))
    (pad "1" smd roundrect (at -0.484 0 270) (size 0.59 0.64) (layers "B.Cu" "B.Paste" "B.Mask") (roundrect_rratio 0.25)
      (net 16 "PS_2V5") (pintype "passive"))
    (pad "2" smd roundrect (at 0.484 0 270) (size 0.59 0.64) (layers "B.Cu" "B.Paste" "B.Mask") (roundrect_rratio 0.25)
      (net 1 "GND") (pintype "passive"))
  )

  (footprint "kria-k26-devboard-footprints:C_0402_1005Metric" (layer "B.Cu")
    (at 146.45 80.625 90)
    (descr "Capacitor SMD 0402")
    (tags "capacitor SMD 0402")
    (property "Author" "Antmicro")
    (property "Dielectric" "X7R")
    (property "License" "Apache-2.0")
    (property "MPN" "GRM155R71H103KA88D")
    (property "Manufacturer" "Murata")
    (property "Sheetfile" "eth.kicad_sch")
    (property "Sheetname" "Ethernet")
    (property "Val" "10n")
    (property "Voltage" "50V")
    (property "ki_description" " ")
    (attr smd)
    (fp_text reference "C93" (at 1.025 2.14 270) (layer "B.SilkS")
        (effects (font (size 0.7 0.7) (thickness 0.15)) (justify left bottom mirror))
    )
    (fp_text value "C_10n_0402" (at 0 -1.4 270) (layer "B.Fab") hide
        (effects (font (size 0.7 0.7) (thickness 0.15)) (justify left bottom mirror))
    )
    (fp_text user "License: Apache-2.0" (at -0.932 -5.17 270) (layer "B.Fab") hide
        (effects (font (size 0.7 0.7) (thickness 0.15)) (justify left bottom mirror))
    )
    (fp_text user "${REFERENCE}" (at -0.932 -3.168 270) (layer "B.Fab") hide
        (effects (font (size 0.7 0.7) (thickness 0.15)) (justify left bottom mirror))
    )
    (fp_text user "Author: Antmicro" (at -0.932 -4.17 270) (layer "B.Fab") hide
        (effects (font (size 0.7 0.7) (thickness 0.15)) (justify left bottom mirror))
    )
    (fp_rect (start -0.94 0.47) (end 0.94 -0.47)
      (stroke (width 0.05) (type solid)) (fill none) (layer "B.CrtYd"))
    (fp_rect (start -0.499 0.249) (end 0.499 -0.249)
      (stroke (width 0.15) (type solid)) (fill none) (layer "B.Fab"))
    (pad "1" smd roundrect (at -0.484 0 90) (size 0.59 0.64) (layers "B.Cu" "B.Paste" "B.Mask") (roundrect_rratio 0.25)
      (net 16 "PS_2V5") (pintype "passive"))
    (pad "2" smd roundrect (at 0.484 0 90) (size 0.59 0.64) (layers "B.Cu" "B.Paste" "B.Mask") (roundrect_rratio 0.25)
      (net 1 "GND") (pintype "passive"))
  )

  (footprint "kria-k26-devboard-footprints:C_0402_1005Metric" (layer "B.Cu")
    (at 145.895911 88.9)
    (descr "Capacitor SMD 0402")
    (tags "capacitor SMD 0402")
    (property "Author" "Antmicro")
    (property "Dielectric" "")
    (property "License" "Apache-2.0")
    (property "MPN" "C1005X6S1A105K050BC")
    (property "Manufacturer" "TDK")
    (property "Sheetfile" "eth.kicad_sch")
    (property "Sheetname" "Ethernet")
    (property "Val" "1u")
    (property "Voltage" "")
    (property "ki_description" " ")
    (attr smd)
    (fp_text reference "C94" (at -0.935911 0.4 180) (layer "B.SilkS")
        (effects (font (size 0.7 0.7) (thickness 0.15)) (justify left bottom mirror))
    )
    (fp_text value "C_1u_0402" (at 0 -1.4 180) (layer "B.Fab") hide
        (effects (font (size 0.7 0.7) (thickness 0.15)) (justify left bottom mirror))
    )
    (fp_text user "${REFERENCE}" (at -0.932 -3.168 180) (layer "B.Fab") hide
        (effects (font (size 0.7 0.7) (thickness 0.15)) (justify left bottom mirror))
    )
    (fp_text user "Author: Antmicro" (at -0.932 -4.17 180) (layer "B.Fab") hide
        (effects (font (size 0.7 0.7) (thickness 0.15)) (justify left bottom mirror))
    )
    (fp_text user "License: Apache-2.0" (at -0.932 -5.17 180) (layer "B.Fab") hide
        (effects (font (size 0.7 0.7) (thickness 0.15)) (justify left bottom mirror))
    )
    (fp_rect (start -0.94 0.47) (end 0.94 -0.47)
      (stroke (width 0.05) (type solid)) (fill none) (layer "B.CrtYd"))
    (fp_rect (start -0.499 0.249) (end 0.499 -0.249)
      (stroke (width 0.15) (type solid)) (fill none) (layer "B.Fab"))
    (pad "1" smd roundrect (at -0.484 0) (size 0.59 0.64) (layers "B.Cu" "B.Paste" "B.Mask") (roundrect_rratio 0.25)
      (net 17 "PS_1V8") (pintype "passive"))
    (pad "2" smd roundrect (at 0.484 0) (size 0.59 0.64) (layers "B.Cu" "B.Paste" "B.Mask") (roundrect_rratio 0.25)
      (net 1 "GND") (pintype "passive"))
  )

  (footprint "kria-k26-devboard-footprints:C_0402_1005Metric" (layer "B.Cu")
    (at 146.45 85.75 -90)
    (descr "Capacitor SMD 0402")
    (tags "capacitor SMD 0402")
    (property "Author" "Antmicro")
    (property "Dielectric" "")
    (property "License" "Apache-2.0")
    (property "MPN" "C1005X6S1A105K050BC")
    (property "Manufacturer" "TDK")
    (property "Sheetfile" "eth.kicad_sch")
    (property "Sheetname" "Ethernet")
    (property "Val" "1u")
    (property "Voltage" "")
    (property "ki_description" " ")
    (attr smd)
    (fp_text reference "C97" (at -3.712385 -0.37 90) (layer "B.SilkS")
        (effects (font (size 0.7 0.7) (thickness 0.15)) (justify left bottom mirror))
    )
    (fp_text value "C_1u_0402" (at 0 -1.4 90) (layer "B.Fab") hide
        (effects (font (size 0.7 0.7) (thickness 0.15)) (justify left bottom mirror))
    )
    (fp_text user "License: Apache-2.0" (at -0.932 -5.17 90) (layer "B.Fab") hide
        (effects (font (size 0.7 0.7) (thickness 0.15)) (justify left bottom mirror))
    )
    (fp_text user "${REFERENCE}" (at -0.932 -3.168 90) (layer "B.Fab") hide
        (effects (font (size 0.7 0.7) (thickness 0.15)) (justify left bottom mirror))
    )
    (fp_text user "Author: Antmicro" (at -0.932 -4.17 90) (layer "B.Fab") hide
        (effects (font (size 0.7 0.7) (thickness 0.15)) (justify left bottom mirror))
    )
    (fp_rect (start -0.94 0.47) (end 0.94 -0.47)
      (stroke (width 0.05) (type solid)) (fill none) (layer "B.CrtYd"))
    (fp_rect (start -0.499 0.249) (end 0.499 -0.249)
      (stroke (width 0.15) (type solid)) (fill none) (layer "B.Fab"))
    (pad "1" smd roundrect (at -0.484 0 270) (size 0.59 0.64) (layers "B.Cu" "B.Paste" "B.Mask") (roundrect_rratio 0.25)
      (net 16 "PS_2V5") (pintype "passive"))
    (pad "2" smd roundrect (at 0.484 0 270) (size 0.59 0.64) (layers "B.Cu" "B.Paste" "B.Mask") (roundrect_rratio 0.25)
      (net 1 "GND") (pintype "passive"))
  )

  (footprint "kria-k26-devboard-footprints:C_0402_1005Metric" (layer "B.Cu")
    (at 151.85 89.8 180)
    (descr "Capacitor SMD 0402")
    (tags "capacitor SMD 0402")
    (property "Author" "Antmicro")
    (property "Dielectric" "")
    (property "License" "Apache-2.0")
    (property "MPN" "C1005X6S1A105K050BC")
    (property "Manufacturer" "TDK")
    (property "Sheetfile" "eth.kicad_sch")
    (property "Sheetname" "Ethernet")
    (property "Val" "1u")
    (property "Voltage" "")
    (property "ki_description" " ")
    (attr smd)
    (fp_text reference "C96" (at 0.87 -0.41) (layer "B.SilkS")
        (effects (font (size 0.7 0.7) (thickness 0.15)) (justify left bottom mirror))
    )
    (fp_text value "C_1u_0402" (at 0 -1.4) (layer "B.Fab") hide
        (effects (font (size 0.7 0.7) (thickness 0.15)) (justify left bottom mirror))
    )
    (fp_text user "License: Apache-2.0" (at -0.932 -5.17) (layer "B.Fab") hide
        (effects (font (size 0.7 0.7) (thickness 0.15)) (justify left bottom mirror))
    )
    (fp_text user "Author: Antmicro" (at -0.932 -4.17) (layer "B.Fab") hide
        (effects (font (size 0.7 0.7) (thickness 0.15)) (justify left bottom mirror))
    )
    (fp_text user "${REFERENCE}" (at -0.932 -3.168) (layer "B.Fab") hide
        (effects (font (size 0.7 0.7) (thickness 0.15)) (justify left bottom mirror))
    )
    (fp_rect (start -0.94 0.47) (end 0.94 -0.47)
      (stroke (width 0.05) (type solid)) (fill none) (layer "B.CrtYd"))
    (fp_rect (start -0.499 0.249) (end 0.499 -0.249)
      (stroke (width 0.15) (type solid)) (fill none) (layer "B.Fab"))
    (pad "1" smd roundrect (at -0.484 0 180) (size 0.59 0.64) (layers "B.Cu" "B.Paste" "B.Mask") (roundrect_rratio 0.25)
      (net 17 "PS_1V8") (pintype "passive"))
    (pad "2" smd roundrect (at 0.484 0 180) (size 0.59 0.64) (layers "B.Cu" "B.Paste" "B.Mask") (roundrect_rratio 0.25)
      (net 1 "GND") (pintype "passive"))
  )

  (footprint "kria-k26-devboard-footprints:C_0402_1005Metric" (layer "B.Cu")
    (at 148.3 91.614035 90)
    (descr "Capacitor SMD 0402")
    (tags "capacitor SMD 0402")
    (property "Author" "Antmicro")
    (property "Dielectric" "")
    (property "License" "Apache-2.0")
    (property "MPN" "C1005X6S1A105K050BC")
    (property "Manufacturer" "TDK")
    (property "Sheetfile" "eth.kicad_sch")
    (property "Sheetname" "Ethernet")
    (property "Val" "1u")
    (property "Voltage" "")
    (property "ki_description" " ")
    (attr smd)
    (fp_text reference "C95" (at -0.895965 0.42 270) (layer "B.SilkS")
        (effects (font (size 0.7 0.7) (thickness 0.15)) (justify left bottom mirror))
    )
    (fp_text value "C_1u_0402" (at 0 -1.4 270) (layer "B.Fab") hide
        (effects (font (size 0.7 0.7) (thickness 0.15)) (justify left bottom mirror))
    )
    (fp_text user "${REFERENCE}" (at -0.932 -3.168 270) (layer "B.Fab") hide
        (effects (font (size 0.7 0.7) (thickness 0.15)) (justify left bottom mirror))
    )
    (fp_text user "License: Apache-2.0" (at -0.932 -5.17 270) (layer "B.Fab") hide
        (effects (font (size 0.7 0.7) (thickness 0.15)) (justify left bottom mirror))
    )
    (fp_text user "Author: Antmicro" (at -0.932 -4.17 270) (layer "B.Fab") hide
        (effects (font (size 0.7 0.7) (thickness 0.15)) (justify left bottom mirror))
    )
    (fp_rect (start -0.94 0.47) (end 0.94 -0.47)
      (stroke (width 0.05) (type solid)) (fill none) (layer "B.CrtYd"))
    (fp_rect (start -0.499 0.249) (end 0.499 -0.249)
      (stroke (width 0.15) (type solid)) (fill none) (layer "B.Fab"))
    (pad "1" smd roundrect (at -0.484 0 90) (size 0.59 0.64) (layers "B.Cu" "B.Paste" "B.Mask") (roundrect_rratio 0.25)
      (net 17 "PS_1V8") (pintype "passive"))
    (pad "2" smd roundrect (at 0.484 0 90) (size 0.59 0.64) (layers "B.Cu" "B.Paste" "B.Mask") (roundrect_rratio 0.25)
      (net 1 "GND") (pintype "passive"))
  )

  (footprint "kria-k26-devboard-footprints:R_0402_1005Metric" (layer "B.Cu")
    (at 154.629289 92.675)
    (descr "Resistor SMD 0402")
    (tags "resistor SMD 0402")
    (property "Author" "Antmicro")
    (property "License" "Apache-2.0")
    (property "MPN" "CR0402-FX-2491GLF")
    (property "Manufacturer" "Bourns")
    (property "Sheetfile" "eth.kicad_sch")
    (property "Sheetname" "Ethernet")
    (property "Tolerance" "1%")
    (property "Val" "2k49")
    (property "ki_description" "2k49 resistor in 0402 package with 1% tolerance")
    (attr smd)
    (fp_text reference "R70" (at 3.000711 0.405 180) (layer "B.SilkS")
        (effects (font (size 0.7 0.7) (thickness 0.15)) (justify left bottom mirror))
    )
    (fp_text value "R_2k49_0402" (at 0 -1.4 180) (layer "B.Fab") hide
        (effects (font (size 0.7 0.7) (thickness 0.15)) (justify left bottom mirror))
    )
    (fp_text user "${REFERENCE}" (at -0.95 -3.168 180) (layer "B.Fab") hide
        (effects (font (size 0.7 0.7) (thickness 0.15)) (justify left bottom mirror))
    )
    (fp_text user "License: Apache-2.0" (at -0.95 -5.169 180) (layer "B.Fab") hide
        (effects (font (size 0.7 0.7) (thickness 0.15)) (justify left bottom mirror))
    )
    (fp_text user "Author: Antmicro" (at -0.95 -4.169 180) (layer "B.Fab") hide
        (effects (font (size 0.7 0.7) (thickness 0.15)) (justify left bottom mirror))
    )
    (fp_rect (start -0.93 0.47) (end 0.93 -0.47)
      (stroke (width 0.05) (type solid)) (fill none) (layer "B.CrtYd"))
    (fp_rect (start -0.5 0.25) (end 0.5 -0.25)
      (stroke (width 0.15) (type solid)) (fill none) (layer "B.Fab"))
    (pad "1" smd roundrect (at -0.485 0) (size 0.59 0.64) (layers "B.Cu" "B.Paste" "B.Mask") (roundrect_rratio 0.25)
      (net 28 "/Ethernet/MIO75") (pintype "passive"))
    (pad "2" smd roundrect (at 0.485 0) (size 0.59 0.64) (layers "B.Cu" "B.Paste" "B.Mask") (roundrect_rratio 0.25)
      (net 1 "GND") (pintype "passive"))
  )

  (footprint "kria-k26-devboard-footprints:C_0402_1005Metric" (layer "B.Cu")
    (at 145.94591 91.514035)
    (descr "Capacitor SMD 0402")
    (tags "capacitor SMD 0402")
    (property "Author" "Antmicro")
    (property "Dielectric" "")
    (property "License" "Apache-2.0")
    (property "MPN" "C1005X6S1A105K050BC")
    (property "Manufacturer" "TDK")
    (property "Sheetfile" "eth.kicad_sch")
    (property "Sheetname" "Ethernet")
    (property "Val" "1u")
    (property "Voltage" "")
    (property "ki_description" " ")
    (attr smd)
    (fp_text reference "C110" (at 1.40409 1.355965 180) (layer "B.SilkS")
        (effects (font (size 0.7 0.7) (thickness 0.15)) (justify left bottom mirror))
    )
    (fp_text value "C_1u_0402" (at 0 -1.4 180) (layer "B.Fab") hide
        (effects (font (size 0.7 0.7) (thickness 0.15)) (justify left bottom mirror))
    )
    (fp_text user "${REFERENCE}" (at -0.932 -3.168 180) (layer "B.Fab") hide
        (effects (font (size 0.7 0.7) (thickness 0.15)) (justify left bottom mirror))
    )
    (fp_text user "License: Apache-2.0" (at -0.932 -5.17 180) (layer "B.Fab") hide
        (effects (font (size 0.7 0.7) (thickness 0.15)) (justify left bottom mirror))
    )
    (fp_text user "Author: Antmicro" (at -0.932 -4.17 180) (layer "B.Fab") hide
        (effects (font (size 0.7 0.7) (thickness 0.15)) (justify left bottom mirror))
    )
    (fp_rect (start -0.94 0.47) (end 0.94 -0.47)
      (stroke (width 0.05) (type solid)) (fill none) (layer "B.CrtYd"))
    (fp_rect (start -0.499 0.249) (end 0.499 -0.249)
      (stroke (width 0.15) (type solid)) (fill none) (layer "B.Fab"))
    (pad "1" smd roundrect (at -0.484 0) (size 0.59 0.64) (layers "B.Cu" "B.Paste" "B.Mask") (roundrect_rratio 0.25)
      (net 19 "PS_1V0") (pintype "passive"))
    (pad "2" smd roundrect (at 0.484 0) (size 0.59 0.64) (layers "B.Cu" "B.Paste" "B.Mask") (roundrect_rratio 0.25)
      (net 1 "GND") (pintype "passive"))
  )

  (footprint "kria-k26-devboard-footprints:C_0402_1005Metric" (layer "B.Cu")
    (at 150.45 85.762385 -90)
    (descr "Capacitor SMD 0402")
    (tags "capacitor SMD 0402")
    (property "Author" "Antmicro")
    (property "Dielectric" "")
    (property "License" "Apache-2.0")
    (property "MPN" "C1005X6S1A105K050BC")
    (property "Manufacturer" "TDK")
    (property "Sheetfile" "eth.kicad_sch")
    (property "Sheetname" "Ethernet")
    (property "Val" "1u")
    (property "Voltage" "")
    (property "ki_description" " ")
    (attr smd)
    (fp_text reference "C98" (at -3.712385 -0.37 90) (layer "B.SilkS")
        (effects (font (size 0.7 0.7) (thickness 0.15)) (justify left bottom mirror))
    )
    (fp_text value "C_1u_0402" (at 0 -1.4 90) (layer "B.Fab") hide
        (effects (font (size 0.7 0.7) (thickness 0.15)) (justify left bottom mirror))
    )
    (fp_text user "${REFERENCE}" (at -0.932 -3.168 90) (layer "B.Fab") hide
        (effects (font (size 0.7 0.7) (thickness 0.15)) (justify left bottom mirror))
    )
    (fp_text user "License: Apache-2.0" (at -0.932 -5.17 90) (layer "B.Fab") hide
        (effects (font (size 0.7 0.7) (thickness 0.15)) (justify left bottom mirror))
    )
    (fp_text user "Author: Antmicro" (at -0.932 -4.17 90) (layer "B.Fab") hide
        (effects (font (size 0.7 0.7) (thickness 0.15)) (justify left bottom mirror))
    )
    (fp_rect (start -0.94 0.47) (end 0.94 -0.47)
      (stroke (width 0.05) (type solid)) (fill none) (layer "B.CrtYd"))
    (fp_rect (start -0.499 0.249) (end 0.499 -0.249)
      (stroke (width 0.15) (type solid)) (fill none) (layer "B.Fab"))
    (pad "1" smd roundrect (at -0.484 0 270) (size 0.59 0.64) (layers "B.Cu" "B.Paste" "B.Mask") (roundrect_rratio 0.25)
      (net 16 "PS_2V5") (pintype "passive"))
    (pad "2" smd roundrect (at 0.484 0 270) (size 0.59 0.64) (layers "B.Cu" "B.Paste" "B.Mask") (roundrect_rratio 0.25)
      (net 1 "GND") (pintype "passive"))
  )

  (footprint "kria-k26-devboard-footprints:C_0402_1005Metric" (layer "B.Cu")
    (at 147.45 85.765 -90)
    (descr "Capacitor SMD 0402")
    (tags "capacitor SMD 0402")
    (property "Author" "Antmicro")
    (property "Dielectric" "X5R")
    (property "License" "Apache-2.0")
    (property "MPN" "GRM155R61H104KE14D")
    (property "Manufacturer" "Murata")
    (property "Sheetfile" "eth.kicad_sch")
    (property "Sheetname" "Ethernet")
    (property "Val" "100n")
    (property "Voltage" "50V")
    (property "ki_description" " ")
    (attr smd)
    (fp_text reference "C102" (at -3.712385 -0.37 90) (layer "B.SilkS")
        (effects (font (size 0.7 0.7) (thickness 0.15)) (justify left bottom mirror))
    )
    (fp_text value "C_100n_0402" (at 0 -1.4 90) (layer "B.Fab") hide
        (effects (font (size 0.7 0.7) (thickness 0.15)) (justify left bottom mirror))
    )
    (fp_text user "Author: Antmicro" (at -0.932 -4.17 90) (layer "B.Fab") hide
        (effects (font (size 0.7 0.7) (thickness 0.15)) (justify left bottom mirror))
    )
    (fp_text user "${REFERENCE}" (at -0.932 -3.168 90) (layer "B.Fab") hide
        (effects (font (size 0.7 0.7) (thickness 0.15)) (justify left bottom mirror))
    )
    (fp_text user "License: Apache-2.0" (at -0.932 -5.17 90) (layer "B.Fab") hide
        (effects (font (size 0.7 0.7) (thickness 0.15)) (justify left bottom mirror))
    )
    (fp_rect (start -0.94 0.47) (end 0.94 -0.47)
      (stroke (width 0.05) (type solid)) (fill none) (layer "B.CrtYd"))
    (fp_rect (start -0.499 0.249) (end 0.499 -0.249)
      (stroke (width 0.15) (type solid)) (fill none) (layer "B.Fab"))
    (pad "1" smd roundrect (at -0.484 0 270) (size 0.59 0.64) (layers "B.Cu" "B.Paste" "B.Mask") (roundrect_rratio 0.25)
      (net 16 "PS_2V5") (pintype "passive"))
    (pad "2" smd roundrect (at 0.484 0 270) (size 0.59 0.64) (layers "B.Cu" "B.Paste" "B.Mask") (roundrect_rratio 0.25)
      (net 1 "GND") (pintype "passive"))
  )

  (footprint "kria-k26-devboard-footprints:R_0402_1005Metric" (layer "B.Cu")
    (at 154.615255 93.65 180)
    (descr "Resistor SMD 0402")
    (tags "resistor SMD 0402")
    (property "Author" "Antmicro")
    (property "License" "Apache-2.0")
    (property "MPN" "CR0402-FX-5761GLF")
    (property "Manufacturer" "Bourns")
    (property "Sheetfile" "eth.kicad_sch")
    (property "Sheetname" "Ethernet")
    (property "Tolerance" "1%")
    (property "Val" "5k76")
    (property "ki_description" "5k76 resistor in 0402 package with 1% tolerance")
    (attr smd)
    (fp_text reference "R69" (at -3.034745 -0.37) (layer "B.SilkS")
        (effects (font (size 0.7 0.7) (thickness 0.15)) (justify left bottom mirror))
    )
    (fp_text value "R_5k76_0402" (at 0 -1.4) (layer "B.Fab") hide
        (effects (font (size 0.7 0.7) (thickness 0.15)) (justify left bottom mirror))
    )
    (fp_text user "License: Apache-2.0" (at -0.95 -5.169) (layer "B.Fab") hide
        (effects (font (size 0.7 0.7) (thickness 0.15)) (justify left bottom mirror))
    )
    (fp_text user "Author: Antmicro" (at -0.95 -4.169) (layer "B.Fab") hide
        (effects (font (size 0.7 0.7) (thickness 0.15)) (justify left bottom mirror))
    )
    (fp_text user "${REFERENCE}" (at -0.95 -3.168) (layer "B.Fab") hide
        (effects (font (size 0.7 0.7) (thickness 0.15)) (justify left bottom mirror))
    )
    (fp_rect (start -0.93 0.47) (end 0.93 -0.47)
      (stroke (width 0.05) (type solid)) (fill none) (layer "B.CrtYd"))
    (fp_rect (start -0.5 0.25) (end 0.5 -0.25)
      (stroke (width 0.15) (type solid)) (fill none) (layer "B.Fab"))
    (pad "1" smd roundrect (at -0.485 0 180) (size 0.59 0.64) (layers "B.Cu" "B.Paste" "B.Mask") (roundrect_rratio 0.25)
      (net 17 "PS_1V8") (pintype "passive"))
    (pad "2" smd roundrect (at 0.485 0 180) (size 0.59 0.64) (layers "B.Cu" "B.Paste" "B.Mask") (roundrect_rratio 0.25)
      (net 28 "/Ethernet/MIO75") (pintype "passive"))
  )

  (footprint "kria-k26-devboard-footprints:SOT-563" (layer "B.Cu")
    (at 135.103449 74.171573 90)
    (property "Author" "Antmicro")
    (property "License" "Apache-2.0")
    (property "MPN" "82400152")
    (property "Manufacturer" "Würth Elektronik")
    (property "Sheetfile" "usb.kicad_sch")
    (property "Sheetname" "USB")
    (property "ki_description" "TVS diode")
    (property "ki_keywords" "SMT, DIODE, IC, ESD, TVS")
    (attr smd)
    (fp_text reference "U20" (at -0.298427 1.056551 180) (layer "B.SilkS")
        (effects (font (size 0.7 0.7) (thickness 0.15)) (justify right bottom mirror))
    )
    (fp_text value "82400152" (at 0 -2 90) (layer "B.Fab") hide
        (effects (font (size 0.7 0.7) (thickness 0.15)) (justify right bottom mirror))
    )
    (fp_text user "${REFERENCE}" (at -1.299 -7.323 90) (layer "B.Fab") hide
        (effects (font (size 0.7 0.7) (thickness 0.15)) (justify right bottom mirror))
    )
    (fp_text user "License: Apache-2.0" (at -1.299 -4.924 90) (layer "B.Fab") hide
        (effects (font (size 0.7 0.7) (thickness 0.15)) (justify right bottom mirror))
    )
    (fp_text user "Author: Antmicro" (at -1.299 -6.124 90) (layer "B.Fab") hide
        (effects (font (size 0.7 0.7) (thickness 0.15)) (justify right bottom mirror))
    )
    (fp_line (start -0.778 -0.949) (end -0.424 -0.949)
      (stroke (width 0.15) (type solid)) (layer "B.SilkS"))
    (fp_line (start -0.778 -0.776) (end -0.778 -0.949)
      (stroke (width 0.15) (type solid)) (layer "B.SilkS"))
    (fp_line (start -0.499 0.974) (end -0.724 0.778)
      (stroke (width 0.15) (type solid)) (layer "B.SilkS"))
    (fp_line (start 0.776 -0.972) (end 0.526 -0.972)
      (stroke (width 0.15) (type solid)) (layer "B.SilkS"))
    (fp_line (start 0.776 -0.776) (end 0.776 -0.972)
      (stroke (width 0.15) (type solid)) (layer "B.SilkS"))
    (fp_line (start 0.776 0.974) (end 0.526 0.974)
      (stroke (width 0.15) (type solid)) (layer "B.SilkS"))
    (fp_line (start 0.776 0.974) (end 0.776 0.778)
      (stroke (width 0.15) (type solid)) (layer "B.SilkS"))
    (fp_circle (center -0.903 0.999) (end -0.952 0.95)
      (stroke (width 0.15) (type solid)) (fill solid) (layer "B.SilkS"))
    (fp_rect (start 1.19 1.12) (end -1.2 -1.1)
      (stroke (width 0.05) (type solid)) (fill none) (layer "B.CrtYd"))
    (fp_line (start -0.653 0.678) (end -0.653 -0.847)
      (stroke (width 0.15) (type solid)) (layer "B.Fab"))
    (fp_line (start -0.453 0.849) (end -0.653 0.678)
      (stroke (width 0.15) (type solid)) (layer "B.Fab"))
    (fp_line (start -0.453 0.849) (end 0.651 0.849)
      (stroke (width 0.15) (type solid)) (layer "B.Fab"))
    (fp_line (start 0.651 -0.847) (end -0.653 -0.847)
      (stroke (width 0.15) (type solid)) (layer "B.Fab"))
    (fp_line (start 0.651 0.849) (end 0.651 -0.847)
      (stroke (width 0.15) (type solid)) (layer "B.Fab"))
    (pad "1" smd roundrect (at -0.749 0.499 180) (size 0.3 0.6) (layers "B.Cu" "B.Paste" "B.Mask") (roundrect_rratio 0.25)
      (net 67 "/USB/USB1_N") (pintype "passive"))
    (pad "2" smd roundrect (at -0.749 -0.001 180) (size 0.3 0.6) (layers "B.Cu" "B.Paste" "B.Mask") (roundrect_rratio 0.25)
      (net 1 "GND") (pintype "passive"))
    (pad "3" smd roundrect (at -0.749 -0.497 180) (size 0.3 0.6) (layers "B.Cu" "B.Paste" "B.Mask") (roundrect_rratio 0.25)
      (net 68 "/USB/USB1_P") (pintype "passive"))
    (pad "4" smd roundrect (at 0.747 -0.497 180) (size 0.3 0.6) (layers "B.Cu" "B.Paste" "B.Mask") (roundrect_rratio 0.25)
      (net 287 "/USB/USB1_TVS_P") (pintype "passive"))
    (pad "5" smd roundrect (at 0.747 -0.001 180) (size 0.3 0.6) (layers "B.Cu" "B.Paste" "B.Mask") (roundrect_rratio 0.25)
      (net 64 "/USB/USB1_VBUS") (pintype "passive"))
    (pad "6" smd roundrect (at 0.747 0.499 180) (size 0.3 0.6) (layers "B.Cu" "B.Paste" "B.Mask") (roundrect_rratio 0.25)
      (net 286 "/USB/USB1_TVS_N") (pintype "passive"))
  )

  (footprint "kria-k26-devboard-footprints:Nexperia_SOD128" (layer "B.Cu")
    (at 186.175 63.95 180)
    (property "Author" "Antmicro")
    (property "DNP" "DNP")
    (property "License" "Apache-2.0")
    (property "MPN" "PMEG3050EP,115")
    (property "Manufacturer" "Nexperia")
    (property "Sheetfile" "supply-oring.kicad_sch")
    (property "Sheetname" "Supply ORing")
    (property "dnp" "")
    (property "exclude_from_bom" "")
    (property "ki_description" "SCHOTTKY RECT 30V 5A, Vf=315 mV")
    (attr exclude_from_pos_files exclude_from_bom)
    (fp_text reference "D25" (at -1.015 1.78) (layer "B.SilkS")
        (effects (font (size 0.7 0.7) (thickness 0.15)) (justify left bottom mirror))
    )
    (fp_text value "PMEG3050EP,115" (at -4.37 -2.5) (layer "B.Fab") hide
        (effects (font (size 0.7 0.7) (thickness 0.15)) (justify left bottom mirror))
    )
    (fp_text user "Author: Antmicro" (at -4.37 -4.5) (layer "B.Fab") hide
        (effects (font (size 0.7 0.7) (thickness 0.15)) (justify left bottom mirror))
    )
    (fp_text user "${REFERENCE}" (at -4.37 -6.9) (layer "B.Fab") hide
        (effects (font (size 0.7 0.7) (thickness 0.15)) (justify left bottom mirror))
    )
    (fp_text user "License: Apache-2.0" (at -4.37 -5.7) (layer "B.Fab") hide
        (effects (font (size 0.7 0.7) (thickness 0.15)) (justify left bottom mirror))
    )
    (fp_line (start -2.121 -1.473) (end 2.12 -1.473)
      (stroke (width 0.15) (type solid)) (layer "B.SilkS"))
    (fp_line (start -2.121 -1.284) (end -2.121 -1.473)
      (stroke (width 0.15) (type solid)) (layer "B.SilkS"))
    (fp_line (start -2.121 1.474) (end -2.121 1.287)
      (stroke (width 0.15) (type solid)) (layer "B.SilkS"))
    (fp_line (start -1.6 1.4) (end -1.6 -1.4)
      (stroke (width 0.12) (type solid)) (layer "B.SilkS"))
    (fp_line (start 2.12 -1.473) (end 2.12 -1.284)
      (stroke (width 0.15) (type solid)) (layer "B.SilkS"))
    (fp_line (start 2.12 1.287) (end 2.12 1.474)
      (stroke (width 0.15) (type solid)) (layer "B.SilkS"))
    (fp_line (start 2.12 1.474) (end -2.121 1.474)
      (stroke (width 0.15) (type solid)) (layer "B.SilkS"))
    (fp_rect (start -2.8 1.6) (end 2.8 -1.6)
      (stroke (width 0.05) (type solid)) (fill none) (layer "B.CrtYd"))
    (fp_line (start -2.503 -0.952) (end -1.994 -0.952)
      (stroke (width 0.15) (type solid)) (layer "B.Fab"))
    (fp_line (start -2.503 0.954) (end -2.503 -0.952)
      (stroke (width 0.15) (type solid)) (layer "B.Fab"))
    (fp_line (start -1.994 -1.346) (end 1.993 -1.346)
      (stroke (width 0.15) (type solid)) (layer "B.Fab"))
    (fp_line (start -1.994 -0.952) (end -1.994 0.954)
      (stroke (width 0.15) (type solid)) (layer "B.Fab"))
    (fp_line (start -1.994 -0.673) (end -1.321 -1.346)
      (stroke (width 0.15) (type solid)) (layer "B.Fab"))
    (fp_line (start -1.994 0.675) (end -1.321 1.347)
      (stroke (width 0.15) (type solid)) (layer "B.Fab"))
    (fp_line (start -1.994 0.954) (end -2.503 0.954)
      (stroke (width 0.15) (type solid)) (layer "B.Fab"))
    (fp_line (start -1.994 1.347) (end -1.994 -1.346)
      (stroke (width 0.15) (type solid)) (layer "B.Fab"))
    (fp_line (start 1.993 -1.346) (end 1.993 1.347)
      (stroke (width 0.15) (type solid)) (layer "B.Fab"))
    (fp_line (start 1.993 -0.952) (end 2.5 -0.952)
      (stroke (width 0.15) (type solid)) (layer "B.Fab"))
    (fp_line (start 1.993 0.954) (end 1.993 -0.952)
      (stroke (width 0.15) (type solid)) (layer "B.Fab"))
    (fp_line (start 1.993 1.347) (end -1.994 1.347)
      (stroke (width 0.15) (type solid)) (layer "B.Fab"))
    (fp_line (start 2.5 -0.952) (end 2.5 0.954)
      (stroke (width 0.15) (type solid)) (layer "B.Fab"))
    (fp_line (start 2.5 0.954) (end 1.993 0.954)
      (stroke (width 0.15) (type solid)) (layer "B.Fab"))
    (pad "1" smd rect (at -2.298 0 180) (size 0.8096 1.905) (layers "B.Cu" "B.Paste" "B.Mask")
      (net 14 "/Power Supply/DC/DC conventers/DC_MAIN_BUS") (pinfunction "1") (pintype "passive"))
    (pad "2" smd rect (at 2.297 0 180) (size 0.8096 1.905) (layers "B.Cu" "B.Paste" "B.Mask")
      (net 22 "/Power Supply/DC Input/DC_IN") (pinfunction "2") (pintype "passive"))
  )

  (footprint "kria-k26-devboard-footprints:SOT-563" (layer "B.Cu")
    (at 115.72 74.21 90)
    (property "Author" "Antmicro")
    (property "License" "Apache-2.0")
    (property "MPN" "82400152")
    (property "Manufacturer" "Würth Elektronik")
    (property "Sheetfile" "usb.kicad_sch")
    (property "Sheetname" "USB")
    (property "ki_description" "TVS diode")
    (property "ki_keywords" "SMT, DIODE, IC, ESD, TVS")
    (attr smd)
    (fp_text reference "U27" (at -1.1 1.97 90) (layer "B.SilkS")
        (effects (font (size 0.7 0.7) (thickness 0.15)) (justify right bottom mirror))
    )
    (fp_text value "82400152" (at 0 -2 90) (layer "B.Fab") hide
        (effects (font (size 0.7 0.7) (thickness 0.15)) (justify right bottom mirror))
    )
    (fp_text user "${REFERENCE}" (at -1.299 -7.323 90) (layer "B.Fab") hide
        (effects (font (size 0.7 0.7) (thickness 0.15)) (justify right bottom mirror))
    )
    (fp_text user "License: Apache-2.0" (at -1.299 -4.924 90) (layer "B.Fab") hide
        (effects (font (size 0.7 0.7) (thickness 0.15)) (justify right bottom mirror))
    )
    (fp_text user "Author: Antmicro" (at -1.299 -6.124 90) (layer "B.Fab") hide
        (effects (font (size 0.7 0.7) (thickness 0.15)) (justify right bottom mirror))
    )
    (fp_line (start -0.778 -0.949) (end -0.424 -0.949)
      (stroke (width 0.15) (type solid)) (layer "B.SilkS"))
    (fp_line (start -0.778 -0.776) (end -0.778 -0.949)
      (stroke (width 0.15) (type solid)) (layer "B.SilkS"))
    (fp_line (start -0.499 0.974) (end -0.724 0.778)
      (stroke (width 0.15) (type solid)) (layer "B.SilkS"))
    (fp_line (start 0.776 -0.972) (end 0.526 -0.972)
      (stroke (width 0.15) (type solid)) (layer "B.SilkS"))
    (fp_line (start 0.776 -0.776) (end 0.776 -0.972)
      (stroke (width 0.15) (type solid)) (layer "B.SilkS"))
    (fp_line (start 0.776 0.974) (end 0.526 0.974)
      (stroke (width 0.15) (type solid)) (layer "B.SilkS"))
    (fp_line (start 0.776 0.974) (end 0.776 0.778)
      (stroke (width 0.15) (type solid)) (layer "B.SilkS"))
    (fp_circle (center -0.903 0.999) (end -0.952 0.95)
      (stroke (width 0.15) (type solid)) (fill solid) (layer "B.SilkS"))
    (fp_rect (start 1.19 1.12) (end -1.2 -1.1)
      (stroke (width 0.05) (type solid)) (fill none) (layer "B.CrtYd"))
    (fp_line (start -0.653 0.678) (end -0.653 -0.847)
      (stroke (width 0.15) (type solid)) (layer "B.Fab"))
    (fp_line (start -0.453 0.849) (end -0.653 0.678)
      (stroke (width 0.15) (type solid)) (layer "B.Fab"))
    (fp_line (start -0.453 0.849) (end 0.651 0.849)
      (stroke (width 0.15) (type solid)) (layer "B.Fab"))
    (fp_line (start 0.651 -0.847) (end -0.653 -0.847)
      (stroke (width 0.15) (type solid)) (layer "B.Fab"))
    (fp_line (start 0.651 0.849) (end 0.651 -0.847)
      (stroke (width 0.15) (type solid)) (layer "B.Fab"))
    (pad "1" smd roundrect (at -0.749 0.499 180) (size 0.3 0.6) (layers "B.Cu" "B.Paste" "B.Mask") (roundrect_rratio 0.25)
      (net 71 "/USB/USB3_N") (pintype "passive"))
    (pad "2" smd roundrect (at -0.749 -0.001 180) (size 0.3 0.6) (layers "B.Cu" "B.Paste" "B.Mask") (roundrect_rratio 0.25)
      (net 1 "GND") (pintype "passive"))
    (pad "3" smd roundrect (at -0.749 -0.497 180) (size 0.3 0.6) (layers "B.Cu" "B.Paste" "B.Mask") (roundrect_rratio 0.25)
      (net 72 "/USB/USB3_P") (pintype "passive"))
    (pad "4" smd roundrect (at 0.747 -0.497 180) (size 0.3 0.6) (layers "B.Cu" "B.Paste" "B.Mask") (roundrect_rratio 0.25)
      (net 291 "/USB/USB3_TVS_P") (pintype "passive"))
    (pad "5" smd roundrect (at 0.747 -0.001 180) (size 0.3 0.6) (layers "B.Cu" "B.Paste" "B.Mask") (roundrect_rratio 0.25)
      (net 86 "/USB/USB3_VBUS") (pintype "passive"))
    (pad "6" smd roundrect (at 0.747 0.499 180) (size 0.3 0.6) (layers "B.Cu" "B.Paste" "B.Mask") (roundrect_rratio 0.25)
      (net 290 "/USB/USB3_TVS_N") (pintype "passive"))
  )

  (footprint "kria-k26-devboard-footprints:C_0402_1005Metric" (layer "B.Cu")
    (at 134.225 122.050277 180)
    (descr "Capacitor SMD 0402")
    (tags "capacitor SMD 0402")
    (property "Author" "Antmicro")
    (property "Dielectric" "X5R")
    (property "License" "Apache-2.0")
    (property "MPN" "GRM155R61H104KE14D")
    (property "Manufacturer" "Murata")
    (property "Sheetfile" "pcie-m2-key-e.kicad_sch")
    (property "Sheetname" "PCIE M2 key E ")
    (property "Val" "100n")
    (property "Voltage" "50V")
    (property "ki_description" " ")
    (attr smd)
    (fp_text reference "C234" (at -3.785 -0.379724) (layer "B.SilkS")
        (effects (font (size 0.7 0.7) (thickness 0.15)) (justify left bottom mirror))
    )
    (fp_text value "C_100n_0402" (at 0 -1.4) (layer "B.Fab") hide
        (effects (font (size 0.7 0.7) (thickness 0.15)) (justify left bottom mirror))
    )
    (fp_text user "Author: Antmicro" (at -0.932 -4.17) (layer "B.Fab") hide
        (effects (font (size 0.7 0.7) (thickness 0.15)) (justify left bottom mirror))
    )
    (fp_text user "${REFERENCE}" (at -0.932 -3.168) (layer "B.Fab") hide
        (effects (font (size 0.7 0.7) (thickness 0.15)) (justify left bottom mirror))
    )
    (fp_text user "License: Apache-2.0" (at -0.932 -5.17) (layer "B.Fab") hide
        (effects (font (size 0.7 0.7) (thickness 0.15)) (justify left bottom mirror))
    )
    (fp_rect (start -0.94 0.47) (end 0.94 -0.47)
      (stroke (width 0.05) (type solid)) (fill none) (layer "B.CrtYd"))
    (fp_rect (start -0.499 0.249) (end 0.499 -0.249)
      (stroke (width 0.15) (type solid)) (fill none) (layer "B.Fab"))
    (pad "1" smd roundrect (at -0.484 0 180) (size 0.59 0.64) (layers "B.Cu" "B.Paste" "B.Mask") (roundrect_rratio 0.25)
      (net 90 "/PCIE M2 key E /GTR_DP3_M2C_N") (pintype "passive"))
    (pad "2" smd roundrect (at 0.484 0 180) (size 0.59 0.64) (layers "B.Cu" "B.Paste" "B.Mask") (roundrect_rratio 0.25)
      (net 91 "/PCIE M2 key E /GTR_DP3_M2C_C_N") (pintype "passive"))
  )

  (footprint "kria-k26-devboard-footprints:C_0402_1005Metric" (layer "B.Cu")
    (at 134.225 123.000276 180)
    (descr "Capacitor SMD 0402")
    (tags "capacitor SMD 0402")
    (property "Author" "Antmicro")
    (property "Dielectric" "X5R")
    (property "License" "Apache-2.0")
    (property "MPN" "GRM155R61H104KE14D")
    (property "Manufacturer" "Murata")
    (property "Sheetfile" "pcie-m2-key-e.kicad_sch")
    (property "Sheetname" "PCIE M2 key E ")
    (property "Val" "100n")
    (property "Voltage" "50V")
    (property "ki_description" " ")
    (attr smd)
    (fp_text reference "C233" (at -3.785 -0.379724) (layer "B.SilkS")
        (effects (font (size 0.7 0.7) (thickness 0.15)) (justify left bottom mirror))
    )
    (fp_text value "C_100n_0402" (at 0 -1.4) (layer "B.Fab") hide
        (effects (font (size 0.7 0.7) (thickness 0.15)) (justify left bottom mirror))
    )
    (fp_text user "Author: Antmicro" (at -0.932 -4.17) (layer "B.Fab") hide
        (effects (font (size 0.7 0.7) (thickness 0.15)) (justify left bottom mirror))
    )
    (fp_text user "${REFERENCE}" (at -0.932 -3.168) (layer "B.Fab") hide
        (effects (font (size 0.7 0.7) (thickness 0.15)) (justify left bottom mirror))
    )
    (fp_text user "License: Apache-2.0" (at -0.932 -5.17) (layer "B.Fab") hide
        (effects (font (size 0.7 0.7) (thickness 0.15)) (justify left bottom mirror))
    )
    (fp_rect (start -0.94 0.47) (end 0.94 -0.47)
      (stroke (width 0.05) (type solid)) (fill none) (layer "B.CrtYd"))
    (fp_rect (start -0.499 0.249) (end 0.499 -0.249)
      (stroke (width 0.15) (type solid)) (fill none) (layer "B.Fab"))
    (pad "1" smd roundrect (at -0.484 0 180) (size 0.59 0.64) (layers "B.Cu" "B.Paste" "B.Mask") (roundrect_rratio 0.25)
      (net 88 "/PCIE M2 key E /GTR_DP3_M2C_P") (pintype "passive"))
    (pad "2" smd roundrect (at 0.484 0 180) (size 0.59 0.64) (layers "B.Cu" "B.Paste" "B.Mask") (roundrect_rratio 0.25)
      (net 89 "/PCIE M2 key E /GTR_DP3_M2C_C_P") (pintype "passive"))
  )

  (footprint "kria-k26-devboard-footprints:R_0402_1005Metric" (layer "B.Cu")
    (at 173.225 125.35 90)
    (descr "Resistor SMD 0402")
    (tags "resistor SMD 0402")
    (property "Author" "Antmicro")
    (property "License" "Apache-2.0")
    (property "MPN" "CR0402-FX-1003GLF")
    (property "Manufacturer" "Bourns")
    (property "Sheetfile" "dc-dc-conventers.kicad_sch")
    (property "Sheetname" "DC/DC conventers")
    (property "Tolerance" "1%")
    (property "Val" "100k")
    (property "ki_description" "100k resistor in 0402 package with 1% tolerance")
    (attr smd)
    (fp_text reference "R119" (at 1.4 1.325 270) (layer "B.SilkS")
        (effects (font (size 0.7 0.7) (thickness 0.15)) (justify left bottom mirror))
    )
    (fp_text value "R_100k_0402" (at 0 -1.4 270) (layer "B.Fab") hide
        (effects (font (size 0.7 0.7) (thickness 0.15)) (justify left bottom mirror))
    )
    (fp_text user "License: Apache-2.0" (at -0.95 -5.169 270) (layer "B.Fab") hide
        (effects (font (size 0.7 0.7) (thickness 0.15)) (justify left bottom mirror))
    )
    (fp_text user "Author: Antmicro" (at -0.95 -4.169 270) (layer "B.Fab") hide
        (effects (font (size 0.7 0.7) (thickness 0.15)) (justify left bottom mirror))
    )
    (fp_text user "${REFERENCE}" (at -0.95 -3.168 270) (layer "B.Fab") hide
        (effects (font (size 0.7 0.7) (thickness 0.15)) (justify left bottom mirror))
    )
    (fp_rect (start -0.93 0.47) (end 0.93 -0.47)
      (stroke (width 0.05) (type solid)) (fill none) (layer "B.CrtYd"))
    (fp_rect (start -0.5 0.25) (end 0.5 -0.25)
      (stroke (width 0.15) (type solid)) (fill none) (layer "B.Fab"))
    (pad "1" smd roundrect (at -0.485 0 90) (size 0.59 0.64) (layers "B.Cu" "B.Paste" "B.Mask") (roundrect_rratio 0.25)
      (net 686 "Net-(U48-EN)") (pintype "passive"))
    (pad "2" smd roundrect (at 0.485 0 90) (size 0.59 0.64) (layers "B.Cu" "B.Paste" "B.Mask") (roundrect_rratio 0.25)
      (net 14 "/Power Supply/DC/DC conventers/DC_MAIN_BUS") (pintype "passive"))
  )

  (footprint "kria-k26-devboard-footprints:R_0402_1005Metric" (layer "B.Cu")
    (at 176.29 126.95 180)
    (descr "Resistor SMD 0402")
    (tags "resistor SMD 0402")
    (property "Author" "Antmicro")
    (property "License" "Apache-2.0")
    (property "MPN" "CR0402-FX-2201GLF")
    (property "Manufacturer" "Bourns")
    (property "Sheetfile" "dc-dc-conventers.kicad_sch")
    (property "Sheetname" "DC/DC conventers")
    (property "Tolerance" "1%")
    (property "Val" "2k2")
    (property "ki_description" "2k2 resistor in 0402 package with 1% tolerance")
    (attr smd)
    (fp_text reference "R120" (at -1.33 0.55) (layer "B.SilkS")
        (effects (font (size 0.7 0.7) (thickness 0.15)) (justify left bottom mirror))
    )
    (fp_text value "R_2k2_0402" (at 0 -1.4) (layer "B.Fab") hide
        (effects (font (size 0.7 0.7) (thickness 0.15)) (justify left bottom mirror))
    )
    (fp_text user "License: Apache-2.0" (at -0.95 -5.169) (layer "B.Fab") hide
        (effects (font (size 0.7 0.7) (thickness 0.15)) (justify left bottom mirror))
    )
    (fp_text user "${REFERENCE}" (at -0.95 -3.168) (layer "B.Fab") hide
        (effects (font (size 0.7 0.7) (thickness 0.15)) (justify left bottom mirror))
    )
    (fp_text user "Author: Antmicro" (at -0.95 -4.169) (layer "B.Fab") hide
        (effects (font (size 0.7 0.7) (thickness 0.15)) (justify left bottom mirror))
    )
    (fp_rect (start -0.93 0.47) (end 0.93 -0.47)
      (stroke (width 0.05) (type solid)) (fill none) (layer "B.CrtYd"))
    (fp_rect (start -0.5 0.25) (end 0.5 -0.25)
      (stroke (width 0.15) (type solid)) (fill none) (layer "B.Fab"))
    (pad "1" smd roundrect (at -0.485 0 180) (size 0.59 0.64) (layers "B.Cu" "B.Paste" "B.Mask") (roundrect_rratio 0.25)
      (net 329 "Net-(D12-Pad1)") (pintype "passive"))
    (pad "2" smd roundrect (at 0.485 0 180) (size 0.59 0.64) (layers "B.Cu" "B.Paste" "B.Mask") (roundrect_rratio 0.25)
      (net 773 "/Power Supply/DC/DC conventers/SOM_5V_OUT") (pintype "passive"))
  )

  (footprint "kria-k26-devboard-footprints:C_0402_1005Metric" (layer "B.Cu")
    (at 144.57 74 180)
    (descr "Capacitor SMD 0402")
    (tags "capacitor SMD 0402")
    (property "Author" "Antmicro")
    (property "Dielectric" "")
    (property "License" "Apache-2.0")
    (property "MPN" "GRM155R71H392KA01D")
    (property "Manufacturer" "Murata")
    (property "Sheetfile" "dc-dc-conventers.kicad_sch")
    (property "Sheetname" "DC/DC conventers")
    (property "Val" "3n9")
    (property "Voltage" "")
    (property "ki_description" " ")
    (attr smd)
    (fp_text reference "C189" (at 0.825 -0.44) (layer "B.SilkS")
        (effects (font (size 0.7 0.7) (thickness 0.15)) (justify left bottom mirror))
    )
    (fp_text value "C_3n9_0402" (at 0 -1.4) (layer "B.Fab") hide
        (effects (font (size 0.7 0.7) (thickness 0.15)) (justify left bottom mirror))
    )
    (fp_text user "Author: Antmicro" (at -0.932 -4.17) (layer "B.Fab") hide
        (effects (font (size 0.7 0.7) (thickness 0.15)) (justify left bottom mirror))
    )
    (fp_text user "${REFERENCE}" (at -0.932 -3.168) (layer "B.Fab") hide
        (effects (font (size 0.7 0.7) (thickness 0.15)) (justify left bottom mirror))
    )
    (fp_text user "License: Apache-2.0" (at -0.932 -5.17) (layer "B.Fab") hide
        (effects (font (size 0.7 0.7) (thickness 0.15)) (justify left bottom mirror))
    )
    (fp_rect (start -0.94 0.47) (end 0.94 -0.47)
      (stroke (width 0.05) (type solid)) (fill none) (layer "B.CrtYd"))
    (fp_rect (start -0.499 0.249) (end 0.499 -0.249)
      (stroke (width 0.15) (type solid)) (fill none) (layer "B.Fab"))
    (pad "1" smd roundrect (at -0.484 0 180) (size 0.59 0.64) (layers "B.Cu" "B.Paste" "B.Mask") (roundrect_rratio 0.25)
      (net 250 "Net-(U47-SS)") (pintype "passive"))
    (pad "2" smd roundrect (at 0.484 0 180) (size 0.59 0.64) (layers "B.Cu" "B.Paste" "B.Mask") (roundrect_rratio 0.25)
      (net 1 "GND") (pintype "passive"))
  )

  (footprint "kria-k26-devboard-footprints:C_0402_1005Metric" (layer "B.Cu")
    (at 150.61 71.36)
    (descr "Capacitor SMD 0402")
    (tags "capacitor SMD 0402")
    (property "Author" "Antmicro")
    (property "Dielectric" "X5R")
    (property "License" "Apache-2.0")
    (property "MPN" "GRM155R61H104KE14D")
    (property "Manufacturer" "Murata")
    (property "Sheetfile" "dc-dc-conventers.kicad_sch")
    (property "Sheetname" "DC/DC conventers")
    (property "Val" "100n")
    (property "Voltage" "50V")
    (property "ki_description" " ")
    (attr smd)
    (fp_text reference "C191" (at 1.18 -0.58 180) (layer "B.SilkS")
        (effects (font (size 0.7 0.7) (thickness 0.15)) (justify left bottom mirror))
    )
    (fp_text value "C_100n_0402" (at 0 -1.4 180) (layer "B.Fab") hide
        (effects (font (size 0.7 0.7) (thickness 0.15)) (justify left bottom mirror))
    )
    (fp_text user "Author: Antmicro" (at -0.932 -4.17 180) (layer "B.Fab") hide
        (effects (font (size 0.7 0.7) (thickness 0.15)) (justify left bottom mirror))
    )
    (fp_text user "License: Apache-2.0" (at -0.932 -5.17 180) (layer "B.Fab") hide
        (effects (font (size 0.7 0.7) (thickness 0.15)) (justify left bottom mirror))
    )
    (fp_text user "${REFERENCE}" (at -0.932 -3.168 180) (layer "B.Fab") hide
        (effects (font (size 0.7 0.7) (thickness 0.15)) (justify left bottom mirror))
    )
    (fp_rect (start -0.94 0.47) (end 0.94 -0.47)
      (stroke (width 0.05) (type solid)) (fill none) (layer "B.CrtYd"))
    (fp_rect (start -0.499 0.249) (end 0.499 -0.249)
      (stroke (width 0.15) (type solid)) (fill none) (layer "B.Fab"))
    (pad "1" smd roundrect (at -0.484 0) (size 0.59 0.64) (layers "B.Cu" "B.Paste" "B.Mask") (roundrect_rratio 0.25)
      (net 252 "Net-(U47-BOOT)") (pintype "passive"))
    (pad "2" smd roundrect (at 0.484 0) (size 0.59 0.64) (layers "B.Cu" "B.Paste" "B.Mask") (roundrect_rratio 0.25)
      (net 365 "/Power Supply/DC/DC conventers/SW_USB_5V") (pintype "passive"))
  )

  (footprint "kria-k26-devboard-footprints:C_0402_1005Metric" (layer "B.Cu")
    (at 144.56 76.14 -90)
    (descr "Capacitor SMD 0402")
    (tags "capacitor SMD 0402")
    (property "Author" "Antmicro")
    (property "Dielectric" "")
    (property "License" "Apache-2.0")
    (property "MPN" "CC0402JRNPO9BN220")
    (property "Manufacturer" "Yaego")
    (property "Sheetfile" "dc-dc-conventers.kicad_sch")
    (property "Sheetname" "DC/DC conventers")
    (property "Val" "22p")
    (property "Voltage" "")
    (property "ki_description" " ")
    (attr smd)
    (fp_text reference "C193" (at -1.53 2.36 90) (layer "B.SilkS")
        (effects (font (size 0.7 0.7) (thickness 0.15)) (justify left bottom mirror))
    )
    (fp_text value "C_22p_0402" (at 0 -1.4 90) (layer "B.Fab") hide
        (effects (font (size 0.7 0.7) (thickness 0.15)) (justify left bottom mirror))
    )
    (fp_text user "License: Apache-2.0" (at -0.932 -5.17 90) (layer "B.Fab") hide
        (effects (font (size 0.7 0.7) (thickness 0.15)) (justify left bottom mirror))
    )
    (fp_text user "${REFERENCE}" (at -0.932 -3.168 90) (layer "B.Fab") hide
        (effects (font (size 0.7 0.7) (thickness 0.15)) (justify left bottom mirror))
    )
    (fp_text user "Author: Antmicro" (at -0.932 -4.17 90) (layer "B.Fab") hide
        (effects (font (size 0.7 0.7) (thickness 0.15)) (justify left bottom mirror))
    )
    (fp_rect (start -0.94 0.47) (end 0.94 -0.47)
      (stroke (width 0.05) (type solid)) (fill none) (layer "B.CrtYd"))
    (fp_rect (start -0.499 0.249) (end 0.499 -0.249)
      (stroke (width 0.15) (type solid)) (fill none) (layer "B.Fab"))
    (pad "1" smd roundrect (at -0.484 0 270) (size 0.59 0.64) (layers "B.Cu" "B.Paste" "B.Mask") (roundrect_rratio 0.25)
      (net 254 "Net-(U47-FB)") (pintype "passive"))
    (pad "2" smd roundrect (at 0.484 0 270) (size 0.59 0.64) (layers "B.Cu" "B.Paste" "B.Mask") (roundrect_rratio 0.25)
      (net 772 "/Power Supply/DC/DC conventers/USB_5V_OUT") (pintype "passive"))
  )

  (footprint "kria-k26-devboard-footprints:C_0603_1608Metric" (layer "B.Cu")
    (at 147.335 69.76 180)
    (descr "Capacitor SMD 0603")
    (tags "capacitor 0603")
    (property "Author" "Antmicro")
    (property "Dielectric" "")
    (property "License" "Apache-2.0")
    (property "MPN" "C1608X5R1E106M080AC")
    (property "Manufacturer" "TDK")
    (property "Sheetfile" "dc-dc-conventers.kicad_sch")
    (property "Sheetname" "DC/DC conventers")
    (property "Val" "10u/25V")
    (property "Voltage" "")
    (property "ki_description" " ")
    (attr smd)
    (fp_text reference "C183" (at -1.465 1.64) (layer "B.SilkS")
        (effects (font (size 0.7 0.7) (thickness 0.15)) (justify left bottom mirror))
    )
    (fp_text value "C_10u_25V_0603" (at 0 -1.6) (layer "B.Fab") hide
        (effects (font (size 0.7 0.7) (thickness 0.15)) (justify left bottom mirror))
    )
    (fp_text user "${REFERENCE}" (at -1.682 -3.895) (layer "B.Fab") hide
        (effects (font (size 0.7 0.7) (thickness 0.15)) (justify left bottom mirror))
    )
    (fp_text user "License: Apache-2.0" (at -1.682 -5.895) (layer "B.Fab") hide
        (effects (font (size 0.7 0.7) (thickness 0.15)) (justify left bottom mirror))
    )
    (fp_text user "Author: Antmicro" (at -1.682 -4.894) (layer "B.Fab") hide
        (effects (font (size 0.7 0.7) (thickness 0.15)) (justify left bottom mirror))
    )
    (fp_line (start -0.3 -0.3) (end 0.3 -0.3)
      (stroke (width 0.15) (type solid)) (layer "B.SilkS"))
    (fp_line (start -0.3 0.3) (end 0.3 0.3)
      (stroke (width 0.15) (type solid)) (layer "B.SilkS"))
    (fp_rect (start -1.24 0.7) (end 1.24 -0.7)
      (stroke (width 0.05) (type solid)) (fill none) (layer "B.CrtYd"))
    (fp_rect (start -0.8 0.4) (end 0.8 -0.4)
      (stroke (width 0.15) (type solid)) (fill none) (layer "B.Fab"))
    (pad "1" smd roundrect (at -0.7 0 180) (size 0.6 0.8) (layers "B.Cu" "B.Paste" "B.Mask") (roundrect_rratio 0.2)
      (net 14 "/Power Supply/DC/DC conventers/DC_MAIN_BUS") (pintype "passive"))
    (pad "2" smd roundrect (at 0.7 0 180) (size 0.6 0.8) (layers "B.Cu" "B.Paste" "B.Mask") (roundrect_rratio 0.2)
      (net 1 "GND") (pintype "passive"))
  )

  (footprint "kria-k26-devboard-footprints:L_Coilcraft-XEL4030" (layer "B.Cu")
    (at 151.875 74.3 -90)
    (property "Author" "Antmicro")
    (property "IMax" "")
    (property "ISat" "")
    (property "License" "Apache-2.0")
    (property "MPN" "XEL4030-332MEC")
    (property "Manufacturer" "Coilcraft")
    (property "Sheetfile" "dc-dc-conventers.kicad_sch")
    (property "Sheetname" "DC/DC conventers")
    (property "Size" "4x4")
    (property "Val" "3u3/5.9A")
    (attr smd)
    (fp_text reference "L1" (at 2.13 -3.595 180) (layer "B.SilkS")
        (effects (font (size 0.7 0.7) (thickness 0.15)) (justify left bottom mirror))
    )
    (fp_text value "L_3u3_5.9A_XEL4030" (at 0.05 -2.996 90) (layer "B.Fab") hide
        (effects (font (size 0.7 0.7) (thickness 0.15)) (justify left bottom mirror))
    )
    (fp_text user "${REFERENCE}" (at -2.15 -4.996 90) (layer "B.Fab") hide
        (effects (font (size 0.7 0.7) (thickness 0.15)) (justify left bottom mirror))
    )
    (fp_text user "Author: Antmicro" (at -2.15 -5.996 90) (layer "B.Fab") hide
        (effects (font (size 0.7 0.7) (thickness 0.15)) (justify left bottom mirror))
    )
    (fp_text user "License: Apache-2.0" (at -2.15 -6.996 90) (layer "B.Fab") hide
        (effects (font (size 0.7 0.7) (thickness 0.15)) (justify left bottom mirror))
    )
    (fp_line (start -1.8 -2.2) (end 1.85 -2.199)
      (stroke (width 0.15) (type solid)) (layer "B.SilkS"))
    (fp_line (start -1.8 2.2) (end 1.85 2.201)
      (stroke (width 0.15) (type solid)) (layer "B.SilkS"))
    (fp_rect (start -2.45 2.45) (end 2.45 -2.45)
      (stroke (width 0.05) (type solid)) (fill none) (layer "B.CrtYd"))
    (fp_line (start -2 -1.999) (end -2 2)
      (stroke (width 0.15) (type solid)) (layer "B.Fab"))
    (fp_line (start -2 2) (end 1.999 2)
      (stroke (width 0.15) (type solid)) (layer "B.Fab"))
    (fp_line (start 1.999 -1.999) (end -2 -1.999)
      (stroke (width 0.15) (type solid)) (layer "B.Fab"))
    (fp_line (start 1.999 2) (end 1.999 -1.999)
      (stroke (width 0.15) (type solid)) (layer "B.Fab"))
    (pad "1" smd rect (at -1.186 0 270) (size 0.98 3.4) (layers "B.Cu" "B.Paste" "B.Mask")
      (net 365 "/Power Supply/DC/DC conventers/SW_USB_5V") (pintype "passive"))
    (pad "2" smd rect (at 1.185 0 270) (size 0.98 3.4) (layers "B.Cu" "B.Paste" "B.Mask")
      (net 772 "/Power Supply/DC/DC conventers/USB_5V_OUT") (pintype "passive"))
  )

  (footprint "kria-k26-devboard-footprints:C_0603_1608Metric" (layer "B.Cu")
    (at 148.375 77.4 180)
    (descr "Capacitor SMD 0603")
    (tags "capacitor 0603")
    (property "Author" "Antmicro")
    (property "Dielectric" "")
    (property "License" "Apache-2.0")
    (property "MPN" "CL10A226MO7JZNC")
    (property "Manufacturer" "Samsung")
    (property "Sheetfile" "dc-dc-conventers.kicad_sch")
    (property "Sheetname" "DC/DC conventers")
    (property "Val" "22u/16V")
    (property "Voltage" "")
    (property "ki_description" " ")
    (attr smd)
    (fp_text reference "C197" (at -0.515 -2.28) (layer "B.SilkS")
        (effects (font (size 0.7 0.7) (thickness 0.15)) (justify left bottom mirror))
    )
    (fp_text value "C_22u_16V_0603" (at 0 -1.6) (layer "B.Fab") hide
        (effects (font (size 0.7 0.7) (thickness 0.15)) (justify left bottom mirror))
    )
    (fp_text user "Author: Antmicro" (at -1.682 -4.894) (layer "B.Fab") hide
        (effects (font (size 0.7 0.7) (thickness 0.15)) (justify left bottom mirror))
    )
    (fp_text user "${REFERENCE}" (at -1.682 -3.895) (layer "B.Fab") hide
        (effects (font (size 0.7 0.7) (thickness 0.15)) (justify left bottom mirror))
    )
    (fp_text user "License: Apache-2.0" (at -1.682 -5.895) (layer "B.Fab") hide
        (effects (font (size 0.7 0.7) (thickness 0.15)) (justify left bottom mirror))
    )
    (fp_line (start -0.3 -0.3) (end 0.3 -0.3)
      (stroke (width 0.15) (type solid)) (layer "B.SilkS"))
    (fp_line (start -0.3 0.3) (end 0.3 0.3)
      (stroke (width 0.15) (type solid)) (layer "B.SilkS"))
    (fp_rect (start -1.24 0.7) (end 1.24 -0.7)
      (stroke (width 0.05) (type solid)) (fill none) (layer "B.CrtYd"))
    (fp_rect (start -0.8 0.4) (end 0.8 -0.4)
      (stroke (width 0.15) (type solid)) (fill none) (layer "B.Fab"))
    (pad "1" smd roundrect (at -0.7 0 180) (size 0.6 0.8) (layers "B.Cu" "B.Paste" "B.Mask") (roundrect_rratio 0.2)
      (net 772 "/Power Supply/DC/DC conventers/USB_5V_OUT") (pintype "passive"))
    (pad "2" smd roundrect (at 0.7 0 180) (size 0.6 0.8) (layers "B.Cu" "B.Paste" "B.Mask") (roundrect_rratio 0.2)
      (net 1 "GND") (pintype "passive"))
  )

  (footprint "kria-k26-devboard-footprints:C_0603_1608Metric" (layer "B.Cu")
    (at 148.375 75.95 180)
    (descr "Capacitor SMD 0603")
    (tags "capacitor 0603")
    (property "Author" "Antmicro")
    (property "Dielectric" "")
    (property "License" "Apache-2.0")
    (property "MPN" "CL10A226MO7JZNC")
    (property "Manufacturer" "Samsung")
    (property "Sheetfile" "dc-dc-conventers.kicad_sch")
    (property "Sheetname" "DC/DC conventers")
    (property "Val" "22u/16V")
    (property "Voltage" "")
    (property "ki_description" " ")
    (attr smd)
    (fp_text reference "C199" (at -0.515 -2.86) (layer "B.SilkS")
        (effects (font (size 0.7 0.7) (thickness 0.15)) (justify left bottom mirror))
    )
    (fp_text value "C_22u_16V_0603" (at 0 -1.6) (layer "B.Fab") hide
        (effects (font (size 0.7 0.7) (thickness 0.15)) (justify left bottom mirror))
    )
    (fp_text user "Author: Antmicro" (at -1.682 -4.894) (layer "B.Fab") hide
        (effects (font (size 0.7 0.7) (thickness 0.15)) (justify left bottom mirror))
    )
    (fp_text user "${REFERENCE}" (at -1.682 -3.895) (layer "B.Fab") hide
        (effects (font (size 0.7 0.7) (thickness 0.15)) (justify left bottom mirror))
    )
    (fp_text user "License: Apache-2.0" (at -1.682 -5.895) (layer "B.Fab") hide
        (effects (font (size 0.7 0.7) (thickness 0.15)) (justify left bottom mirror))
    )
    (fp_line (start -0.3 -0.3) (end 0.3 -0.3)
      (stroke (width 0.15) (type solid)) (layer "B.SilkS"))
    (fp_line (start -0.3 0.3) (end 0.3 0.3)
      (stroke (width 0.15) (type solid)) (layer "B.SilkS"))
    (fp_rect (start -1.24 0.7) (end 1.24 -0.7)
      (stroke (width 0.05) (type solid)) (fill none) (layer "B.CrtYd"))
    (fp_rect (start -0.8 0.4) (end 0.8 -0.4)
      (stroke (width 0.15) (type solid)) (fill none) (layer "B.Fab"))
    (pad "1" smd roundrect (at -0.7 0 180) (size 0.6 0.8) (layers "B.Cu" "B.Paste" "B.Mask") (roundrect_rratio 0.2)
      (net 772 "/Power Supply/DC/DC conventers/USB_5V_OUT") (pintype "passive"))
    (pad "2" smd roundrect (at 0.7 0 180) (size 0.6 0.8) (layers "B.Cu" "B.Paste" "B.Mask") (roundrect_rratio 0.2)
      (net 1 "GND") (pintype "passive"))
  )

  (footprint "kria-k26-devboard-footprints:C_0402_1005Metric" (layer "B.Cu")
    (at 144.57 73 180)
    (descr "Capacitor SMD 0402")
    (tags "capacitor SMD 0402")
    (property "Author" "Antmicro")
    (property "Dielectric" "")
    (property "License" "Apache-2.0")
    (property "MPN" "C1005X6S1A105K050BC")
    (property "Manufacturer" "TDK")
    (property "Sheetfile" "dc-dc-conventers.kicad_sch")
    (property "Sheetname" "DC/DC conventers")
    (property "Val" "1u")
    (property "Voltage" "")
    (property "ki_description" " ")
    (attr smd)
    (fp_text reference "C187" (at 0.825 -0.44) (layer "B.SilkS")
        (effects (font (size 0.7 0.7) (thickness 0.15)) (justify left bottom mirror))
    )
    (fp_text value "C_1u_0402" (at 0 -1.4) (layer "B.Fab") hide
        (effects (font (size 0.7 0.7) (thickness 0.15)) (justify left bottom mirror))
    )
    (fp_text user "${REFERENCE}" (at -0.932 -3.168) (layer "B.Fab") hide
        (effects (font (size 0.7 0.7) (thickness 0.15)) (justify left bottom mirror))
    )
    (fp_text user "License: Apache-2.0" (at -0.932 -5.17) (layer "B.Fab") hide
        (effects (font (size 0.7 0.7) (thickness 0.15)) (justify left bottom mirror))
    )
    (fp_text user "Author: Antmicro" (at -0.932 -4.17) (layer "B.Fab") hide
        (effects (font (size 0.7 0.7) (thickness 0.15)) (justify left bottom mirror))
    )
    (fp_rect (start -0.94 0.47) (end 0.94 -0.47)
      (stroke (width 0.05) (type solid)) (fill none) (layer "B.CrtYd"))
    (fp_rect (start -0.499 0.249) (end 0.499 -0.249)
      (stroke (width 0.15) (type solid)) (fill none) (layer "B.Fab"))
    (pad "1" smd roundrect (at -0.484 0 180) (size 0.59 0.64) (layers "B.Cu" "B.Paste" "B.Mask") (roundrect_rratio 0.25)
      (net 248 "Net-(U47-PVCC)") (pintype "passive"))
    (pad "2" smd roundrect (at 0.484 0 180) (size 0.59 0.64) (layers "B.Cu" "B.Paste" "B.Mask") (roundrect_rratio 0.25)
      (net 1 "GND") (pintype "passive"))
  )

  (footprint "kria-k26-devboard-footprints:UQFN-13_2x3mm_P0.5mm" (layer "B.Cu")
    (at 147.675 73.55 90)
    (property "Author" "Antmicro")
    (property "License" "Apache-2.0")
    (property "MPN" "RT6236AHGQUF")
    (property "Manufacturer" "Richtek")
    (property "Sheetfile" "dc-dc-conventers.kicad_sch")
    (property "Sheetname" "DC/DC conventers")
    (property "ki_description" "DC-DC Switching Buck Step Down Regulator, Adjustable, 4.5V-18Vin, 700mV-8V/6A out, 650kHz, UQFN-13")
    (property "ki_keywords" "SMT, PMIC, IC, SWITCHING, VOLTAGE, REGULATOR, DC-DC")
    (attr smd)
    (fp_text reference "U47" (at 1.46 -1.615) (layer "B.SilkS")
        (effects (font (size 0.7 0.7) (thickness 0.15)) (justify left bottom mirror))
    )
    (fp_text value "RT6236AHGQUF" (at 0.812 -3.293 270) (layer "B.Fab") hide
        (effects (font (size 0.7 0.7) (thickness 0.15)) (justify left bottom mirror))
    )
    (fp_text user "License: Apache-2.0" (at -1.537 -7.693 270) (layer "B.Fab") hide
        (effects (font (size 0.7 0.7) (thickness 0.15)) (justify left bottom mirror))
    )
    (fp_text user "${REFERENCE}" (at -1.537 -5.294 270) (layer "B.Fab") hide
        (effects (font (size 0.7 0.7) (thickness 0.15)) (justify left bottom mirror))
    )
    (fp_text user "Author: Antmicro" (at -1.537 -6.493 270) (layer "B.Fab") hide
        (effects (font (size 0.7 0.7) (thickness 0.15)) (justify left bottom mirror))
    )
    (fp_circle (center -1.25 1.65) (end -1.2 1.65)
      (stroke (width 0.15) (type solid)) (fill solid) (layer "B.SilkS"))
    (fp_rect (start -1.65 2.15) (end 1.65 -2.15)
      (stroke (width 0.05) (type solid)) (fill none) (layer "B.CrtYd"))
    (fp_line (start -0.9 -1.3) (end -0.9 0.85)
      (stroke (width 0.15) (type solid)) (layer "B.Fab"))
    (fp_line (start -0.9 0.85) (end -0.45 1.3)
      (stroke (width 0.15) (type solid)) (layer "B.Fab"))
    (fp_line (start -0.45 1.3) (end 0.9 1.3)
      (stroke (width 0.15) (type solid)) (layer "B.Fab"))
    (fp_line (start 0.9 -1.3) (end -0.9 -1.3)
      (stroke (width 0.15) (type solid)) (layer "B.Fab"))
    (fp_line (start 0.9 1.3) (end 0.9 -1.3)
      (stroke (width 0.15) (type solid)) (layer "B.Fab"))
    (pad "1" smd roundrect (at -1 0.75 270) (size 0.8 0.3) (layers "B.Cu" "B.Paste" "B.Mask") (roundrect_rratio 0.25)
      (net 1 "GND") (pinfunction "GND") (pintype "power_in") (zone_connect 2))
    (pad "2" smd roundrect (at -1 0.25 270) (size 0.8 0.3) (layers "B.Cu" "B.Paste" "B.Mask") (roundrect_rratio 0.25)
      (net 685 "Net-(U47-EN)") (pinfunction "EN") (pintype "input") (zone_connect 2))
    (pad "3" smd roundrect (at -1 -0.248 270) (size 0.8 0.3) (layers "B.Cu" "B.Paste" "B.Mask") (roundrect_rratio 0.25)
      (net 254 "Net-(U47-FB)") (pinfunction "FB") (pintype "input") (zone_connect 2))
    (pad "4" smd roundrect (at -1 -0.748 270) (size 0.8 0.3) (layers "B.Cu" "B.Paste" "B.Mask") (roundrect_rratio 0.25)
      (net 779 "unconnected-(U47-NC-Pad4)") (pinfunction "NC") (pintype "no_connect") (zone_connect 2))
    (pad "5" smd roundrect (at -0.25 -0.998) (size 1.8 0.3) (layers "B.Cu" "B.Paste" "B.Mask") (roundrect_rratio 0.25)
      (net 250 "Net-(U47-SS)") (pinfunction "SS") (pintype "input") (zone_connect 2))
    (pad "6" smd roundrect (at 0.248 -0.998) (size 1.8 0.3) (layers "B.Cu" "B.Paste" "B.Mask") (roundrect_rratio 0.25)
      (net 248 "Net-(U47-PVCC)") (pinfunction "PVCC") (pintype "output") (zone_connect 2))
    (pad "7" smd roundrect (at 0.998 -0.748 270) (size 0.8 0.3) (layers "B.Cu" "B.Paste" "B.Mask") (roundrect_rratio 0.25)
      (net 780 "unconnected-(U47-NC-Pad7)") (pinfunction "NC") (pintype "no_connect") (zone_connect 2))
    (pad "8" smd roundrect (at 0.998 -0.248 270) (size 0.8 0.3) (layers "B.Cu" "B.Paste" "B.Mask") (roundrect_rratio 0.25)
      (net 781 "unconnected-(U47-PG-Pad8)") (pinfunction "PG") (pintype "output+no_connect") (zone_connect 2))
    (pad "9" smd roundrect (at 0.998 0.25 270) (size 0.8 0.3) (layers "B.Cu" "B.Paste" "B.Mask") (roundrect_rratio 0.25)
      (net 14 "/Power Supply/DC/DC conventers/DC_MAIN_BUS") (pinfunction "VIN") (pintype "passive") (zone_connect 2))
    (pad "10" smd roundrect (at 0.998 0.75 270) (size 0.8 0.3) (layers "B.Cu" "B.Paste" "B.Mask") (roundrect_rratio 0.25)
      (net 14 "/Power Supply/DC/DC conventers/DC_MAIN_BUS") (pinfunction "VIN") (pintype "power_in") (zone_connect 2))
    (pad "11" smd roundrect (at 0.583 1.476) (size 0.85 0.3) (layers "B.Cu" "B.Paste" "B.Mask") (roundrect_rratio 0.25)
      (net 252 "Net-(U47-BOOT)") (pinfunction "BOOT") (pintype "output") (zone_connect 2))
    (pad "12" smd roundrect (at -0.003 1.2 180) (size 1.4 0.47) (layers "B.Cu" "B.Paste" "B.Mask") (roundrect_rratio 0.25)
      (net 365 "/Power Supply/DC/DC conventers/SW_USB_5V") (pinfunction "SW") (pintype "power_out") (zone_connect 2))
    (pad "13" smd roundrect (at -0.585 1.476) (size 0.85 0.3) (layers "B.Cu" "B.Paste" "B.Mask") (roundrect_rratio 0.25)
      (net 1 "GND") (pinfunction "GND") (pintype "passive") (zone_connect 2))
  )

  (footprint "kria-k26-devboard-footprints:C_0603_1608Metric" (layer "B.Cu")
    (at 147.37 71.18 180)
    (descr "Capacitor SMD 0603")
    (tags "capacitor 0603")
    (property "Author" "Antmicro")
    (property "Dielectric" "")
    (property "License" "Apache-2.0")
    (property "MPN" "C1608X5R1E106M080AC")
    (property "Manufacturer" "TDK")
    (property "Sheetfile" "dc-dc-conventers.kicad_sch")
    (property "Sheetname" "DC/DC conventers")
    (property "Val" "10u/25V")
    (property "Voltage" "")
    (property "ki_description" " ")
    (attr smd)
    (fp_text reference "C185" (at -1.44 2.11) (layer "B.SilkS")
        (effects (font (size 0.7 0.7) (thickness 0.15)) (justify left bottom mirror))
    )
    (fp_text value "C_10u_25V_0603" (at 0 -1.6) (layer "B.Fab") hide
        (effects (font (size 0.7 0.7) (thickness 0.15)) (justify left bottom mirror))
    )
    (fp_text user "Author: Antmicro" (at -1.682 -4.894) (layer "B.Fab") hide
        (effects (font (size 0.7 0.7) (thickness 0.15)) (justify left bottom mirror))
    )
    (fp_text user "${REFERENCE}" (at -1.682 -3.895) (layer "B.Fab") hide
        (effects (font (size 0.7 0.7) (thickness 0.15)) (justify left bottom mirror))
    )
    (fp_text user "License: Apache-2.0" (at -1.682 -5.895) (layer "B.Fab") hide
        (effects (font (size 0.7 0.7) (thickness 0.15)) (justify left bottom mirror))
    )
    (fp_line (start -0.3 -0.3) (end 0.3 -0.3)
      (stroke (width 0.15) (type solid)) (layer "B.SilkS"))
    (fp_line (start -0.3 0.3) (end 0.3 0.3)
      (stroke (width 0.15) (type solid)) (layer "B.SilkS"))
    (fp_rect (start -1.24 0.7) (end 1.24 -0.7)
      (stroke (width 0.05) (type solid)) (fill none) (layer "B.CrtYd"))
    (fp_rect (start -0.8 0.4) (end 0.8 -0.4)
      (stroke (width 0.15) (type solid)) (fill none) (layer "B.Fab"))
    (pad "1" smd roundrect (at -0.7 0 180) (size 0.6 0.8) (layers "B.Cu" "B.Paste" "B.Mask") (roundrect_rratio 0.2)
      (net 14 "/Power Supply/DC/DC conventers/DC_MAIN_BUS") (pintype "passive"))
    (pad "2" smd roundrect (at 0.7 0 180) (size 0.6 0.8) (layers "B.Cu" "B.Paste" "B.Mask") (roundrect_rratio 0.2)
      (net 1 "GND") (pintype "passive"))
  )

  (footprint "kria-k26-devboard-footprints:C_0603_1608Metric" (layer "B.Cu")
    (at 135.7122 83.4644 90)
    (descr "Capacitor SMD 0603")
    (tags "capacitor 0603")
    (property "Author" "Antmicro")
    (property "Dielectric" "")
    (property "License" "Apache-2.0")
    (property "MPN" "GRM188R60J226MEA0D")
    (property "Manufacturer" "Murata")
    (property "Sheetfile" "dc-dc-conventers.kicad_sch")
    (property "Sheetname" "DC/DC conventers")
    (property "Val" "22u")
    (property "Voltage" "")
    (property "ki_description" " ")
    (attr smd)
    (fp_text reference "C212" (at 1.4844 -0.8122 270) (layer "B.SilkS")
        (effects (font (size 0.7 0.7) (thickness 0.15)) (justify left bottom mirror))
    )
    (fp_text value "C_22u_0603" (at 0 -1.6 270) (layer "B.Fab") hide
        (effects (font (size 0.7 0.7) (thickness 0.15)) (justify left bottom mirror))
    )
    (fp_text user "Author: Antmicro" (at -1.682 -4.894 270) (layer "B.Fab") hide
        (effects (font (size 0.7 0.7) (thickness 0.15)) (justify left bottom mirror))
    )
    (fp_text user "License: Apache-2.0" (at -1.682 -5.895 270) (layer "B.Fab") hide
        (effects (font (size 0.7 0.7) (thickness 0.15)) (justify left bottom mirror))
    )
    (fp_text user "${REFERENCE}" (at -1.682 -3.895 270) (layer "B.Fab") hide
        (effects (font (size 0.7 0.7) (thickness 0.15)) (justify left bottom mirror))
    )
    (fp_line (start -0.3 -0.3) (end 0.3 -0.3)
      (stroke (width 0.15) (type solid)) (layer "B.SilkS"))
    (fp_line (start -0.3 0.3) (end 0.3 0.3)
      (stroke (width 0.15) (type solid)) (layer "B.SilkS"))
    (fp_rect (start -1.24 0.7) (end 1.24 -0.7)
      (stroke (width 0.05) (type solid)) (fill none) (layer "B.CrtYd"))
    (fp_rect (start -0.8 0.4) (end 0.8 -0.4)
      (stroke (width 0.15) (type solid)) (fill none) (layer "B.Fab"))
    (pad "1" smd roundrect (at -0.7 0 90) (size 0.6 0.8) (layers "B.Cu" "B.Paste" "B.Mask") (roundrect_rratio 0.2)
      (net 766 "/Power Supply/DC/DC conventers/PS_2V5_OUT") (pintype "passive"))
    (pad "2" smd roundrect (at 0.7 0 90) (size 0.6 0.8) (layers "B.Cu" "B.Paste" "B.Mask") (roundrect_rratio 0.2)
      (net 1 "GND") (pintype "passive"))
  )

  (footprint "kria-k26-devboard-footprints:R_0402_1005Metric" (layer "B.Cu")
    (at 143.025 80.475 90)
    (descr "Resistor SMD 0402")
    (tags "resistor SMD 0402")
    (property "Author" "Antmicro")
    (property "License" "Apache-2.0")
    (property "MPN" "CR0402-FX-2152GLF")
    (property "Manufacturer" "Bourns")
    (property "Sheetfile" "dc-dc-conventers.kicad_sch")
    (property "Sheetname" "DC/DC conventers")
    (property "Tolerance" "1%")
    (property "Val" "21k5")
    (property "ki_description" "21k5 resistor in 0402 package with 1% tolerance")
    (attr smd)
    (fp_text reference "R133" (at 1.205 1.355 270) (layer "B.SilkS")
        (effects (font (size 0.7 0.7) (thickness 0.15)) (justify left bottom mirror))
    )
    (fp_text value "R_21k5_0402" (at 0 -1.4 270) (layer "B.Fab") hide
        (effects (font (size 0.7 0.7) (thickness 0.15)) (justify left bottom mirror))
    )
    (fp_text user "Author: Antmicro" (at -0.95 -4.169 270) (layer "B.Fab") hide
        (effects (font (size 0.7 0.7) (thickness 0.15)) (justify left bottom mirror))
    )
    (fp_text user "${REFERENCE}" (at -0.95 -3.168 270) (layer "B.Fab") hide
        (effects (font (size 0.7 0.7) (thickness 0.15)) (justify left bottom mirror))
    )
    (fp_text user "License: Apache-2.0" (at -0.95 -5.169 270) (layer "B.Fab") hide
        (effects (font (size 0.7 0.7) (thickness 0.15)) (justify left bottom mirror))
    )
    (fp_rect (start -0.93 0.47) (end 0.93 -0.47)
      (stroke (width 0.05) (type solid)) (fill none) (layer "B.CrtYd"))
    (fp_rect (start -0.5 0.25) (end 0.5 -0.25)
      (stroke (width 0.15) (type solid)) (fill none) (layer "B.Fab"))
    (pad "1" smd roundrect (at -0.485 0 90) (size 0.59 0.64) (layers "B.Cu" "B.Paste" "B.Mask") (roundrect_rratio 0.25)
      (net 766 "/Power Supply/DC/DC conventers/PS_2V5_OUT") (pintype "passive"))
    (pad "2" smd roundrect (at 0.485 0 90) (size 0.59 0.64) (layers "B.Cu" "B.Paste" "B.Mask") (roundrect_rratio 0.25)
      (net 689 "Net-(U50-FB)") (pintype "passive"))
  )

  (footprint "kria-k26-devboard-footprints:C_0402_1005Metric" (layer "B.Cu")
    (at 141.315 83.14 180)
    (descr "Capacitor SMD 0402")
    (tags "capacitor SMD 0402")
    (property "Author" "Antmicro")
    (property "Dielectric" "X5R")
    (property "License" "Apache-2.0")
    (property "MPN" "GRM155R61H104KE14D")
    (property "Manufacturer" "Murata")
    (property "Sheetfile" "dc-dc-conventers.kicad_sch")
    (property "Sheetname" "DC/DC conventers")
    (property "Val" "100n")
    (property "Voltage" "50V")
    (property "ki_description" " ")
    (attr smd)
    (fp_text reference "C207" (at -3.725 -0.37) (layer "B.SilkS")
        (effects (font (size 0.7 0.7) (thickness 0.15)) (justify left bottom mirror))
    )
    (fp_text value "C_100n_0402" (at 0 -1.4) (layer "B.Fab") hide
        (effects (font (size 0.7 0.7) (thickness 0.15)) (justify left bottom mirror))
    )
    (fp_text user "License: Apache-2.0" (at -0.932 -5.17) (layer "B.Fab") hide
        (effects (font (size 0.7 0.7) (thickness 0.15)) (justify left bottom mirror))
    )
    (fp_text user "Author: Antmicro" (at -0.932 -4.17) (layer "B.Fab") hide
        (effects (font (size 0.7 0.7) (thickness 0.15)) (justify left bottom mirror))
    )
    (fp_text user "${REFERENCE}" (at -0.932 -3.168) (layer "B.Fab") hide
        (effects (font (size 0.7 0.7) (thickness 0.15)) (justify left bottom mirror))
    )
    (fp_rect (start -0.94 0.47) (end 0.94 -0.47)
      (stroke (width 0.05) (type solid)) (fill none) (layer "B.CrtYd"))
    (fp_rect (start -0.499 0.249) (end 0.499 -0.249)
      (stroke (width 0.15) (type solid)) (fill none) (layer "B.Fab"))
    (pad "1" smd roundrect (at -0.484 0 180) (size 0.59 0.64) (layers "B.Cu" "B.Paste" "B.Mask") (roundrect_rratio 0.25)
      (net 258 "Net-(U50-BST)") (pintype "passive"))
    (pad "2" smd roundrect (at 0.484 0 180) (size 0.59 0.64) (layers "B.Cu" "B.Paste" "B.Mask") (roundrect_rratio 0.25)
      (net 310 "/Power Supply/DC/DC conventers/SW_PS_2V5") (pintype "passive"))
  )

  (footprint "kria-k26-devboard-footprints:C_0603_1608Metric" (layer "B.Cu")
    (at 137.8 80.675001 -90)
    (descr "Capacitor SMD 0603")
    (tags "capacitor 0603")
    (property "Author" "Antmicro")
    (property "Dielectric" "")
    (property "License" "Apache-2.0")
    (property "MPN" "C1608X5R1E106M080AC")
    (property "Manufacturer" "TDK")
    (property "Sheetfile" "dc-dc-conventers.kicad_sch")
    (property "Sheetname" "DC/DC conventers")
    (property "Val" "10u/25V")
    (property "Voltage" "")
    (property "ki_description" " ")
    (attr smd)
    (fp_text reference "C202" (at -1.395001 0.82 90) (layer "B.SilkS")
        (effects (font (size 0.7 0.7) (thickness 0.15)) (justify left bottom mirror))
    )
    (fp_text value "C_10u_25V_0603" (at 0 -1.6 90) (layer "B.Fab") hide
        (effects (font (size 0.7 0.7) (thickness 0.15)) (justify left bottom mirror))
    )
    (fp_text user "${REFERENCE}" (at -1.682 -3.895 90) (layer "B.Fab") hide
        (effects (font (size 0.7 0.7) (thickness 0.15)) (justify left bottom mirror))
    )
    (fp_text user "License: Apache-2.0" (at -1.682 -5.895 90) (layer "B.Fab") hide
        (effects (font (size 0.7 0.7) (thickness 0.15)) (justify left bottom mirror))
    )
    (fp_text user "Author: Antmicro" (at -1.682 -4.894 90) (layer "B.Fab") hide
        (effects (font (size 0.7 0.7) (thickness 0.15)) (justify left bottom mirror))
    )
    (fp_line (start -0.3 -0.3) (end 0.3 -0.3)
      (stroke (width 0.15) (type solid)) (layer "B.SilkS"))
    (fp_line (start -0.3 0.3) (end 0.3 0.3)
      (stroke (width 0.15) (type solid)) (layer "B.SilkS"))
    (fp_rect (start -1.24 0.7) (end 1.24 -0.7)
      (stroke (width 0.05) (type solid)) (fill none) (layer "B.CrtYd"))
    (fp_rect (start -0.8 0.4) (end 0.8 -0.4)
      (stroke (width 0.15) (type solid)) (fill none) (layer "B.Fab"))
    (pad "1" smd roundrect (at -0.7 0 270) (size 0.6 0.8) (layers "B.Cu" "B.Paste" "B.Mask") (roundrect_rratio 0.2)
      (net 14 "/Power Supply/DC/DC conventers/DC_MAIN_BUS") (pintype "passive"))
    (pad "2" smd roundrect (at 0.7 0 270) (size 0.6 0.8) (layers "B.Cu" "B.Paste" "B.Mask") (roundrect_rratio 0.2)
      (net 1 "GND") (pintype "passive"))
  )

  (footprint "kria-k26-devboard-footprints:R_0402_1005Metric" (layer "B.Cu")
    (at 142.6 78.8 180)
    (descr "Resistor SMD 0402")
    (tags "resistor SMD 0402")
    (property "Author" "Antmicro")
    (property "License" "Apache-2.0")
    (property "MPN" "CR0402-FX-1002GLF")
    (property "Manufacturer" "Bourns")
    (property "Sheetfile" "dc-dc-conventers.kicad_sch")
    (property "Sheetname" "DC/DC conventers")
    (property "Tolerance" "1%")
    (property "Val" "10k")
    (property "ki_description" "10k resistor in 0402 package with 1% tolerance")
    (attr smd)
    (fp_text reference "R134" (at -1.28 0.61) (layer "B.SilkS")
        (effects (font (size 0.7 0.7) (thickness 0.15)) (justify left bottom mirror))
    )
    (fp_text value "R_10k_0402" (at 0 -1.4) (layer "B.Fab") hide
        (effects (font (size 0.7 0.7) (thickness 0.15)) (justify left bottom mirror))
    )
    (fp_text user "License: Apache-2.0" (at -0.95 -5.169) (layer "B.Fab") hide
        (effects (font (size 0.7 0.7) (thickness 0.15)) (justify left bottom mirror))
    )
    (fp_text user "${REFERENCE}" (at -0.95 -3.168) (layer "B.Fab") hide
        (effects (font (size 0.7 0.7) (thickness 0.15)) (justify left bottom mirror))
    )
    (fp_text user "Author: Antmicro" (at -0.95 -4.169) (layer "B.Fab") hide
        (effects (font (size 0.7 0.7) (thickness 0.15)) (justify left bottom mirror))
    )
    (fp_rect (start -0.93 0.47) (end 0.93 -0.47)
      (stroke (width 0.05) (type solid)) (fill none) (layer "B.CrtYd"))
    (fp_rect (start -0.5 0.25) (end 0.5 -0.25)
      (stroke (width 0.15) (type solid)) (fill none) (layer "B.Fab"))
    (pad "1" smd roundrect (at -0.485 0 180) (size 0.59 0.64) (layers "B.Cu" "B.Paste" "B.Mask") (roundrect_rratio 0.25)
      (net 689 "Net-(U50-FB)") (pintype "passive"))
    (pad "2" smd roundrect (at 0.485 0 180) (size 0.59 0.64) (layers "B.Cu" "B.Paste" "B.Mask") (roundrect_rratio 0.25)
      (net 1 "GND") (pintype "passive"))
  )

  (footprint "kria-k26-devboard-footprints:TSOT23-6" (layer "B.Cu")
    (at 140.524999 80.975001 90)
    (property "Author" "Antmicro")
    (property "License" "Apache-2.0")
    (property "MPN" "AP62301WU-7")
    (property "Manufacturer" "Diodes Incorporated")
    (property "Sheetfile" "dc-dc-conventers.kicad_sch")
    (property "Sheetname" "DC/DC conventers")
    (property "ki_description" "DC-DC Switching Synchronous Buck Regulator, Adjustable, 4.2V-18Vin, 0.8V-7V/3A out, TSOT-26-6")
    (property "ki_keywords" "SMT, PMIC, IC, VOLTAGE")
    (attr smd)
    (fp_text reference "U50" (at 1.675001 0.575001) (layer "B.SilkS")
        (effects (font (size 0.7 0.7) (thickness 0.15)) (justify left bottom mirror))
    )
    (fp_text value "AP62301_TSOT" (at -0.005 -2.6 270) (layer "B.Fab") hide
        (effects (font (size 0.7 0.7) (thickness 0.15)) (justify left bottom mirror))
    )
    (fp_text user "License: Apache-2.0" (at -1.893 -4.967 270) (layer "B.Fab") hide
        (effects (font (size 0.7 0.7) (thickness 0.15)) (justify left bottom mirror))
    )
    (fp_text user "${REFERENCE}" (at -1.893 -6.168 270) (layer "B.Fab") hide
        (effects (font (size 0.7 0.7) (thickness 0.15)) (justify left bottom mirror))
    )
    (fp_text user "Author: Antmicro" (at -1.893 -7.368 270) (layer "B.Fab") hide
        (effects (font (size 0.7 0.7) (thickness 0.15)) (justify left bottom mirror))
    )
    (fp_line (start -1.4805 -0.725) (end -1.4795 0.725)
      (stroke (width 0.15) (type solid)) (layer "B.SilkS"))
    (fp_line (start -1.4805 -0.725) (end -1.3905 -0.725)
      (stroke (width 0.15) (type solid)) (layer "B.SilkS"))
    (fp_line (start -1.4795 0.725) (end -1.3905 0.725)
      (stroke (width 0.15) (type solid)) (layer "B.SilkS"))
    (fp_line (start 1.479 -0.73) (end 1.38 -0.73)
      (stroke (width 0.15) (type solid)) (layer "B.SilkS"))
    (fp_line (start 1.48 0.72) (end 1.38 0.72)
      (stroke (width 0.15) (type solid)) (layer "B.SilkS"))
    (fp_line (start 1.48 0.72) (end 1.479 -0.73)
      (stroke (width 0.15) (type solid)) (layer "B.SilkS"))
    (fp_circle (center -1.499 -1.236) (end -1.45 -1.236)
      (stroke (width 0.15) (type solid)) (fill solid) (layer "B.SilkS"))
    (fp_rect (start -1.65 1.61) (end 1.65 -1.61)
      (stroke (width 0.05) (type solid)) (fill none) (layer "B.CrtYd"))
    (fp_line (start -1.527 -0.491) (end -1.527 0.833)
      (stroke (width 0.15) (type solid)) (layer "B.Fab"))
    (fp_line (start -1.527 -0.491) (end -1.102 -0.916)
      (stroke (width 0.15) (type solid)) (layer "B.Fab"))
    (fp_line (start -1.527 0.833) (end 1.523 0.833)
      (stroke (width 0.15) (type solid)) (layer "B.Fab"))
    (fp_line (start -1.102 -0.916) (end 1.523 -0.916)
      (stroke (width 0.15) (type solid)) (layer "B.Fab"))
    (fp_line (start 1.523 0.833) (end 1.523 -0.916)
      (stroke (width 0.15) (type solid)) (layer "B.Fab"))
    (pad "1" smd rect (at -0.952 -1.18 90) (size 0.7 0.8) (layers "B.Cu" "B.Paste" "B.Mask")
      (net 1 "GND") (pinfunction "GND") (pintype "power_in"))
    (pad "2" smd rect (at -0.001 -1.18 90) (size 0.7 0.8) (layers "B.Cu" "B.Paste" "B.Mask")
      (net 310 "/Power Supply/DC/DC conventers/SW_PS_2V5") (pinfunction "SW") (pintype "power_out"))
    (pad "3" smd rect (at 0.947 -1.18 90) (size 0.7 0.8) (layers "B.Cu" "B.Paste" "B.Mask")
      (net 14 "/Power Supply/DC/DC conventers/DC_MAIN_BUS") (pinfunction "VIN") (pintype "power_in"))
    (pad "4" smd rect (at 0.947 1.18 90) (size 0.7 0.8) (layers "B.Cu" "B.Paste" "B.Mask")
      (net 689 "Net-(U50-FB)") (pinfunction "FB") (pintype "input"))
    (pad "5" smd rect (at -0.001 1.18 90) (size 0.7 0.8) (layers "B.Cu" "B.Paste" "B.Mask")
      (net 687 "Net-(U50-EN)") (pinfunction "EN") (pintype "input"))
    (pad "6" smd rect (at -0.952 1.18 90) (size 0.7 0.8) (layers "B.Cu" "B.Paste" "B.Mask")
      (net 258 "Net-(U50-BST)") (pinfunction "BST") (pintype "output"))
  )

  (footprint "kria-k26-devboard-footprints:R_0402_1005Metric" (layer "B.Cu")
    (at 103.5 137.915 -90)
    (descr "Resistor SMD 0402")
    (tags "resistor SMD 0402")
    (property "Author" "Antmicro")
    (property "Current" "1A")
    (property "DNP" "DNP")
    (property "License" "Apache-2.0")
    (property "MPN" "ERJ2GE0R00X")
    (property "Manufacturer" "Panasonic")
    (property "Sheetfile" "i2c.kicad_sch")
    (property "Sheetname" "I2C ")
    (property "Tolerance" "")
    (property "Val" "0R")
    (property "dnp" "")
    (property "exclude_from_bom" "")
    (property "ki_description" "0R resistor in 0402 package with unspecified tolerance")
    (attr exclude_from_pos_files exclude_from_bom)
    (fp_text reference "R37" (at -1.055 0.59 90) (layer "B.SilkS")
        (effects (font (size 0.7 0.7) (thickness 0.15)) (justify left bottom mirror))
    )
    (fp_text value "R_0R_0402" (at 0 -1.4 90) (layer "B.Fab") hide
        (effects (font (size 0.7 0.7) (thickness 0.15)) (justify left bottom mirror))
    )
    (fp_text user "Author: Antmicro" (at -0.95 -4.169 90) (layer "B.Fab") hide
        (effects (font (size 0.7 0.7) (thickness 0.15)) (justify left bottom mirror))
    )
    (fp_text user "${REFERENCE}" (at -0.95 -3.168 90) (layer "B.Fab") hide
        (effects (font (size 0.7 0.7) (thickness 0.15)) (justify left bottom mirror))
    )
    (fp_text user "License: Apache-2.0" (at -0.95 -5.169 90) (layer "B.Fab") hide
        (effects (font (size 0.7 0.7) (thickness 0.15)) (justify left bottom mirror))
    )
    (fp_rect (start -0.93 0.47) (end 0.93 -0.47)
      (stroke (width 0.05) (type solid)) (fill none) (layer "B.CrtYd"))
    (fp_rect (start -0.5 0.25) (end 0.5 -0.25)
      (stroke (width 0.15) (type solid)) (fill none) (layer "B.Fab"))
    (pad "1" smd roundrect (at -0.485 0 270) (size 0.59 0.64) (layers "B.Cu" "B.Paste" "B.Mask") (roundrect_rratio 0.25)
      (net 186 "/Debug and JTAG/~{EEPROM_WC}") (pintype "passive"))
    (pad "2" smd roundrect (at 0.485 0 270) (size 0.59 0.64) (layers "B.Cu" "B.Paste" "B.Mask") (roundrect_rratio 0.25)
      (net 1 "GND") (pintype "passive"))
  )

  (footprint "kria-k26-devboard-footprints:C_2220_5650Metric" (layer "B.Cu")
    (at 165.22 82.95 90)
    (descr "Capacitor SMD 2220")
    (tags "capacitor SMD 2220")
    (property "Author" "Antmicro")
    (property "DNP" "DNP")
    (property "Dielectric" "")
    (property "License" "Apache-2.0")
    (property "MPN" "C5750X7S2A226M280KB")
    (property "Manufacturer" "TDK")
    (property "Sheetfile" "PoE.kicad_sch")
    (property "Sheetname" "PoE")
    (property "Val" "22u/100V")
    (property "Voltage" "")
    (property "dnp" "")
    (property "exclude_from_bom" "")
    (property "ki_description" " ")
    (attr exclude_from_pos_files exclude_from_bom)
    (fp_text reference "C176" (at 6.61 0.785 270) (layer "B.SilkS")
        (effects (font (size 0.7 0.7) (thickness 0.15)) (justify left bottom mirror))
    )
    (fp_text value "C_22u_100V_2220" (at 0 -3.9 270) (layer "B.Fab") hide
        (effects (font (size 0.7 0.7) (thickness 0.15)) (justify left bottom mirror))
    )
    (fp_text user "License: Apache-2.0" (at -3.7 -6.9 270) (layer "B.Fab") hide
        (effects (font (size 0.7 0.7) (thickness 0.15)) (justify left bottom mirror))
    )
    (fp_text user "Author: Antmicro" (at -3.7 -7.9 270) (layer "B.Fab") hide
        (effects (font (size 0.7 0.7) (thickness 0.15)) (justify left bottom mirror))
    )
    (fp_text user "${REFERENCE}" (at -3.7 -5.9 270) (layer "B.Fab") hide
        (effects (font (size 0.7 0.7) (thickness 0.15)) (justify left bottom mirror))
    )
    (fp_line (start -1.415 -2.61) (end 1.415 -2.61)
      (stroke (width 0.15) (type solid)) (layer "B.SilkS"))
    (fp_line (start -1.415 2.61) (end 1.415 2.61)
      (stroke (width 0.15) (type solid)) (layer "B.SilkS"))
    (fp_rect (start -3.7 2.95) (end 3.7 -2.95)
      (stroke (width 0.05) (type solid)) (fill none) (layer "B.CrtYd"))
    (fp_rect (start -2.85 2.5) (end 2.85 -2.5)
      (stroke (width 0.15) (type solid)) (fill none) (layer "B.Fab"))
    (pad "1" smd roundrect (at -2.55 0 90) (size 1.8 5.4) (layers "B.Cu" "B.Paste" "B.Mask") (roundrect_rratio 0.138889)
      (net 9 "/Power Supply/PoE/VDD_POE_IN") (pintype "passive"))
    (pad "2" smd roundrect (at 2.55 0 90) (size 1.8 5.4) (layers "B.Cu" "B.Paste" "B.Mask") (roundrect_rratio 0.138889)
      (net 11 "GNDD") (pintype "passive"))
  )

  (footprint "kria-k26-devboard-footprints:C_2220_5650Metric" (layer "B.Cu")
    (at 182.99 82.95 90)
    (descr "Capacitor SMD 2220")
    (tags "capacitor SMD 2220")
    (property "Author" "Antmicro")
    (property "DNP" "DNP")
    (property "Dielectric" "")
    (property "License" "Apache-2.0")
    (property "MPN" "C5750X7S2A226M280KB")
    (property "Manufacturer" "TDK")
    (property "Sheetfile" "PoE.kicad_sch")
    (property "Sheetname" "PoE")
    (property "Val" "22u/100V")
    (property "Voltage" "")
    (property "dnp" "")
    (property "exclude_from_bom" "")
    (property "ki_description" " ")
    (attr exclude_from_pos_files exclude_from_bom)
    (fp_text reference "C178" (at 6.61 0.785 270) (layer "B.SilkS")
        (effects (font (size 0.7 0.7) (thickness 0.15)) (justify left bottom mirror))
    )
    (fp_text value "C_22u_100V_2220" (at 0 -3.9 270) (layer "B.Fab") hide
        (effects (font (size 0.7 0.7) (thickness 0.15)) (justify left bottom mirror))
    )
    (fp_text user "Author: Antmicro" (at -3.7 -7.9 270) (layer "B.Fab") hide
        (effects (font (size 0.7 0.7) (thickness 0.15)) (justify left bottom mirror))
    )
    (fp_text user "${REFERENCE}" (at -3.7 -5.9 270) (layer "B.Fab") hide
        (effects (font (size 0.7 0.7) (thickness 0.15)) (justify left bottom mirror))
    )
    (fp_text user "License: Apache-2.0" (at -3.7 -6.9 270) (layer "B.Fab") hide
        (effects (font (size 0.7 0.7) (thickness 0.15)) (justify left bottom mirror))
    )
    (fp_line (start -1.415 -2.61) (end 1.415 -2.61)
      (stroke (width 0.15) (type solid)) (layer "B.SilkS"))
    (fp_line (start -1.415 2.61) (end 1.415 2.61)
      (stroke (width 0.15) (type solid)) (layer "B.SilkS"))
    (fp_rect (start -3.7 2.95) (end 3.7 -2.95)
      (stroke (width 0.05) (type solid)) (fill none) (layer "B.CrtYd"))
    (fp_rect (start -2.85 2.5) (end 2.85 -2.5)
      (stroke (width 0.15) (type solid)) (fill none) (layer "B.Fab"))
    (pad "1" smd roundrect (at -2.55 0 90) (size 1.8 5.4) (layers "B.Cu" "B.Paste" "B.Mask") (roundrect_rratio 0.138889)
      (net 9 "/Power Supply/PoE/VDD_POE_IN") (pintype "passive"))
    (pad "2" smd roundrect (at 2.55 0 90) (size 1.8 5.4) (layers "B.Cu" "B.Paste" "B.Mask") (roundrect_rratio 0.138889)
      (net 11 "GNDD") (pintype "passive"))
  )

  (footprint "kria-k26-devboard-footprints:C_2220_5650Metric" (layer "B.Cu")
    (at 177.075 82.95 90)
    (descr "Capacitor SMD 2220")
    (tags "capacitor SMD 2220")
    (property "Author" "Antmicro")
    (property "DNP" "DNP")
    (property "Dielectric" "")
    (property "License" "Apache-2.0")
    (property "MPN" "C5750X7S2A226M280KB")
    (property "Manufacturer" "TDK")
    (property "Sheetfile" "PoE.kicad_sch")
    (property "Sheetname" "PoE")
    (property "Val" "22u/100V")
    (property "Voltage" "")
    (property "dnp" "")
    (property "exclude_from_bom" "")
    (property "ki_description" " ")
    (attr exclude_from_pos_files exclude_from_bom)
    (fp_text reference "C179" (at 6.61 0.785 270) (layer "B.SilkS")
        (effects (font (size 0.7 0.7) (thickness 0.15)) (justify left bottom mirror))
    )
    (fp_text value "C_22u_100V_2220" (at 0 -3.9 270) (layer "B.Fab") hide
        (effects (font (size 0.7 0.7) (thickness 0.15)) (justify left bottom mirror))
    )
    (fp_text user "License: Apache-2.0" (at -3.7 -6.9 270) (layer "B.Fab") hide
        (effects (font (size 0.7 0.7) (thickness 0.15)) (justify left bottom mirror))
    )
    (fp_text user "Author: Antmicro" (at -3.7 -7.9 270) (layer "B.Fab") hide
        (effects (font (size 0.7 0.7) (thickness 0.15)) (justify left bottom mirror))
    )
    (fp_text user "${REFERENCE}" (at -3.7 -5.9 270) (layer "B.Fab") hide
        (effects (font (size 0.7 0.7) (thickness 0.15)) (justify left bottom mirror))
    )
    (fp_line (start -1.415 -2.61) (end 1.415 -2.61)
      (stroke (width 0.15) (type solid)) (layer "B.SilkS"))
    (fp_line (start -1.415 2.61) (end 1.415 2.61)
      (stroke (width 0.15) (type solid)) (layer "B.SilkS"))
    (fp_rect (start -3.7 2.95) (end 3.7 -2.95)
      (stroke (width 0.05) (type solid)) (fill none) (layer "B.CrtYd"))
    (fp_rect (start -2.85 2.5) (end 2.85 -2.5)
      (stroke (width 0.15) (type solid)) (fill none) (layer "B.Fab"))
    (pad "1" smd roundrect (at -2.55 0 90) (size 1.8 5.4) (layers "B.Cu" "B.Paste" "B.Mask") (roundrect_rratio 0.138889)
      (net 9 "/Power Supply/PoE/VDD_POE_IN") (pintype "passive"))
    (pad "2" smd roundrect (at 2.55 0 90) (size 1.8 5.4) (layers "B.Cu" "B.Paste" "B.Mask") (roundrect_rratio 0.138889)
      (net 11 "GNDD") (pintype "passive"))
  )

  (footprint "kria-k26-devboard-footprints:C_2220_5650Metric" (layer "B.Cu")
    (at 171.15 82.95 90)
    (descr "Capacitor SMD 2220")
    (tags "capacitor SMD 2220")
    (property "Author" "Antmicro")
    (property "DNP" "DNP")
    (property "Dielectric" "")
    (property "License" "Apache-2.0")
    (property "MPN" "C5750X7S2A226M280KB")
    (property "Manufacturer" "TDK")
    (property "Sheetfile" "PoE.kicad_sch")
    (property "Sheetname" "PoE")
    (property "Val" "22u/100V")
    (property "Voltage" "")
    (property "dnp" "")
    (property "exclude_from_bom" "")
    (property "ki_description" " ")
    (attr exclude_from_pos_files exclude_from_bom)
    (fp_text reference "C177" (at 6.61 0.785 270) (layer "B.SilkS")
        (effects (font (size 0.7 0.7) (thickness 0.15)) (justify left bottom mirror))
    )
    (fp_text value "C_22u_100V_2220" (at 0 -3.9 270) (layer "B.Fab") hide
        (effects (font (size 0.7 0.7) (thickness 0.15)) (justify left bottom mirror))
    )
    (fp_text user "License: Apache-2.0" (at -3.7 -6.9 270) (layer "B.Fab") hide
        (effects (font (size 0.7 0.7) (thickness 0.15)) (justify left bottom mirror))
    )
    (fp_text user "${REFERENCE}" (at -3.7 -5.9 270) (layer "B.Fab") hide
        (effects (font (size 0.7 0.7) (thickness 0.15)) (justify left bottom mirror))
    )
    (fp_text user "Author: Antmicro" (at -3.7 -7.9 270) (layer "B.Fab") hide
        (effects (font (size 0.7 0.7) (thickness 0.15)) (justify left bottom mirror))
    )
    (fp_line (start -1.415 -2.61) (end 1.415 -2.61)
      (stroke (width 0.15) (type solid)) (layer "B.SilkS"))
    (fp_line (start -1.415 2.61) (end 1.415 2.61)
      (stroke (width 0.15) (type solid)) (layer "B.SilkS"))
    (fp_rect (start -3.7 2.95) (end 3.7 -2.95)
      (stroke (width 0.05) (type solid)) (fill none) (layer "B.CrtYd"))
    (fp_rect (start -2.85 2.5) (end 2.85 -2.5)
      (stroke (width 0.15) (type solid)) (fill none) (layer "B.Fab"))
    (pad "1" smd roundrect (at -2.55 0 90) (size 1.8 5.4) (layers "B.Cu" "B.Paste" "B.Mask") (roundrect_rratio 0.138889)
      (net 9 "/Power Supply/PoE/VDD_POE_IN") (pintype "passive"))
    (pad "2" smd roundrect (at 2.55 0 90) (size 1.8 5.4) (layers "B.Cu" "B.Paste" "B.Mask") (roundrect_rratio 0.138889)
      (net 11 "GNDD") (pintype "passive"))
  )

  (footprint "kria-k26-devboard-footprints:R_0402_1005Metric" (layer "B.Cu")
    (at 139.55 87.35 90)
    (descr "Resistor SMD 0402")
    (tags "resistor SMD 0402")
    (property "Author" "Antmicro")
    (property "Current" "1A")
    (property "License" "Apache-2.0")
    (property "MPN" "ERJ2GE0R00X")
    (property "Manufacturer" "Panasonic")
    (property "Sheetfile" "dc-dc-conventers.kicad_sch")
    (property "Sheetname" "DC/DC conventers")
    (property "Tolerance" "")
    (property "Val" "0R")
    (property "ki_description" "0R resistor in 0402 package with unspecified tolerance")
    (attr smd)
    (fp_text reference "R127" (at 1.68 1.33 270) (layer "B.SilkS")
        (effects (font (size 0.7 0.7) (thickness 0.15)) (justify left bottom mirror))
    )
    (fp_text value "R_0R_0402" (at 0 -1.4 270) (layer "B.Fab") hide
        (effects (font (size 0.7 0.7) (thickness 0.15)) (justify left bottom mirror))
    )
    (fp_text user "Author: Antmicro" (at -0.95 -4.169 270) (layer "B.Fab") hide
        (effects (font (size 0.7 0.7) (thickness 0.15)) (justify left bottom mirror))
    )
    (fp_text user "${REFERENCE}" (at -0.95 -3.168 270) (layer "B.Fab") hide
        (effects (font (size 0.7 0.7) (thickness 0.15)) (justify left bottom mirror))
    )
    (fp_text user "License: Apache-2.0" (at -0.95 -5.169 270) (layer "B.Fab") hide
        (effects (font (size 0.7 0.7) (thickness 0.15)) (justify left bottom mirror))
    )
    (fp_rect (start -0.93 0.47) (end 0.93 -0.47)
      (stroke (width 0.05) (type solid)) (fill none) (layer "B.CrtYd"))
    (fp_rect (start -0.5 0.25) (end 0.5 -0.25)
      (stroke (width 0.15) (type solid)) (fill none) (layer "B.Fab"))
    (pad "1" smd roundrect (at -0.485 0 90) (size 0.59 0.64) (layers "B.Cu" "B.Paste" "B.Mask") (roundrect_rratio 0.25)
      (net 185 "/Clock distribution/PS_CLK_EN") (pintype "passive"))
    (pad "2" smd roundrect (at 0.485 0 90) (size 0.59 0.64) (layers "B.Cu" "B.Paste" "B.Mask") (roundrect_rratio 0.25)
      (net 687 "Net-(U50-EN)") (pintype "passive"))
  )

  (footprint "kria-k26-devboard-footprints:R_2010_5025Metric" (layer "B.Cu")
    (at 177.55 94.45)
    (descr "Resistor SMD 2010")
    (tags "resistor SMD 2010")
    (property "Author" "Antmicro")
    (property "License" "Apache-2.0")
    (property "MPN" "CR2010-FX-1502ELF")
    (property "Manufacturer" "Bourns")
    (property "Sheetfile" "PoE.kicad_sch")
    (property "Sheetname" "PoE")
    (property "Tolerance" "1%")
    (property "Val" "15k")
    (property "ki_description" "15k resistor in 2010 package with 1% tolerance")
    (attr smd)
    (fp_text reference "R154" (at 1.44 2.36 180) (layer "B.SilkS")
        (effects (font (size 0.7 0.7) (thickness 0.15)) (justify left bottom mirror))
    )
    (fp_text value "R_15k_2010" (at 0 -2.7 180) (layer "B.Fab") hide
        (effects (font (size 0.7 0.7) (thickness 0.15)) (justify left bottom mirror))
    )
    (fp_text user "${REFERENCE}" (at -3.34 -4.278 180) (layer "B.Fab") hide
        (effects (font (size 0.7 0.7) (thickness 0.15)) (justify left bottom mirror))
    )
    (fp_text user "Author: Antmicro" (at -3.34 -5.278 180) (layer "B.Fab") hide
        (effects (font (size 0.7 0.7) (thickness 0.15)) (justify left bottom mirror))
    )
    (fp_text user "License: Apache-2.0" (at -3.34 -6.278 180) (layer "B.Fab") hide
        (effects (font (size 0.7 0.7) (thickness 0.15)) (justify left bottom mirror))
    )
    (fp_line (start -1.4 -1.36) (end 1.4 -1.36)
      (stroke (width 0.15) (type solid)) (layer "B.SilkS"))
    (fp_line (start -1.4 1.36) (end 1.4 1.36)
      (stroke (width 0.15) (type solid)) (layer "B.SilkS"))
    (fp_rect (start -3.34 1.75) (end 3.34 -1.75)
      (stroke (width 0.05) (type solid)) (fill none) (layer "B.CrtYd"))
    (fp_rect (start -2.5 1.25) (end 2.5 -1.25)
      (stroke (width 0.15) (type solid)) (fill none) (layer "B.Fab"))
    (pad "1" smd rect (at -2.32 0) (size 1.5 2.75) (layers "B.Cu" "B.Paste" "B.Mask")
      (net 9 "/Power Supply/PoE/VDD_POE_IN") (pintype "passive"))
    (pad "2" smd rect (at 2.32 0) (size 1.5 2.75) (layers "B.Cu" "B.Paste" "B.Mask")
      (net 11 "GNDD") (pintype "passive"))
  )

  (footprint "kria-k26-devboard-footprints:R_0402_1005Metric" (layer "B.Cu")
    (at 127.65 84.88 180)
    (descr "Resistor SMD 0402")
    (tags "resistor SMD 0402")
    (property "Author" "Antmicro")
    (property "License" "Apache-2.0")
    (property "MPN" "CR0402-FX-5111GLF")
    (property "Manufacturer" "Bourns")
    (property "Sheetfile" "usb.kicad_sch")
    (property "Sheetname" "USB")
    (property "Tolerance" "1%")
    (property "Val" "5k11")
    (property "ki_description" "5k11 resistor in 0402 package with 1% tolerance")
    (attr smd)
    (fp_text reference "R62" (at 0.9 -0.38) (layer "B.SilkS")
        (effects (font (size 0.7 0.7) (thickness 0.15)) (justify left bottom mirror))
    )
    (fp_text value "R_5k11_0402" (at 0 -1.4) (layer "B.Fab") hide
        (effects (font (size 0.7 0.7) (thickness 0.15)) (justify left bottom mirror))
    )
    (fp_text user "Author: Antmicro" (at -0.95 -4.169) (layer "B.Fab") hide
        (effects (font (size 0.7 0.7) (thickness 0.15)) (justify left bottom mirror))
    )
    (fp_text user "${REFERENCE}" (at -0.95 -3.168) (layer "B.Fab") hide
        (effects (font (size 0.7 0.7) (thickness 0.15)) (justify left bottom mirror))
    )
    (fp_text user "License: Apache-2.0" (at -0.95 -5.169) (layer "B.Fab") hide
        (effects (font (size 0.7 0.7) (thickness 0.15)) (justify left bottom mirror))
    )
    (fp_rect (start -0.93 0.47) (end 0.93 -0.47)
      (stroke (width 0.05) (type solid)) (fill none) (layer "B.CrtYd"))
    (fp_rect (start -0.5 0.25) (end 0.5 -0.25)
      (stroke (width 0.15) (type solid)) (fill none) (layer "B.Fab"))
    (pad "1" smd roundrect (at -0.485 0 180) (size 0.59 0.64) (layers "B.Cu" "B.Paste" "B.Mask") (roundrect_rratio 0.25)
      (net 665 "Net-(U17-DP1_CC1)") (pintype "passive"))
    (pad "2" smd roundrect (at 0.485 0 180) (size 0.59 0.64) (layers "B.Cu" "B.Paste" "B.Mask") (roundrect_rratio 0.25)
      (net 1 "GND") (pintype "passive"))
  )

  (footprint "kria-k26-devboard-footprints:SOT-416" (layer "B.Cu")
    (at 100.6 89.2)
    (descr "SOT-416")
    (tags "SOT-416")
    (property "Author" "Antmicro")
    (property "License" "Apache-2.0")
    (property "MPN" "DTC014TEBTL")
    (property "Manufacturer" "ROHM Semiconductor")
    (property "Sheetfile" "k26_som.kicad_sch")
    (property "Sheetname" "Xilinx K26 SOM")
    (property "ki_description" "Digital NPN Transistor, 10k/NONE, EMT-3")
    (attr smd)
    (fp_text reference "Q7" (at 0.9 1.92 180) (layer "B.SilkS")
        (effects (font (size 0.7 0.7) (thickness 0.15)) (justify left bottom mirror))
    )
    (fp_text value "DTC014T_SOT-416" (at 0 -2 180) (layer "B.Fab") hide
        (effects (font (size 0.7 0.7) (thickness 0.15)) (justify left bottom mirror))
    )
    (fp_text user "${REFERENCE}" (at -1 -3.4 180) (layer "B.Fab") hide
        (effects (font (size 0.7 0.7) (thickness 0.15)) (justify left bottom mirror))
    )
    (fp_text user "Author: Antmicro" (at -1 -4.602 180) (layer "B.Fab") hide
        (effects (font (size 0.7 0.7) (thickness 0.15)) (justify left bottom mirror))
    )
    (fp_text user "License: Apache-2.0" (at -1 -5.802 180) (layer "B.Fab") hide
        (effects (font (size 0.7 0.7) (thickness 0.15)) (justify left bottom mirror))
    )
    (fp_line (start -0.5 0.15) (end -0.5 -0.15)
      (stroke (width 0.15) (type solid)) (layer "B.SilkS"))
    (fp_line (start 0.5 -0.9) (end -0.5 -0.9)
      (stroke (width 0.15) (type solid)) (layer "B.SilkS"))
    (fp_line (start 0.5 -0.9) (end 0.5 -0.7)
      (stroke (width 0.15) (type solid)) (layer "B.SilkS"))
    (fp_line (start 0.508 0.9) (end -0.5 0.9)
      (stroke (width 0.15) (type solid)) (layer "B.SilkS"))
    (fp_line (start 0.508 0.9) (end 0.508 0.592)
      (stroke (width 0.15) (type solid)) (layer "B.SilkS"))
    (fp_rect (start -1 1.05) (end 1 -1.05)
      (stroke (width 0.05) (type solid)) (fill none) (layer "B.CrtYd"))
    (fp_line (start -0.05 0.9) (end -0.45 0.5)
      (stroke (width 0.15) (type solid)) (layer "B.Fab"))
    (fp_rect (start 0.45 -0.9) (end -0.45 0.9)
      (stroke (width 0.15) (type solid)) (fill none) (layer "B.Fab"))
    (pad "1" smd rect (at -0.652 0.5) (size 0.6 0.5) (layers "B.Cu" "B.Paste" "B.Mask")
      (net 431 "Net-(Q19-C)") (pinfunction "B") (pintype "input"))
    (pad "2" smd rect (at -0.652 -0.498) (size 0.6 0.5) (layers "B.Cu" "B.Paste" "B.Mask")
      (net 1 "GND") (pinfunction "E") (pintype "passive"))
    (pad "3" smd rect (at 0.65 0) (size 0.6 0.5) (layers "B.Cu" "B.Paste" "B.Mask")
      (net 430 "Net-(Q6-G)") (pinfunction "C") (pintype "passive"))
  )

  (footprint "kria-k26-devboard-footprints:R_0402_1005Metric" (layer "B.Cu")
    (at 101 87.45 180)
    (descr "Resistor SMD 0402")
    (tags "resistor SMD 0402")
    (property "Author" "Antmicro")
    (property "License" "Apache-2.0")
    (property "MPN" "CR0402-FX-1003GLF")
    (property "Manufacturer" "Bourns")
    (property "Sheetfile" "k26_som.kicad_sch")
    (property "Sheetname" "Xilinx K26 SOM")
    (property "Tolerance" "1%")
    (property "Val" "100k")
    (property "ki_description" "100k resistor in 0402 package with 1% tolerance")
    (attr smd)
    (fp_text reference "R83" (at -1.12 0.62) (layer "B.SilkS")
        (effects (font (size 0.7 0.7) (thickness 0.15)) (justify left bottom mirror))
    )
    (fp_text value "R_100k_0402" (at 0 -1.4) (layer "B.Fab") hide
        (effects (font (size 0.7 0.7) (thickness 0.15)) (justify left bottom mirror))
    )
    (fp_text user "${REFERENCE}" (at -0.95 -3.168) (layer "B.Fab") hide
        (effects (font (size 0.7 0.7) (thickness 0.15)) (justify left bottom mirror))
    )
    (fp_text user "License: Apache-2.0" (at -0.95 -5.169) (layer "B.Fab") hide
        (effects (font (size 0.7 0.7) (thickness 0.15)) (justify left bottom mirror))
    )
    (fp_text user "Author: Antmicro" (at -0.95 -4.169) (layer "B.Fab") hide
        (effects (font (size 0.7 0.7) (thickness 0.15)) (justify left bottom mirror))
    )
    (fp_rect (start -0.93 0.47) (end 0.93 -0.47)
      (stroke (width 0.05) (type solid)) (fill none) (layer "B.CrtYd"))
    (fp_rect (start -0.5 0.25) (end 0.5 -0.25)
      (stroke (width 0.15) (type solid)) (fill none) (layer "B.Fab"))
    (pad "1" smd roundrect (at -0.485 0 180) (size 0.59 0.64) (layers "B.Cu" "B.Paste" "B.Mask") (roundrect_rratio 0.25)
      (net 306 "USB_5V") (pintype "passive"))
    (pad "2" smd roundrect (at 0.485 0 180) (size 0.59 0.64) (layers "B.Cu" "B.Paste" "B.Mask") (roundrect_rratio 0.25)
      (net 430 "Net-(Q6-G)") (pintype "passive"))
  )

  (footprint "kria-k26-devboard-footprints:SOT-23-3" (layer "B.Cu")
    (at 103.8 88.4)
    (property "Author" "Antmicro")
    (property "License" "Apache-2.0")
    (property "MPN" "PJA3441_R1_00001")
    (property "Manufacturer" "Panjit")
    (property "Sheetfile" "k26_som.kicad_sch")
    (property "Sheetname" "Xilinx K26 SOM")
    (property "ki_description" "MOSFET 40V P-Channel Enhancement Mode MOSFET")
    (attr smd)
    (fp_text reference "Q6" (at 0.21 2.49 180) (layer "B.SilkS")
        (effects (font (size 0.7 0.7) (thickness 0.15)) (justify left bottom mirror))
    )
    (fp_text value "PJA3441" (at -1.9 -2.7 180) (layer "B.Fab") hide
        (effects (font (size 0.7 0.7) (thickness 0.15)) (justify left bottom mirror))
    )
    (fp_text user "License: Apache-2.0" (at -1.8 -6.8 180) (layer "B.Fab") hide
        (effects (font (size 0.7 0.7) (thickness 0.15)) (justify left bottom mirror))
    )
    (fp_text user "Author: Antmicro" (at -1.837 -5.3 180) (layer "B.Fab") hide
        (effects (font (size 0.7 0.7) (thickness 0.15)) (justify left bottom mirror))
    )
    (fp_text user "${REFERENCE}" (at -1.837 -4 180) (layer "B.Fab") hide
        (effects (font (size 0.7 0.7) (thickness 0.15)) (justify left bottom mirror))
    )
    (fp_line (start -1.45 1.35) (end -0.85 1.35)
      (stroke (width 0.15) (type solid)) (layer "B.SilkS"))
    (fp_line (start -0.85 1.35) (end -0.7 1.5)
      (stroke (width 0.15) (type solid)) (layer "B.SilkS"))
    (fp_line (start -0.7 -1.5) (end -0.7 -1.35)
      (stroke (width 0.15) (type solid)) (layer "B.SilkS"))
    (fp_line (start 0.7 -1.5) (end -0.7 -1.5)
      (stroke (width 0.15) (type solid)) (layer "B.SilkS"))
    (fp_line (start 0.7 -0.4) (end 0.7 -1.5)
      (stroke (width 0.15) (type solid)) (layer "B.SilkS"))
    (fp_line (start 0.7 0.4) (end 0.7 1.5)
      (stroke (width 0.15) (type solid)) (layer "B.SilkS"))
    (fp_line (start 0.7 1.5) (end -0.7 1.5)
      (stroke (width 0.15) (type solid)) (layer "B.SilkS"))
    (fp_line (start -1.75 -1.4) (end -1.75 -0.5)
      (stroke (width 0.05) (type solid)) (layer "B.CrtYd"))
    (fp_line (start -1.75 -0.5) (end -0.85 -0.5)
      (stroke (width 0.05) (type solid)) (layer "B.CrtYd"))
    (fp_line (start -1.75 0.5) (end -1.75 1.4)
      (stroke (width 0.05) (type solid)) (layer "B.CrtYd"))
    (fp_line (start -0.9 1.4) (end -1.75 1.4)
      (stroke (width 0.05) (type solid)) (layer "B.CrtYd"))
    (fp_line (start -0.9 1.6) (end -0.9 1.4)
      (stroke (width 0.05) (type solid)) (layer "B.CrtYd"))
    (fp_line (start -0.9 1.6) (end 0.825 1.6)
      (stroke (width 0.05) (type solid)) (layer "B.CrtYd"))
    (fp_line (start -0.85 -1.65) (end -0.85 -1.4)
      (stroke (width 0.05) (type solid)) (layer "B.CrtYd"))
    (fp_line (start -0.85 -1.4) (end -1.75 -1.4)
      (stroke (width 0.05) (type solid)) (layer "B.CrtYd"))
    (fp_line (start -0.85 -0.5) (end -0.85 0.5)
      (stroke (width 0.05) (type solid)) (layer "B.CrtYd"))
    (fp_line (start -0.85 0.5) (end -1.75 0.5)
      (stroke (width 0.05) (type solid)) (layer "B.CrtYd"))
    (fp_line (start 0.825 0.45) (end 1.75 0.45)
      (stroke (width 0.05) (type solid)) (layer "B.CrtYd"))
    (fp_line (start 0.825 1.6) (end 0.825 0.45)
      (stroke (width 0.05) (type solid)) (layer "B.CrtYd"))
    (fp_line (start 0.85 -1.65) (end -0.85 -1.65)
      (stroke (width 0.05) (type solid)) (layer "B.CrtYd"))
    (fp_line (start 0.85 -0.45) (end 0.85 -1.65)
      (stroke (width 0.05) (type solid)) (layer "B.CrtYd"))
    (fp_line (start 1.75 -0.45) (end 0.85 -0.45)
      (stroke (width 0.05) (type solid)) (layer "B.CrtYd"))
    (fp_line (start 1.75 0.45) (end 1.75 -0.45)
      (stroke (width 0.05) (type solid)) (layer "B.CrtYd"))
    (fp_line (start -0.712 -1.519) (end 0.688 -1.519)
      (stroke (width 0.15) (type solid)) (layer "B.Fab"))
    (fp_line (start -0.712 1.325) (end -0.712 -1.523)
      (stroke (width 0.15) (type solid)) (layer "B.Fab"))
    (fp_line (start -0.437 1.526) (end -0.712 1.325)
      (stroke (width 0.15) (type solid)) (layer "B.Fab"))
    (fp_line (start -0.437 1.526) (end 0.688 1.526)
      (stroke (width 0.15) (type solid)) (layer "B.Fab"))
    (fp_line (start 0.688 -1.519) (end 0.688 1.52)
      (stroke (width 0.15) (type solid)) (layer "B.Fab"))
    (pad "1" smd roundrect (at -1.1 0.951) (size 1 0.6) (layers "B.Cu" "B.Paste" "B.Mask") (roundrect_rratio 0.15)
      (net 430 "Net-(Q6-G)") (pinfunction "G") (pintype "bidirectional"))
    (pad "2" smd roundrect (at -1.1 -0.949) (size 1 0.6) (layers "B.Cu" "B.Paste" "B.Mask") (roundrect_rratio 0.15)
      (net 306 "USB_5V") (pinfunction "S") (pintype "bidirectional"))
    (pad "3" smd roundrect (at 1.1 0.0005) (size 1 0.6) (layers "B.Cu" "B.Paste" "B.Mask") (roundrect_rratio 0.15)
      (net 243 "Net-(Q6-D)") (pinfunction "D") (pintype "bidirectional"))
  )

  (footprint "kria-k26-devboard-footprints:FB_0402_1005Metric" (layer "B.Cu")
    (at 110.75 86 90)
    (descr "Ferrite Bead SMD 0402")
    (tags "ferrite bead SMD 0402")
    (property "Author" "Antmicro")
    (property "License" "Apache-2.0")
    (property "MPN" "BLM15PD121SN1D")
    (property "Manufacturer" "Murata")
    (property "Sheetfile" "k26_som.kicad_sch")
    (property "Sheetname" "Xilinx K26 SOM")
    (attr smd)
    (fp_text reference "FB2" (at 1.07 1.35 270) (layer "B.SilkS")
        (effects (font (size 0.7 0.7) (thickness 0.15)) (justify left bottom mirror))
    )
    (fp_text value "FB_120Z_1.3A_0402" (at 0 -1.4 270) (layer "B.Fab") hide
        (effects (font (size 0.7 0.7) (thickness 0.15)) (justify left bottom mirror))
    )
    (fp_text user "${REFERENCE}" (at -0.95 -3.168 270) (layer "B.Fab") hide
        (effects (font (size 0.7 0.7) (thickness 0.15)) (justify left bottom mirror))
    )
    (fp_text user "Author: Antmicro" (at -0.95 -4.169 270) (layer "B.Fab") hide
        (effects (font (size 0.7 0.7) (thickness 0.15)) (justify left bottom mirror))
    )
    (fp_text user "License: Apache-2.0" (at -0.95 -5.169 270) (layer "B.Fab") hide
        (effects (font (size 0.7 0.7) (thickness 0.15)) (justify left bottom mirror))
    )
    (fp_rect (start -0.95 0.48) (end 0.95 -0.48)
      (stroke (width 0.05) (type solid)) (fill none) (layer "B.CrtYd"))
    (fp_rect (start -0.5 0.25) (end 0.5 -0.25)
      (stroke (width 0.15) (type solid)) (fill none) (layer "B.Fab"))
    (pad "1" smd roundrect (at -0.485 0 90) (size 0.59 0.64) (layers "B.Cu" "B.Paste" "B.Mask") (roundrect_rratio 0.25)
      (net 1 "GND") (pintype "passive"))
    (pad "2" smd roundrect (at 0.485 0 90) (size 0.59 0.64) (layers "B.Cu" "B.Paste" "B.Mask") (roundrect_rratio 0.25)
      (net 245 "Net-(FB2-Pad2)") (pintype "passive"))
  )

  (footprint "kria-k26-devboard-footprints:FB_0402_1005Metric" (layer "B.Cu")
    (at 105.45 86 90)
    (descr "Ferrite Bead SMD 0402")
    (tags "ferrite bead SMD 0402")
    (property "Author" "Antmicro")
    (property "License" "Apache-2.0")
    (property "MPN" "BLM15PD121SN1D")
    (property "Manufacturer" "Murata")
    (property "Sheetfile" "k26_som.kicad_sch")
    (property "Sheetname" "Xilinx K26 SOM")
    (attr smd)
    (fp_text reference "FB1" (at 1.17 -0.61 270) (layer "B.SilkS")
        (effects (font (size 0.7 0.7) (thickness 0.15)) (justify left bottom mirror))
    )
    (fp_text value "FB_120Z_1.3A_0402" (at 0 -1.4 270) (layer "B.Fab") hide
        (effects (font (size 0.7 0.7) (thickness 0.15)) (justify left bottom mirror))
    )
    (fp_text user "Author: Antmicro" (at -0.95 -4.169 270) (layer "B.Fab") hide
        (effects (font (size 0.7 0.7) (thickness 0.15)) (justify left bottom mirror))
    )
    (fp_text user "${REFERENCE}" (at -0.95 -3.168 270) (layer "B.Fab") hide
        (effects (font (size 0.7 0.7) (thickness 0.15)) (justify left bottom mirror))
    )
    (fp_text user "License: Apache-2.0" (at -0.95 -5.169 270) (layer "B.Fab") hide
        (effects (font (size 0.7 0.7) (thickness 0.15)) (justify left bottom mirror))
    )
    (fp_rect (start -0.95 0.48) (end 0.95 -0.48)
      (stroke (width 0.05) (type solid)) (fill none) (layer "B.CrtYd"))
    (fp_rect (start -0.5 0.25) (end 0.5 -0.25)
      (stroke (width 0.15) (type solid)) (fill none) (layer "B.Fab"))
    (pad "1" smd roundrect (at -0.485 0 90) (size 0.59 0.64) (layers "B.Cu" "B.Paste" "B.Mask") (roundrect_rratio 0.25)
      (net 243 "Net-(Q6-D)") (pintype "passive"))
    (pad "2" smd roundrect (at 0.485 0 90) (size 0.59 0.64) (layers "B.Cu" "B.Paste" "B.Mask") (roundrect_rratio 0.25)
      (net 244 "Net-(FB1-Pad2)") (pintype "passive"))
  )

  (footprint "kria-k26-devboard-footprints:D_SOD-323F" (layer "B.Cu")
    (at 108 90.05)
    (property "Author" "Antmicro")
    (property "License" "Apache-2.0")
    (property "MPN" "1N4148WS")
    (property "Manufacturer" "ON Semiconductor")
    (property "Sheetfile" "k26_som.kicad_sch")
    (property "Sheetname" "Xilinx K26 SOM")
    (property "ki_description" "Small Signal Fast Switching Diode")
    (attr smd)
    (fp_text reference "D3" (at 0.8 1.65 180) (layer "B.SilkS")
        (effects (font (size 0.7 0.7) (thickness 0.15)) (justify left bottom mirror))
    )
    (fp_text value "1N4148WS" (at -1.7 -1.9 180) (layer "B.Fab") hide
        (effects (font (size 0.7 0.7) (thickness 0.15)) (justify left bottom mirror))
    )
    (fp_text user "${REFERENCE}" (at -1.8 -3.2 180) (layer "B.Fab") hide
        (effects (font (size 0.7 0.7) (thickness 0.15)) (justify left bottom mirror))
    )
    (fp_text user "Author: Antmicro" (at -1.8 -4.46 180) (layer "B.Fab") hide
        (effects (font (size 0.7 0.7) (thickness 0.15)) (justify left bottom mirror))
    )
    (fp_text user "License: Apache-2.0" (at -1.8 -5.8 180) (layer "B.Fab") hide
        (effects (font (size 0.7 0.7) (thickness 0.15)) (justify left bottom mirror))
    )
    (fp_line (start -0.975 -0.748) (end -0.975 -0.45)
      (stroke (width 0.15) (type solid)) (layer "B.SilkS"))
    (fp_line (start -0.975 0.75) (end -0.975 0.45)
      (stroke (width 0.15) (type solid)) (layer "B.SilkS"))
    (fp_line (start -0.625 -0.748) (end -0.975 -0.748)
      (stroke (width 0.15) (type solid)) (layer "B.SilkS"))
    (fp_line (start -0.625 0.75) (end -0.975 0.75)
      (stroke (width 0.15) (type solid)) (layer "B.SilkS"))
    (fp_line (start -0.5 0.426) (end -0.5 -0.424)
      (stroke (width 0.15) (type solid)) (layer "B.SilkS"))
    (fp_line (start 0.623 0.75) (end 0.973 0.75)
      (stroke (width 0.15) (type solid)) (layer "B.SilkS"))
    (fp_line (start 0.973 -0.748) (end 0.623 -0.748)
      (stroke (width 0.15) (type solid)) (layer "B.SilkS"))
    (fp_line (start 0.973 -0.45) (end 0.973 -0.748)
      (stroke (width 0.15) (type solid)) (layer "B.SilkS"))
    (fp_line (start 0.973 0.75) (end 0.973 0.45)
      (stroke (width 0.15) (type solid)) (layer "B.SilkS"))
    (fp_rect (start -1.6 0.827) (end 1.599 -0.825)
      (stroke (width 0.05) (type solid)) (fill none) (layer "B.CrtYd"))
    (fp_line (start -0.85 -0.623) (end -0.85 0.625)
      (stroke (width 0.15) (type solid)) (layer "B.Fab"))
    (fp_line (start -0.85 -0.623) (end 0.848 -0.623)
      (stroke (width 0.15) (type solid)) (layer "B.Fab"))
    (fp_line (start -0.85 0.625) (end 0.848 0.625)
      (stroke (width 0.15) (type solid)) (layer "B.Fab"))
    (fp_line (start 0.848 0.625) (end 0.848 -0.623)
      (stroke (width 0.15) (type solid)) (layer "B.Fab"))
    (pad "A" smd roundrect (at 1.05 0) (size 0.8 0.6) (layers "B.Cu" "B.Paste" "B.Mask") (roundrect_rratio 0.15)
      (net 1 "GND") (pinfunction "A") (pintype "passive"))
    (pad "K" smd roundrect (at -1.051 0) (size 0.8 0.6) (layers "B.Cu" "B.Paste" "B.Mask") (roundrect_rratio 0.15)
      (net 243 "Net-(Q6-D)") (pinfunction "K") (pintype "passive"))
  )

  (footprint "kria-k26-devboard-footprints:C_0402_1005Metric" (layer "B.Cu")
    (at 108.95 88.55)
    (descr "Capacitor SMD 0402")
    (tags "capacitor SMD 0402")
    (property "Author" "Antmicro")
    (property "Dielectric" "X5R")
    (property "License" "Apache-2.0")
    (property "MPN" "GRM155R61H104KE14D")
    (property "Manufacturer" "Murata")
    (property "Sheetfile" "k26_som.kicad_sch")
    (property "Sheetname" "Xilinx K26 SOM")
    (property "Val" "100n")
    (property "Voltage" "50V")
    (property "ki_description" " ")
    (attr smd)
    (fp_text reference "C126" (at 3.68 1.56 180) (layer "B.SilkS")
        (effects (font (size 0.7 0.7) (thickness 0.15)) (justify left bottom mirror))
    )
    (fp_text value "C_100n_0402" (at 0 -1.4 180) (layer "B.Fab") hide
        (effects (font (size 0.7 0.7) (thickness 0.15)) (justify left bottom mirror))
    )
    (fp_text user "Author: Antmicro" (at -0.932 -4.17 180) (layer "B.Fab") hide
        (effects (font (size 0.7 0.7) (thickness 0.15)) (justify left bottom mirror))
    )
    (fp_text user "License: Apache-2.0" (at -0.932 -5.17 180) (layer "B.Fab") hide
        (effects (font (size 0.7 0.7) (thickness 0.15)) (justify left bottom mirror))
    )
    (fp_text user "${REFERENCE}" (at -0.932 -3.168 180) (layer "B.Fab") hide
        (effects (font (size 0.7 0.7) (thickness 0.15)) (justify left bottom mirror))
    )
    (fp_rect (start -0.94 0.47) (end 0.94 -0.47)
      (stroke (width 0.05) (type solid)) (fill none) (layer "B.CrtYd"))
    (fp_rect (start -0.499 0.249) (end 0.499 -0.249)
      (stroke (width 0.15) (type solid)) (fill none) (layer "B.Fab"))
    (pad "1" smd roundrect (at -0.484 0) (size 0.59 0.64) (layers "B.Cu" "B.Paste" "B.Mask") (roundrect_rratio 0.25)
      (net 243 "Net-(Q6-D)") (pintype "passive"))
    (pad "2" smd roundrect (at 0.484 0) (size 0.59 0.64) (layers "B.Cu" "B.Paste" "B.Mask") (roundrect_rratio 0.25)
      (net 1 "GND") (pintype "passive"))
  )

  (footprint "kria-k26-devboard-footprints:C_0402_1005Metric" (layer "B.Cu")
    (at 150.94 145.93)
    (descr "Capacitor SMD 0402")
    (tags "capacitor SMD 0402")
    (property "Author" "Antmicro")
    (property "Dielectric" "X5R")
    (property "License" "Apache-2.0")
    (property "MPN" "GRM155R61H104KE14D")
    (property "Manufacturer" "Murata")
    (property "Sheetfile" "kria-k26-devboard.kicad_sch")
    (property "Sheetname" "")
    (property "Val" "100n")
    (property "Voltage" "50V")
    (property "ki_description" " ")
    (attr smd)
    (fp_text reference "C1" (at 2.360711 0.312133 180) (layer "B.SilkS")
        (effects (font (size 0.7 0.7) (thickness 0.15)) (justify left bottom mirror))
    )
    (fp_text value "C_100n_0402" (at 0 -1.4 180) (layer "B.Fab") hide
        (effects (font (size 0.7 0.7) (thickness 0.15)) (justify left bottom mirror))
    )
    (fp_text user "Author: Antmicro" (at -0.932 -4.17 180) (layer "B.Fab") hide
        (effects (font (size 0.7 0.7) (thickness 0.15)) (justify left bottom mirror))
    )
    (fp_text user "License: Apache-2.0" (at -0.932 -5.17 180) (layer "B.Fab") hide
        (effects (font (size 0.7 0.7) (thickness 0.15)) (justify left bottom mirror))
    )
    (fp_text user "${REFERENCE}" (at -0.932 -3.168 180) (layer "B.Fab") hide
        (effects (font (size 0.7 0.7) (thickness 0.15)) (justify left bottom mirror))
    )
    (fp_rect (start -0.94 0.47) (end 0.94 -0.47)
      (stroke (width 0.05) (type solid)) (fill none) (layer "B.CrtYd"))
    (fp_rect (start -0.499 0.249) (end 0.499 -0.249)
      (stroke (width 0.15) (type solid)) (fill none) (layer "B.Fab"))
    (pad "1" smd roundrect (at -0.484 0) (size 0.59 0.64) (layers "B.Cu" "B.Paste" "B.Mask") (roundrect_rratio 0.25)
      (net 318 "SH_DOWN") (pintype "passive"))
    (pad "2" smd roundrect (at 0.484 0) (size 0.59 0.64) (layers "B.Cu" "B.Paste" "B.Mask") (roundrect_rratio 0.25)
      (net 1 "GND") (pintype "passive"))
  )

  (footprint "kria-k26-devboard-footprints:C_0402_1005Metric" (layer "B.Cu")
    (at 90.6 127.775 180)
    (descr "Capacitor SMD 0402")
    (tags "capacitor SMD 0402")
    (property "Author" "Antmicro")
    (property "Dielectric" "X5R")
    (property "License" "Apache-2.0")
    (property "MPN" "GRM155R61H104KE14D")
    (property "Manufacturer" "Murata")
    (property "Sheetfile" "k26_som.kicad_sch")
    (property "Sheetname" "Xilinx K26 SOM")
    (property "Val" "100n")
    (property "Voltage" "50V")
    (property "ki_description" " ")
    (attr smd)
    (fp_text reference "C128" (at 0.87 -0.355) (layer "B.SilkS")
        (effects (font (size 0.7 0.7) (thickness 0.15)) (justify left bottom mirror))
    )
    (fp_text value "C_100n_0402" (at 0 -1.4) (layer "B.Fab") hide
        (effects (font (size 0.7 0.7) (thickness 0.15)) (justify left bottom mirror))
    )
    (fp_text user "License: Apache-2.0" (at -0.932 -5.17) (layer "B.Fab") hide
        (effects (font (size 0.7 0.7) (thickness 0.15)) (justify left bottom mirror))
    )
    (fp_text user "Author: Antmicro" (at -0.932 -4.17) (layer "B.Fab") hide
        (effects (font (size 0.7 0.7) (thickness 0.15)) (justify left bottom mirror))
    )
    (fp_text user "${REFERENCE}" (at -0.932 -3.168) (layer "B.Fab") hide
        (effects (font (size 0.7 0.7) (thickness 0.15)) (justify left bottom mirror))
    )
    (fp_rect (start -0.94 0.47) (end 0.94 -0.47)
      (stroke (width 0.05) (type solid)) (fill none) (layer "B.CrtYd"))
    (fp_rect (start -0.499 0.249) (end 0.499 -0.249)
      (stroke (width 0.15) (type solid)) (fill none) (layer "B.Fab"))
    (pad "1" smd roundrect (at -0.484 0 180) (size 0.59 0.64) (layers "B.Cu" "B.Paste" "B.Mask") (roundrect_rratio 0.25)
      (net 20 "PL_3V3") (pintype "passive"))
    (pad "2" smd roundrect (at 0.484 0 180) (size 0.59 0.64) (layers "B.Cu" "B.Paste" "B.Mask") (roundrect_rratio 0.25)
      (net 1 "GND") (pintype "passive"))
  )

  (footprint "kria-k26-devboard-footprints:C_0402_1005Metric" (layer "B.Cu")
    (at 120.2 78.97 -90)
    (descr "Capacitor SMD 0402")
    (tags "capacitor SMD 0402")
    (property "Author" "Antmicro")
    (property "Dielectric" "X5R")
    (property "License" "Apache-2.0")
    (property "MPN" "GRM155R61H104KE14D")
    (property "Manufacturer" "Murata")
    (property "Sheetfile" "usb.kicad_sch")
    (property "Sheetname" "USB")
    (property "Val" "100n")
    (property "Voltage" "50V")
    (property "ki_description" " ")
    (attr smd)
    (fp_text reference "C50" (at -3.055 -0.28 90) (layer "B.SilkS")
        (effects (font (size 0.7 0.7) (thickness 0.15)) (justify left bottom mirror))
    )
    (fp_text value "C_100n_0402" (at 0 -1.4 90) (layer "B.Fab") hide
        (effects (font (size 0.7 0.7) (thickness 0.15)) (justify left bottom mirror))
    )
    (fp_text user "Author: Antmicro" (at -0.932 -4.17 90) (layer "B.Fab") hide
        (effects (font (size 0.7 0.7) (thickness 0.15)) (justify left bottom mirror))
    )
    (fp_text user "${REFERENCE}" (at -0.932 -3.168 90) (layer "B.Fab") hide
        (effects (font (size 0.7 0.7) (thickness 0.15)) (justify left bottom mirror))
    )
    (fp_text user "License: Apache-2.0" (at -0.932 -5.17 90) (layer "B.Fab") hide
        (effects (font (size 0.7 0.7) (thickness 0.15)) (justify left bottom mirror))
    )
    (fp_rect (start -0.94 0.47) (end 0.94 -0.47)
      (stroke (width 0.05) (type solid)) (fill none) (layer "B.CrtYd"))
    (fp_rect (start -0.499 0.249) (end 0.499 -0.249)
      (stroke (width 0.15) (type solid)) (fill none) (layer "B.Fab"))
    (pad "1" smd roundrect (at -0.484 0 270) (size 0.59 0.64) (layers "B.Cu" "B.Paste" "B.Mask") (roundrect_rratio 0.25)
      (net 15 "PS_3V3") (pintype "passive"))
    (pad "2" smd roundrect (at 0.484 0 270) (size 0.59 0.64) (layers "B.Cu" "B.Paste" "B.Mask") (roundrect_rratio 0.25)
      (net 1 "GND") (pintype "passive"))
  )

  (footprint "kria-k26-devboard-footprints:C_0603_1608Metric" (layer "B.Cu")
    (at 151.025 77.66)
    (descr "Capacitor SMD 0603")
    (tags "capacitor 0603")
    (property "Author" "Antmicro")
    (property "Dielectric" "")
    (property "License" "Apache-2.0")
    (property "MPN" "CL10A226MO7JZNC")
    (property "Manufacturer" "Samsung")
    (property "Sheetfile" "dc-dc-conventers.kicad_sch")
    (property "Sheetname" "DC/DC conventers")
    (property "Val" "22u/16V")
    (property "Voltage" "")
    (property "ki_description" " ")
    (attr smd)
    (fp_text reference "C195" (at 4.005 0.48 180) (layer "B.SilkS")
        (effects (font (size 0.7 0.7) (thickness 0.15)) (justify left bottom mirror))
    )
    (fp_text value "C_22u_16V_0603" (at 0 -1.6 180) (layer "B.Fab") hide
        (effects (font (size 0.7 0.7) (thickness 0.15)) (justify left bottom mirror))
    )
    (fp_text user "${REFERENCE}" (at -1.682 -3.895 180) (layer "B.Fab") hide
        (effects (font (size 0.7 0.7) (thickness 0.15)) (justify left bottom mirror))
    )
    (fp_text user "License: Apache-2.0" (at -1.682 -5.895 180) (layer "B.Fab") hide
        (effects (font (size 0.7 0.7) (thickness 0.15)) (justify left bottom mirror))
    )
    (fp_text user "Author: Antmicro" (at -1.682 -4.894 180) (layer "B.Fab") hide
        (effects (font (size 0.7 0.7) (thickness 0.15)) (justify left bottom mirror))
    )
    (fp_line (start -0.3 -0.3) (end 0.3 -0.3)
      (stroke (width 0.15) (type solid)) (layer "B.SilkS"))
    (fp_line (start -0.3 0.3) (end 0.3 0.3)
      (stroke (width 0.15) (type solid)) (layer "B.SilkS"))
    (fp_rect (start -1.24 0.7) (end 1.24 -0.7)
      (stroke (width 0.05) (type solid)) (fill none) (layer "B.CrtYd"))
    (fp_rect (start -0.8 0.4) (end 0.8 -0.4)
      (stroke (width 0.15) (type solid)) (fill none) (layer "B.Fab"))
    (pad "1" smd roundrect (at -0.7 0) (size 0.6 0.8) (layers "B.Cu" "B.Paste" "B.Mask") (roundrect_rratio 0.2)
      (net 772 "/Power Supply/DC/DC conventers/USB_5V_OUT") (pintype "passive"))
    (pad "2" smd roundrect (at 0.7 0) (size 0.6 0.8) (layers "B.Cu" "B.Paste" "B.Mask") (roundrect_rratio 0.2)
      (net 1 "GND") (pintype "passive"))
  )

  (footprint "kria-k26-devboard-footprints:R_0402_1005Metric" (layer "B.Cu")
    (at 146.559999 76.14 -90)
    (descr "Resistor SMD 0402")
    (tags "resistor SMD 0402")
    (property "Author" "Antmicro")
    (property "License" "Apache-2.0")
    (property "MPN" "CR0402-FX-2402GLF")
    (property "Manufacturer" "Bourns")
    (property "Sheetfile" "dc-dc-conventers.kicad_sch")
    (property "Sheetname" "DC/DC conventers")
    (property "Tolerance" "1%")
    (property "Val" "24k")
    (property "ki_description" "24k resistor in 0402 package with 1% tolerance")
    (attr smd)
    (fp_text reference "R123" (at -1.494239 2.543351 90) (layer "B.SilkS")
        (effects (font (size 0.7 0.7) (thickness 0.15)) (justify left bottom mirror))
    )
    (fp_text value "R_24k_0402" (at 0 -1.4 90) (layer "B.Fab") hide
        (effects (font (size 0.7 0.7) (thickness 0.15)) (justify left bottom mirror))
    )
    (fp_text user "Author: Antmicro" (at -0.95 -4.169 90) (layer "B.Fab") hide
        (effects (font (size 0.7 0.7) (thickness 0.15)) (justify left bottom mirror))
    )
    (fp_text user "${REFERENCE}" (at -0.95 -3.168 90) (layer "B.Fab") hide
        (effects (font (size 0.7 0.7) (thickness 0.15)) (justify left bottom mirror))
    )
    (fp_text user "License: Apache-2.0" (at -0.95 -5.169 90) (layer "B.Fab") hide
        (effects (font (size 0.7 0.7) (thickness 0.15)) (justify left bottom mirror))
    )
    (fp_rect (start -0.93 0.47) (end 0.93 -0.47)
      (stroke (width 0.05) (type solid)) (fill none) (layer "B.CrtYd"))
    (fp_rect (start -0.5 0.25) (end 0.5 -0.25)
      (stroke (width 0.15) (type solid)) (fill none) (layer "B.Fab"))
    (pad "1" smd roundrect (at -0.485 0 270) (size 0.59 0.64) (layers "B.Cu" "B.Paste" "B.Mask") (roundrect_rratio 0.25)
      (net 254 "Net-(U47-FB)") (pintype "passive"))
    (pad "2" smd roundrect (at 0.485 0 270) (size 0.59 0.64) (layers "B.Cu" "B.Paste" "B.Mask") (roundrect_rratio 0.25)
      (net 1 "GND") (pintype "passive"))
  )

  (footprint "kria-k26-devboard-footprints:C_0402_1005Metric" (layer "B.Cu")
    (at 95.49 84.96 90)
    (descr "Capacitor SMD 0402")
    (tags "capacitor SMD 0402")
    (property "Author" "Antmicro")
    (property "Dielectric" "X5R")
    (property "License" "Apache-2.0")
    (property "MPN" "GRM155R61H104KE14D")
    (property "Manufacturer" "Murata")
    (property "Sheetfile" "dp.kicad_sch")
    (property "Sheetname" "Display Port")
    (property "Val" "100n")
    (property "Voltage" "50V")
    (property "ki_description" " ")
    (attr smd)
    (fp_text reference "C4" (at 0.88 1.38 270) (layer "B.SilkS")
        (effects (font (size 0.7 0.7) (thickness 0.15)) (justify left bottom mirror))
    )
    (fp_text value "C_100n_0402" (at 0 -1.4 270) (layer "B.Fab") hide
        (effects (font (size 0.7 0.7) (thickness 0.15)) (justify left bottom mirror))
    )
    (fp_text user "License: Apache-2.0" (at -0.932 -5.17 270) (layer "B.Fab") hide
        (effects (font (size 0.7 0.7) (thickness 0.15)) (justify left bottom mirror))
    )
    (fp_text user "${REFERENCE}" (at -0.932 -3.168 270) (layer "B.Fab") hide
        (effects (font (size 0.7 0.7) (thickness 0.15)) (justify left bottom mirror))
    )
    (fp_text user "Author: Antmicro" (at -0.932 -4.17 270) (layer "B.Fab") hide
        (effects (font (size 0.7 0.7) (thickness 0.15)) (justify left bottom mirror))
    )
    (fp_rect (start -0.94 0.47) (end 0.94 -0.47)
      (stroke (width 0.05) (type solid)) (fill none) (layer "B.CrtYd"))
    (fp_rect (start -0.499 0.249) (end 0.499 -0.249)
      (stroke (width 0.15) (type solid)) (fill none) (layer "B.Fab"))
    (pad "1" smd roundrect (at -0.484 0 90) (size 0.59 0.64) (layers "B.Cu" "B.Paste" "B.Mask") (roundrect_rratio 0.25)
      (net 15 "PS_3V3") (pintype "passive"))
    (pad "2" smd roundrect (at 0.484 0 90) (size 0.59 0.64) (layers "B.Cu" "B.Paste" "B.Mask") (roundrect_rratio 0.25)
      (net 1 "GND") (pintype "passive"))
  )

  (footprint "kria-k26-devboard-footprints:C_0402_1005Metric" (layer "B.Cu")
    (at 118.9 90.35 90)
    (descr "Capacitor SMD 0402")
    (tags "capacitor SMD 0402")
    (property "Author" "Antmicro")
    (property "Dielectric" "X5R")
    (property "License" "Apache-2.0")
    (property "MPN" "GRM155R61H104KE14D")
    (property "Manufacturer" "Murata")
    (property "Sheetfile" "usb.kicad_sch")
    (property "Sheetname" "USB")
    (property "Val" "100n")
    (property "Voltage" "50V")
    (property "ki_description" " ")
    (attr smd)
    (fp_text reference "C47" (at 0.5 -1.52 270) (layer "B.SilkS")
        (effects (font (size 0.7 0.7) (thickness 0.15)) (justify left bottom mirror))
    )
    (fp_text value "C_100n_0402" (at 0 -1.4 270) (layer "B.Fab") hide
        (effects (font (size 0.7 0.7) (thickness 0.15)) (justify left bottom mirror))
    )
    (fp_text user "Author: Antmicro" (at -0.932 -4.17 270) (layer "B.Fab") hide
        (effects (font (size 0.7 0.7) (thickness 0.15)) (justify left bottom mirror))
    )
    (fp_text user "License: Apache-2.0" (at -0.932 -5.17 270) (layer "B.Fab") hide
        (effects (font (size 0.7 0.7) (thickness 0.15)) (justify left bottom mirror))
    )
    (fp_text user "${REFERENCE}" (at -0.932 -3.168 270) (layer "B.Fab") hide
        (effects (font (size 0.7 0.7) (thickness 0.15)) (justify left bottom mirror))
    )
    (fp_rect (start -0.94 0.47) (end 0.94 -0.47)
      (stroke (width 0.05) (type solid)) (fill none) (layer "B.CrtYd"))
    (fp_rect (start -0.499 0.249) (end 0.499 -0.249)
      (stroke (width 0.15) (type solid)) (fill none) (layer "B.Fab"))
    (pad "1" smd roundrect (at -0.484 0 90) (size 0.59 0.64) (layers "B.Cu" "B.Paste" "B.Mask") (roundrect_rratio 0.25)
      (net 15 "PS_3V3") (pintype "passive"))
    (pad "2" smd roundrect (at 0.484 0 90) (size 0.59 0.64) (layers "B.Cu" "B.Paste" "B.Mask") (roundrect_rratio 0.25)
      (net 1 "GND") (pintype "passive"))
  )

  (footprint "kria-k26-devboard-footprints:C_0402_1005Metric" (layer "B.Cu")
    (at 116.656942 81.5)
    (descr "Capacitor SMD 0402")
    (tags "capacitor SMD 0402")
    (property "Author" "Antmicro")
    (property "Dielectric" "X5R")
    (property "License" "Apache-2.0")
    (property "MPN" "GRM155R61H104KE14D")
    (property "Manufacturer" "Murata")
    (property "Sheetfile" "usb.kicad_sch")
    (property "Sheetname" "USB")
    (property "Val" "100n")
    (property "Voltage" "50V")
    (property "ki_description" " ")
    (attr smd)
    (fp_text reference "C45" (at -0.916942 0.43 180) (layer "B.SilkS")
        (effects (font (size 0.7 0.7) (thickness 0.15)) (justify left bottom mirror))
    )
    (fp_text value "C_100n_0402" (at 0 -1.4 180) (layer "B.Fab") hide
        (effects (font (size 0.7 0.7) (thickness 0.15)) (justify left bottom mirror))
    )
    (fp_text user "${REFERENCE}" (at -0.932 -3.168 180) (layer "B.Fab") hide
        (effects (font (size 0.7 0.7) (thickness 0.15)) (justify left bottom mirror))
    )
    (fp_text user "License: Apache-2.0" (at -0.932 -5.17 180) (layer "B.Fab") hide
        (effects (font (size 0.7 0.7) (thickness 0.15)) (justify left bottom mirror))
    )
    (fp_text user "Author: Antmicro" (at -0.932 -4.17 180) (layer "B.Fab") hide
        (effects (font (size 0.7 0.7) (thickness 0.15)) (justify left bottom mirror))
    )
    (fp_rect (start -0.94 0.47) (end 0.94 -0.47)
      (stroke (width 0.05) (type solid)) (fill none) (layer "B.CrtYd"))
    (fp_rect (start -0.499 0.249) (end 0.499 -0.249)
      (stroke (width 0.15) (type solid)) (fill none) (layer "B.Fab"))
    (pad "1" smd roundrect (at -0.484 0) (size 0.59 0.64) (layers "B.Cu" "B.Paste" "B.Mask") (roundrect_rratio 0.25)
      (net 18 "PS_1V2") (pintype "passive"))
    (pad "2" smd roundrect (at 0.484 0) (size 0.59 0.64) (layers "B.Cu" "B.Paste" "B.Mask") (roundrect_rratio 0.25)
      (net 1 "GND") (pintype "passive"))
  )

  (footprint "kria-k26-devboard-footprints:R_0402_1005Metric" (layer "B.Cu")
    (at 116.2 78.97 90)
    (descr "Resistor SMD 0402")
    (tags "resistor SMD 0402")
    (property "Author" "Antmicro")
    (property "License" "Apache-2.0")
    (property "MPN" "CR0402-FX-2003GLF")
    (property "Manufacturer" "Bourns")
    (property "Sheetfile" "usb.kicad_sch")
    (property "Sheetname" "USB")
    (property "Tolerance" "1%")
    (property "Val" "200k")
    (property "ki_description" "200k resistor in 0402 package with 1% tolerance")
    (attr smd)
    (fp_text reference "R59" (at 3.065 0.38 270) (layer "B.SilkS")
        (effects (font (size 0.7 0.7) (thickness 0.15)) (justify left bottom mirror))
    )
    (fp_text value "R_200k_0402" (at 0 -1.4 270) (layer "B.Fab") hide
        (effects (font (size 0.7 0.7) (thickness 0.15)) (justify left bottom mirror))
    )
    (fp_text user "${REFERENCE}" (at -0.95 -3.168 270) (layer "B.Fab") hide
        (effects (font (size 0.7 0.7) (thickness 0.15)) (justify left bottom mirror))
    )
    (fp_text user "Author: Antmicro" (at -0.95 -4.169 270) (layer "B.Fab") hide
        (effects (font (size 0.7 0.7) (thickness 0.15)) (justify left bottom mirror))
    )
    (fp_text user "License: Apache-2.0" (at -0.95 -5.169 270) (layer "B.Fab") hide
        (effects (font (size 0.7 0.7) (thickness 0.15)) (justify left bottom mirror))
    )
    (fp_rect (start -0.93 0.47) (end 0.93 -0.47)
      (stroke (width 0.05) (type solid)) (fill none) (layer "B.CrtYd"))
    (fp_rect (start -0.5 0.25) (end 0.5 -0.25)
      (stroke (width 0.15) (type solid)) (fill none) (layer "B.Fab"))
    (pad "1" smd roundrect (at -0.485 0 90) (size 0.59 0.64) (layers "B.Cu" "B.Paste" "B.Mask") (roundrect_rratio 0.25)
      (net 1 "GND") (pintype "passive"))
    (pad "2" smd roundrect (at 0.485 0 90) (size 0.59 0.64) (layers "B.Cu" "B.Paste" "B.Mask") (roundrect_rratio 0.25)
      (net 662 "Net-(U17-PF9)") (pintype "passive"))
  )

  (footprint "kria-k26-devboard-footprints:R_0402_1005Metric" (layer "B.Cu")
    (at 119.2 78.97 90)
    (descr "Resistor SMD 0402")
    (tags "resistor SMD 0402")
    (property "Author" "Antmicro")
    (property "License" "Apache-2.0")
    (property "MPN" "CR0402-FX-2003GLF")
    (property "Manufacturer" "Bourns")
    (property "Sheetfile" "usb.kicad_sch")
    (property "Sheetname" "USB")
    (property "Tolerance" "1%")
    (property "Val" "200k")
    (property "ki_description" "200k resistor in 0402 package with 1% tolerance")
    (attr smd)
    (fp_text reference "R53" (at 3.065 0.38 270) (layer "B.SilkS")
        (effects (font (size 0.7 0.7) (thickness 0.15)) (justify left bottom mirror))
    )
    (fp_text value "R_200k_0402" (at 0 -1.4 270) (layer "B.Fab") hide
        (effects (font (size 0.7 0.7) (thickness 0.15)) (justify left bottom mirror))
    )
    (fp_text user "Author: Antmicro" (at -0.95 -4.169 270) (layer "B.Fab") hide
        (effects (font (size 0.7 0.7) (thickness 0.15)) (justify left bottom mirror))
    )
    (fp_text user "License: Apache-2.0" (at -0.95 -5.169 270) (layer "B.Fab") hide
        (effects (font (size 0.7 0.7) (thickness 0.15)) (justify left bottom mirror))
    )
    (fp_text user "${REFERENCE}" (at -0.95 -3.168 270) (layer "B.Fab") hide
        (effects (font (size 0.7 0.7) (thickness 0.15)) (justify left bottom mirror))
    )
    (fp_rect (start -0.93 0.47) (end 0.93 -0.47)
      (stroke (width 0.05) (type solid)) (fill none) (layer "B.CrtYd"))
    (fp_rect (start -0.5 0.25) (end 0.5 -0.25)
      (stroke (width 0.15) (type solid)) (fill none) (layer "B.Fab"))
    (pad "1" smd roundrect (at -0.485 0 90) (size 0.59 0.64) (layers "B.Cu" "B.Paste" "B.Mask") (roundrect_rratio 0.25)
      (net 1 "GND") (pintype "passive"))
    (pad "2" smd roundrect (at 0.485 0 90) (size 0.59 0.64) (layers "B.Cu" "B.Paste" "B.Mask") (roundrect_rratio 0.25)
      (net 656 "Net-(U17-PF3)") (pintype "passive"))
  )

  (footprint "kria-k26-devboard-footprints:C_0402_1005Metric" (layer "B.Cu")
    (at 133.4 63.741421 90)
    (descr "Capacitor SMD 0402")
    (tags "capacitor SMD 0402")
    (property "Author" "Antmicro")
    (property "Dielectric" "")
    (property "License" "Apache-2.0")
    (property "MPN" "CC0402MRX5R5BB106")
    (property "Manufacturer" "Yaego")
    (property "Sheetfile" "usb.kicad_sch")
    (property "Sheetname" "USB")
    (property "Val" "10u")
    (property "Voltage" "")
    (property "ki_description" " ")
    (attr smd)
    (fp_text reference "C73" (at 3.781421 0.36 270) (layer "B.SilkS")
        (effects (font (size 0.7 0.7) (thickness 0.15)) (justify left bottom mirror))
    )
    (fp_text value "C_10u_0402" (at 0 -1.4 270) (layer "B.Fab") hide
        (effects (font (size 0.7 0.7) (thickness 0.15)) (justify left bottom mirror))
    )
    (fp_text user "${REFERENCE}" (at -0.932 -3.168 270) (layer "B.Fab") hide
        (effects (font (size 0.7 0.7) (thickness 0.15)) (justify left bottom mirror))
    )
    (fp_text user "License: Apache-2.0" (at -0.932 -5.17 270) (layer "B.Fab") hide
        (effects (font (size 0.7 0.7) (thickness 0.15)) (justify left bottom mirror))
    )
    (fp_text user "Author: Antmicro" (at -0.932 -4.17 270) (layer "B.Fab") hide
        (effects (font (size 0.7 0.7) (thickness 0.15)) (justify left bottom mirror))
    )
    (fp_rect (start -0.94 0.47) (end 0.94 -0.47)
      (stroke (width 0.05) (type solid)) (fill none) (layer "B.CrtYd"))
    (fp_rect (start -0.499 0.249) (end 0.499 -0.249)
      (stroke (width 0.15) (type solid)) (fill none) (layer "B.Fab"))
    (pad "1" smd roundrect (at -0.484 0 90) (size 0.59 0.64) (layers "B.Cu" "B.Paste" "B.Mask") (roundrect_rratio 0.25)
      (net 64 "/USB/USB1_VBUS") (pintype "passive"))
    (pad "2" smd roundrect (at 0.484 0 90) (size 0.59 0.64) (layers "B.Cu" "B.Paste" "B.Mask") (roundrect_rratio 0.25)
      (net 1 "GND") (pintype "passive"))
  )

  (footprint "kria-k26-devboard-footprints:C_0402_1005Metric" (layer "B.Cu")
    (at 118.35 67.55)
    (descr "Capacitor SMD 0402")
    (tags "capacitor SMD 0402")
    (property "Author" "Antmicro")
    (property "Dielectric" "X5R")
    (property "License" "Apache-2.0")
    (property "MPN" "GRM155R61H104KE14D")
    (property "Manufacturer" "Murata")
    (property "Sheetfile" "usb.kicad_sch")
    (property "Sheetname" "USB")
    (property "Val" "100n")
    (property "Voltage" "50V")
    (property "ki_description" " ")
    (attr smd)
    (fp_text reference "C88" (at 3.04 0.32 180) (layer "B.SilkS")
        (effects (font (size 0.7 0.7) (thickness 0.15)) (justify left bottom mirror))
    )
    (fp_text value "C_100n_0402" (at 0 -1.4 180) (layer "B.Fab") hide
        (effects (font (size 0.7 0.7) (thickness 0.15)) (justify left bottom mirror))
    )
    (fp_text user "${REFERENCE}" (at -0.932 -3.168 180) (layer "B.Fab") hide
        (effects (font (size 0.7 0.7) (thickness 0.15)) (justify left bottom mirror))
    )
    (fp_text user "Author: Antmicro" (at -0.932 -4.17 180) (layer "B.Fab") hide
        (effects (font (size 0.7 0.7) (thickness 0.15)) (justify left bottom mirror))
    )
    (fp_text user "License: Apache-2.0" (at -0.932 -5.17 180) (layer "B.Fab") hide
        (effects (font (size 0.7 0.7) (thickness 0.15)) (justify left bottom mirror))
    )
    (fp_rect (start -0.94 0.47) (end 0.94 -0.47)
      (stroke (width 0.05) (type solid)) (fill none) (layer "B.CrtYd"))
    (fp_rect (start -0.499 0.249) (end 0.499 -0.249)
      (stroke (width 0.15) (type solid)) (fill none) (layer "B.Fab"))
    (pad "1" smd roundrect (at -0.484 0) (size 0.59 0.64) (layers "B.Cu" "B.Paste" "B.Mask") (roundrect_rratio 0.25)
      (net 87 "/USB/USB4_VBUS") (pintype "passive"))
    (pad "2" smd roundrect (at 0.484 0) (size 0.59 0.64) (layers "B.Cu" "B.Paste" "B.Mask") (roundrect_rratio 0.25)
      (net 1 "GND") (pintype "passive"))
  )

  (footprint "kria-k26-devboard-footprints:C_0402_1005Metric" (layer "B.Cu")
    (at 151.845911 88.814035 180)
    (descr "Capacitor SMD 0402")
    (tags "capacitor SMD 0402")
    (property "Author" "Antmicro")
    (property "Dielectric" "")
    (property "License" "Apache-2.0")
    (property "MPN" "C1005X6S1A105K050BC")
    (property "Manufacturer" "TDK")
    (property "Sheetfile" "eth.kicad_sch")
    (property "Sheetname" "Ethernet")
    (property "Val" "1u")
    (property "Voltage" "")
    (property "ki_description" " ")
    (attr smd)
    (fp_text reference "C112" (at 0.87 -0.41) (layer "B.SilkS")
        (effects (font (size 0.7 0.7) (thickness 0.15)) (justify left bottom mirror))
    )
    (fp_text value "C_1u_0402" (at 0 -1.4) (layer "B.Fab") hide
        (effects (font (size 0.7 0.7) (thickness 0.15)) (justify left bottom mirror))
    )
    (fp_text user "Author: Antmicro" (at -0.932 -4.17) (layer "B.Fab") hide
        (effects (font (size 0.7 0.7) (thickness 0.15)) (justify left bottom mirror))
    )
    (fp_text user "${REFERENCE}" (at -0.932 -3.168) (layer "B.Fab") hide
        (effects (font (size 0.7 0.7) (thickness 0.15)) (justify left bottom mirror))
    )
    (fp_text user "License: Apache-2.0" (at -0.932 -5.17) (layer "B.Fab") hide
        (effects (font (size 0.7 0.7) (thickness 0.15)) (justify left bottom mirror))
    )
    (fp_rect (start -0.94 0.47) (end 0.94 -0.47)
      (stroke (width 0.05) (type solid)) (fill none) (layer "B.CrtYd"))
    (fp_rect (start -0.499 0.249) (end 0.499 -0.249)
      (stroke (width 0.15) (type solid)) (fill none) (layer "B.Fab"))
    (pad "1" smd roundrect (at -0.484 0 180) (size 0.59 0.64) (layers "B.Cu" "B.Paste" "B.Mask") (roundrect_rratio 0.25)
      (net 19 "PS_1V0") (pintype "passive"))
    (pad "2" smd roundrect (at 0.484 0 180) (size 0.59 0.64) (layers "B.Cu" "B.Paste" "B.Mask") (roundrect_rratio 0.25)
      (net 1 "GND") (pintype "passive"))
  )

  (footprint "kria-k26-devboard-footprints:C_0402_1005Metric" (layer "B.Cu")
    (at 145.888373 89.9)
    (descr "Capacitor SMD 0402")
    (tags "capacitor SMD 0402")
    (property "Author" "Antmicro")
    (property "Dielectric" "X5R")
    (property "License" "Apache-2.0")
    (property "MPN" "GRM155R61H104KE14D")
    (property "Manufacturer" "Murata")
    (property "Sheetfile" "eth.kicad_sch")
    (property "Sheetname" "Ethernet")
    (property "Val" "100n")
    (property "Voltage" "50V")
    (property "ki_description" " ")
    (attr smd)
    (fp_text reference "C99" (at -0.935911 0.4 180) (layer "B.SilkS")
        (effects (font (size 0.7 0.7) (thickness 0.15)) (justify left bottom mirror))
    )
    (fp_text value "C_100n_0402" (at 0 -1.4 180) (layer "B.Fab") hide
        (effects (font (size 0.7 0.7) (thickness 0.15)) (justify left bottom mirror))
    )
    (fp_text user "${REFERENCE}" (at -0.932 -3.168 180) (layer "B.Fab") hide
        (effects (font (size 0.7 0.7) (thickness 0.15)) (justify left bottom mirror))
    )
    (fp_text user "Author: Antmicro" (at -0.932 -4.17 180) (layer "B.Fab") hide
        (effects (font (size 0.7 0.7) (thickness 0.15)) (justify left bottom mirror))
    )
    (fp_text user "License: Apache-2.0" (at -0.932 -5.17 180) (layer "B.Fab") hide
        (effects (font (size 0.7 0.7) (thickness 0.15)) (justify left bottom mirror))
    )
    (fp_rect (start -0.94 0.47) (end 0.94 -0.47)
      (stroke (width 0.05) (type solid)) (fill none) (layer "B.CrtYd"))
    (fp_rect (start -0.499 0.249) (end 0.499 -0.249)
      (stroke (width 0.15) (type solid)) (fill none) (layer "B.Fab"))
    (pad "1" smd roundrect (at -0.484 0) (size 0.59 0.64) (layers "B.Cu" "B.Paste" "B.Mask") (roundrect_rratio 0.25)
      (net 17 "PS_1V8") (pintype "passive"))
    (pad "2" smd roundrect (at 0.484 0) (size 0.59 0.64) (layers "B.Cu" "B.Paste" "B.Mask") (roundrect_rratio 0.25)
      (net 1 "GND") (pintype "passive"))
  )

  (footprint "kria-k26-devboard-footprints:R_0402_1005Metric" (layer "B.Cu")
    (at 141.315 84.19 180)
    (descr "Resistor SMD 0402")
    (tags "resistor SMD 0402")
    (property "Author" "Antmicro")
    (property "License" "Apache-2.0")
    (property "MPN" "CR0402-FX-5100GLF")
    (property "Manufacturer" "Bourns")
    (property "Sheetfile" "dc-dc-conventers.kicad_sch")
    (property "Sheetname" "DC/DC conventers")
    (property "Tolerance" "1%")
    (property "Val" "510R")
    (property "ki_description" "510R resistor in 0402 package with 1% tolerance")
    (attr smd)
    (fp_text reference "R128" (at -3.726 -0.37) (layer "B.SilkS")
        (effects (font (size 0.7 0.7) (thickness 0.15)) (justify left bottom mirror))
    )
    (fp_text value "R_510R_0402" (at 0 -1.4) (layer "B.Fab") hide
        (effects (font (size 0.7 0.7) (thickness 0.15)) (justify left bottom mirror))
    )
    (fp_text user "License: Apache-2.0" (at -0.95 -5.169) (layer "B.Fab") hide
        (effects (font (size 0.7 0.7) (thickness 0.15)) (justify left bottom mirror))
    )
    (fp_text user "Author: Antmicro" (at -0.95 -4.169) (layer "B.Fab") hide
        (effects (font (size 0.7 0.7) (thickness 0.15)) (justify left bottom mirror))
    )
    (fp_text user "${REFERENCE}" (at -0.95 -3.168) (layer "B.Fab") hide
        (effects (font (size 0.7 0.7) (thickness 0.15)) (justify left bottom mirror))
    )
    (fp_rect (start -0.93 0.47) (end 0.93 -0.47)
      (stroke (width 0.05) (type solid)) (fill none) (layer "B.CrtYd"))
    (fp_rect (start -0.5 0.25) (end 0.5 -0.25)
      (stroke (width 0.15) (type solid)) (fill none) (layer "B.Fab"))
    (pad "1" smd roundrect (at -0.485 0 180) (size 0.59 0.64) (layers "B.Cu" "B.Paste" "B.Mask") (roundrect_rratio 0.25)
      (net 240 "Net-(D15-Pad1)") (pintype "passive"))
    (pad "2" smd roundrect (at 0.485 0 180) (size 0.59 0.64) (layers "B.Cu" "B.Paste" "B.Mask") (roundrect_rratio 0.25)
      (net 766 "/Power Supply/DC/DC conventers/PS_2V5_OUT") (pintype "passive"))
  )

  (footprint "kria-k26-devboard-footprints:C_0603_1608Metric" (layer "B.Cu")
    (at 134.839 94.392 90)
    (descr "Capacitor SMD 0603")
    (tags "capacitor 0603")
    (property "Author" "Antmicro")
    (property "Dielectric" "")
    (property "License" "Apache-2.0")
    (property "MPN" "GRM188R60J226MEA0D")
    (property "Manufacturer" "Murata")
    (property "Sheetfile" "dc-dc-conventers.kicad_sch")
    (property "Sheetname" "DC/DC conventers")
    (property "Val" "22u")
    (property "Voltage" "")
    (property "ki_description" " ")
    (attr smd)
    (fp_text reference "C215" (at 1.582 -0.829 270) (layer "B.SilkS")
        (effects (font (size 0.7 0.7) (thickness 0.15)) (justify left bottom mirror))
    )
    (fp_text value "C_22u_0603" (at 0 -1.6 270) (layer "B.Fab") hide
        (effects (font (size 0.7 0.7) (thickness 0.15)) (justify left bottom mirror))
    )
    (fp_text user "Author: Antmicro" (at -1.682 -4.894 270) (layer "B.Fab") hide
        (effects (font (size 0.7 0.7) (thickness 0.15)) (justify left bottom mirror))
    )
    (fp_text user "License: Apache-2.0" (at -1.682 -5.895 270) (layer "B.Fab") hide
        (effects (font (size 0.7 0.7) (thickness 0.15)) (justify left bottom mirror))
    )
    (fp_text user "${REFERENCE}" (at -1.682 -3.895 270) (layer "B.Fab") hide
        (effects (font (size 0.7 0.7) (thickness 0.15)) (justify left bottom mirror))
    )
    (fp_line (start -0.3 -0.3) (end 0.3 -0.3)
      (stroke (width 0.15) (type solid)) (layer "B.SilkS"))
    (fp_line (start -0.3 0.3) (end 0.3 0.3)
      (stroke (width 0.15) (type solid)) (layer "B.SilkS"))
    (fp_rect (start -1.24 0.7) (end 1.24 -0.7)
      (stroke (width 0.05) (type solid)) (fill none) (layer "B.CrtYd"))
    (fp_rect (start -0.8 0.4) (end 0.8 -0.4)
      (stroke (width 0.15) (type solid)) (fill none) (layer "B.Fab"))
    (pad "1" smd roundrect (at -0.7 0 90) (size 0.6 0.8) (layers "B.Cu" "B.Paste" "B.Mask") (roundrect_rratio 0.2)
      (net 769 "/Power Supply/DC/DC conventers/PS_1V0_OUT") (pintype "passive"))
    (pad "2" smd roundrect (at 0.7 0 90) (size 0.6 0.8) (layers "B.Cu" "B.Paste" "B.Mask") (roundrect_rratio 0.2)
      (net 1 "GND") (pintype "passive"))
  )

  (footprint "kria-k26-devboard-footprints:R_0402_1005Metric" (layer "B.Cu")
    (at 139.100001 89.05 180)
    (descr "Resistor SMD 0402")
    (tags "resistor SMD 0402")
    (property "Author" "Antmicro")
    (property "License" "Apache-2.0")
    (property "MPN" "CR0402-FX-1002GLF")
    (property "Manufacturer" "Bourns")
    (property "Sheetfile" "dc-dc-conventers.kicad_sch")
    (property "Sheetname" "DC/DC conventers")
    (property "Tolerance" "1%")
    (property "Val" "10k")
    (property "ki_description" "10k resistor in 0402 package with 1% tolerance")
    (attr smd)
    (fp_text reference "R140" (at -3.669999 -0.32) (layer "B.SilkS")
        (effects (font (size 0.7 0.7) (thickness 0.15)) (justify left bottom mirror))
    )
    (fp_text value "R_10k_0402" (at 0 -1.4) (layer "B.Fab") hide
        (effects (font (size 0.7 0.7) (thickness 0.15)) (justify left bottom mirror))
    )
    (fp_text user "${REFERENCE}" (at -0.95 -3.168) (layer "B.Fab") hide
        (effects (font (size 0.7 0.7) (thickness 0.15)) (justify left bottom mirror))
    )
    (fp_text user "License: Apache-2.0" (at -0.95 -5.169) (layer "B.Fab") hide
        (effects (font (size 0.7 0.7) (thickness 0.15)) (justify left bottom mirror))
    )
    (fp_text user "Author: Antmicro" (at -0.95 -4.169) (layer "B.Fab") hide
        (effects (font (size 0.7 0.7) (thickness 0.15)) (justify left bottom mirror))
    )
    (fp_rect (start -0.93 0.47) (end 0.93 -0.47)
      (stroke (width 0.05) (type solid)) (fill none) (layer "B.CrtYd"))
    (fp_rect (start -0.5 0.25) (end 0.5 -0.25)
      (stroke (width 0.15) (type solid)) (fill none) (layer "B.Fab"))
    (pad "1" smd roundrect (at -0.485 0 180) (size 0.59 0.64) (layers "B.Cu" "B.Paste" "B.Mask") (roundrect_rratio 0.25)
      (net 692 "Net-(U53-FB)") (pintype "passive"))
    (pad "2" smd roundrect (at 0.485 0 180) (size 0.59 0.64) (layers "B.Cu" "B.Paste" "B.Mask") (roundrect_rratio 0.25)
      (net 1 "GND") (pintype "passive"))
  )

  (footprint "kria-k26-devboard-footprints:C_0402_1005Metric" (layer "B.Cu")
    (at 151.58 115.06 180)
    (descr "Capacitor SMD 0402")
    (tags "capacitor SMD 0402")
    (property "Author" "Antmicro")
    (property "Dielectric" "X5R")
    (property "License" "Apache-2.0")
    (property "MPN" "GRM155R61H104KE14D")
    (property "Manufacturer" "Murata")
    (property "Sheetfile" "debug.kicad_sch")
    (property "Sheetname" "Debug and JTAG")
    (property "Val" "100n")
    (property "Voltage" "50V")
    (property "ki_description" " ")
    (attr smd)
    (fp_text reference "C146" (at -3.74 -0.37) (layer "B.SilkS")
        (effects (font (size 0.7 0.7) (thickness 0.15)) (justify left bottom mirror))
    )
    (fp_text value "C_100n_0402" (at 0 -1.4) (layer "B.Fab") hide
        (effects (font (size 0.7 0.7) (thickness 0.15)) (justify left bottom mirror))
    )
    (fp_text user "${REFERENCE}" (at -0.932 -3.168) (layer "B.Fab") hide
        (effects (font (size 0.7 0.7) (thickness 0.15)) (justify left bottom mirror))
    )
    (fp_text user "Author: Antmicro" (at -0.932 -4.17) (layer "B.Fab") hide
        (effects (font (size 0.7 0.7) (thickness 0.15)) (justify left bottom mirror))
    )
    (fp_text user "License: Apache-2.0" (at -0.932 -5.17) (layer "B.Fab") hide
        (effects (font (size 0.7 0.7) (thickness 0.15)) (justify left bottom mirror))
    )
    (fp_rect (start -0.94 0.47) (end 0.94 -0.47)
      (stroke (width 0.05) (type solid)) (fill none) (layer "B.CrtYd"))
    (fp_rect (start -0.499 0.249) (end 0.499 -0.249)
      (stroke (width 0.15) (type solid)) (fill none) (layer "B.Fab"))
    (pad "1" smd roundrect (at -0.484 0 180) (size 0.59 0.64) (layers "B.Cu" "B.Paste" "B.Mask") (roundrect_rratio 0.25)
      (net 138 "/Debug and JTAG/USB_3V3") (pintype "passive"))
    (pad "2" smd roundrect (at 0.484 0 180) (size 0.59 0.64) (layers "B.Cu" "B.Paste" "B.Mask") (roundrect_rratio 0.25)
      (net 1 "GND") (pintype "passive"))
  )

  (footprint "kria-k26-devboard-footprints:USON-10_2.5x1mm_P0.5mm" (layer "B.Cu")
    (at 174.3 141.9 90)
    (descr "USON-10 2.5x1mm_ Pitch 0.5mm")
    (tags "USON-10 2.5x1mm Pitch 0.5mm")
    (property "Author" "Antmicro")
    (property "License" "Apache-2.0")
    (property "MPN" "TPD4E05U06QDQARQ1")
    (property "Manufacturer" "Texas Instruments")
    (property "Sheetfile" "pmod.kicad_sch")
    (property "Sheetname" "PMOD")
    (property "ki_description" "ESD protection")
    (property "ki_keywords" "SMT, DIODE, IC, TVS, ESD")
    (attr smd)
    (fp_text reference "U14" (at 0.018 1.7 270) (layer "B.SilkS")
        (effects (font (size 0.7 0.7) (thickness 0.15)) (justify left bottom mirror))
    )
    (fp_text value "TPD4E05U06QDQARQ1" (at 0.018 -2.499 270) (layer "B.Fab")
        (effects (font (size 0.7 0.7) (thickness 0.15)) (justify left bottom mirror))
    )
    (fp_text user "${REFERENCE}" (at -0.802 -4.498 270) (layer "B.Fab") hide
        (effects (font (size 0.7 0.7) (thickness 0.15)) (justify left bottom mirror))
    )
    (fp_text user "License: Apache-2.0" (at -0.802 -6.9 270) (layer "B.Fab") hide
        (effects (font (size 0.7 0.7) (thickness 0.15)) (justify left bottom mirror))
    )
    (fp_text user "Author: Antmicro" (at -0.802 -5.7 270) (layer "B.Fab") hide
        (effects (font (size 0.7 0.7) (thickness 0.15)) (justify left bottom mirror))
    )
    (fp_line (start 0.498 -1.398) (end -0.5 -1.398)
      (stroke (width 0.15) (type solid)) (layer "B.SilkS"))
    (fp_line (start 0.498 1.401) (end -0.5 1.401)
      (stroke (width 0.15) (type solid)) (layer "B.SilkS"))
    (fp_circle (center -0.68 1.27) (end -0.63 1.27)
      (stroke (width 0.15) (type solid)) (fill solid) (layer "B.SilkS"))
    (fp_rect (start -0.8 1.5) (end 0.8 -1.499)
      (stroke (width 0.05) (type solid)) (fill none) (layer "B.CrtYd"))
    (fp_line (start -0.5 -1.249) (end 0.498 -1.249)
      (stroke (width 0.15) (type solid)) (layer "B.Fab"))
    (fp_line (start -0.5 1) (end -0.5 -1.249)
      (stroke (width 0.15) (type solid)) (layer "B.Fab"))
    (fp_line (start -0.25 1.25) (end -0.5 1)
      (stroke (width 0.15) (type solid)) (layer "B.Fab"))
    (fp_line (start 0.498 1.25) (end -0.25 1.25)
      (stroke (width 0.15) (type solid)) (layer "B.Fab"))
    (fp_line (start 0.498 1.25) (end 0.498 -1.249)
      (stroke (width 0.15) (type solid)) (layer "B.Fab"))
    (pad "1" smd roundrect (at -0.387 1 180) (size 0.25 0.55) (layers "B.Cu" "B.Paste" "B.Mask") (roundrect_rratio 0.25)
      (net 144 "/PMOD/HDA11") (pintype "passive"))
    (pad "2" smd roundrect (at -0.387 0.5 180) (size 0.25 0.55) (layers "B.Cu" "B.Paste" "B.Mask") (roundrect_rratio 0.25)
      (net 155 "/PMOD/HDA12") (pintype "passive"))
    (pad "3" smd roundrect (at -0.387 0 180) (size 0.4 0.55) (layers "B.Cu" "B.Paste" "B.Mask") (roundrect_rratio 0.25)
      (net 1 "GND") (pintype "power_in"))
    (pad "4" smd roundrect (at -0.387 -0.498 180) (size 0.25 0.55) (layers "B.Cu" "B.Paste" "B.Mask") (roundrect_rratio 0.25)
      (net 156 "/PMOD/HDA13") (pintype "passive"))
    (pad "5" smd roundrect (at -0.387 -0.998 180) (size 0.25 0.55) (layers "B.Cu" "B.Paste" "B.Mask") (roundrect_rratio 0.25)
      (net 157 "/PMOD/HDA14") (pintype "passive"))
    (pad "6" smd roundrect (at 0.385 -0.998 180) (size 0.25 0.55) (layers "B.Cu" "B.Paste" "B.Mask") (roundrect_rratio 0.25)
      (net 157 "/PMOD/HDA14") (pintype "passive"))
    (pad "7" smd roundrect (at 0.385 -0.498 180) (size 0.25 0.55) (layers "B.Cu" "B.Paste" "B.Mask") (roundrect_rratio 0.25)
      (net 156 "/PMOD/HDA13") (pintype "passive"))
    (pad "8" smd roundrect (at 0.385 0 180) (size 0.4 0.55) (layers "B.Cu" "B.Paste" "B.Mask") (roundrect_rratio 0.25)
      (net 1 "GND") (pintype "passive"))
    (pad "9" smd roundrect (at 0.385 0.5 180) (size 0.25 0.55) (layers "B.Cu" "B.Paste" "B.Mask") (roundrect_rratio 0.25)
      (net 155 "/PMOD/HDA12") (pintype "passive"))
    (pad "10" smd roundrect (at 0.385 1 180) (size 0.25 0.55) (layers "B.Cu" "B.Paste" "B.Mask") (roundrect_rratio 0.25)
      (net 144 "/PMOD/HDA11") (pintype "passive"))
  )

  (footprint "kria-k26-devboard-footprints:C_0402_1005Metric" (layer "B.Cu")
    (at 110.675 75.133 90)
    (descr "Capacitor SMD 0402")
    (tags "capacitor SMD 0402")
    (property "Author" "Antmicro")
    (property "Dielectric" "X5R")
    (property "License" "Apache-2.0")
    (property "MPN" "GRM155R61H104KE14D")
    (property "Manufacturer" "Murata")
    (property "Sheetfile" "usb.kicad_sch")
    (property "Sheetname" "USB")
    (property "Val" "100n")
    (property "Voltage" "50V")
    (property "ki_description" " ")
    (attr smd)
    (fp_text reference "C78" (at -0.812 0.34 270) (layer "B.SilkS")
        (effects (font (size 0.7 0.7) (thickness 0.15)) (justify left bottom mirror))
    )
    (fp_text value "C_100n_0402" (at 0 -1.4 270) (layer "B.Fab") hide
        (effects (font (size 0.7 0.7) (thickness 0.15)) (justify left bottom mirror))
    )
    (fp_text user "Author: Antmicro" (at -0.932 -4.17 270) (layer "B.Fab") hide
        (effects (font (size 0.7 0.7) (thickness 0.15)) (justify left bottom mirror))
    )
    (fp_text user "License: Apache-2.0" (at -0.932 -5.17 270) (layer "B.Fab") hide
        (effects (font (size 0.7 0.7) (thickness 0.15)) (justify left bottom mirror))
    )
    (fp_text user "${REFERENCE}" (at -0.932 -3.168 270) (layer "B.Fab") hide
        (effects (font (size 0.7 0.7) (thickness 0.15)) (justify left bottom mirror))
    )
    (fp_rect (start -0.94 0.47) (end 0.94 -0.47)
      (stroke (width 0.05) (type solid)) (fill none) (layer "B.CrtYd"))
    (fp_rect (start -0.499 0.249) (end 0.499 -0.249)
      (stroke (width 0.15) (type solid)) (fill none) (layer "B.Fab"))
    (pad "1" smd roundrect (at -0.484 0 90) (size 0.59 0.64) (layers "B.Cu" "B.Paste" "B.Mask") (roundrect_rratio 0.25)
      (net 65 "/USB/USB3_TX_N") (pintype "passive"))
    (pad "2" smd roundrect (at 0.484 0 90) (size 0.59 0.64) (layers "B.Cu" "B.Paste" "B.Mask") (roundrect_rratio 0.25)
      (net 282 "/USB/USB3_TX_C_N") (pintype "passive"))
  )

  (footprint "kria-k26-devboard-footprints:C_0402_1005Metric" (layer "B.Cu")
    (at 111.62 75.138 90)
    (descr "Capacitor SMD 0402")
    (tags "capacitor SMD 0402")
    (property "Author" "Antmicro")
    (property "Dielectric" "X5R")
    (property "License" "Apache-2.0")
    (property "MPN" "GRM155R61H104KE14D")
    (property "Manufacturer" "Murata")
    (property "Sheetfile" "usb.kicad_sch")
    (property "Sheetname" "USB")
    (property "Val" "100n")
    (property "Voltage" "50V")
    (property "ki_description" " ")
    (attr smd)
    (fp_text reference "C79" (at -0.812 0.34 270) (layer "B.SilkS")
        (effects (font (size 0.7 0.7) (thickness 0.15)) (justify left bottom mirror))
    )
    (fp_text value "C_100n_0402" (at 0 -1.4 270) (layer "B.Fab") hide
        (effects (font (size 0.7 0.7) (thickness 0.15)) (justify left bottom mirror))
    )
    (fp_text user "License: Apache-2.0" (at -0.932 -5.17 270) (layer "B.Fab") hide
        (effects (font (size 0.7 0.7) (thickness 0.15)) (justify left bottom mirror))
    )
    (fp_text user "Author: Antmicro" (at -0.932 -4.17 270) (layer "B.Fab") hide
        (effects (font (size 0.7 0.7) (thickness 0.15)) (justify left bottom mirror))
    )
    (fp_text user "${REFERENCE}" (at -0.932 -3.168 270) (layer "B.Fab") hide
        (effects (font (size 0.7 0.7) (thickness 0.15)) (justify left bottom mirror))
    )
    (fp_rect (start -0.94 0.47) (end 0.94 -0.47)
      (stroke (width 0.05) (type solid)) (fill none) (layer "B.CrtYd"))
    (fp_rect (start -0.499 0.249) (end 0.499 -0.249)
      (stroke (width 0.15) (type solid)) (fill none) (layer "B.Fab"))
    (pad "1" smd roundrect (at -0.484 0 90) (size 0.59 0.64) (layers "B.Cu" "B.Paste" "B.Mask") (roundrect_rratio 0.25)
      (net 66 "/USB/USB3_TX_P") (pintype "passive"))
    (pad "2" smd roundrect (at 0.484 0 90) (size 0.59 0.64) (layers "B.Cu" "B.Paste" "B.Mask") (roundrect_rratio 0.25)
      (net 283 "/USB/USB3_TX_C_P") (pintype "passive"))
  )

  (footprint "kria-k26-devboard-footprints:USON-10_2.5x1mm_P0.5mm" (layer "B.Cu")
    (at 129.75 73.25 -90)
    (descr "USON-10 2.5x1mm_ Pitch 0.5mm")
    (tags "USON-10 2.5x1mm Pitch 0.5mm")
    (property "Author" "Antmicro")
    (property "License" "Apache-2.0")
    (property "MPN" "TPD4E05U06QDQARQ1")
    (property "Manufacturer" "Texas Instruments")
    (property "Sheetfile" "usb.kicad_sch")
    (property "Sheetname" "USB")
    (property "ki_description" "ESD protection")
    (property "ki_keywords" "SMT, DIODE, IC, TVS, ESD")
    (attr smd)
    (fp_text reference "U22" (at 0.018 1.7 90) (layer "B.SilkS")
        (effects (font (size 0.7 0.7) (thickness 0.15)) (justify left bottom mirror))
    )
    (fp_text value "TPD4E05U06QDQARQ1" (at 0.018 -2.499 90) (layer "B.Fab")
        (effects (font (size 0.7 0.7) (thickness 0.15)) (justify left bottom mirror))
    )
    (fp_text user "License: Apache-2.0" (at -0.802 -6.9 90) (layer "B.Fab") hide
        (effects (font (size 0.7 0.7) (thickness 0.15)) (justify left bottom mirror))
    )
    (fp_text user "${REFERENCE}" (at -0.802 -4.498 90) (layer "B.Fab") hide
        (effects (font (size 0.7 0.7) (thickness 0.15)) (justify left bottom mirror))
    )
    (fp_text user "Author: Antmicro" (at -0.802 -5.7 90) (layer "B.Fab") hide
        (effects (font (size 0.7 0.7) (thickness 0.15)) (justify left bottom mirror))
    )
    (fp_line (start 0.498 -1.398) (end -0.5 -1.398)
      (stroke (width 0.15) (type solid)) (layer "B.SilkS"))
    (fp_line (start 0.498 1.401) (end -0.5 1.401)
      (stroke (width 0.15) (type solid)) (layer "B.SilkS"))
    (fp_circle (center -0.68 1.27) (end -0.63 1.27)
      (stroke (width 0.15) (type solid)) (fill solid) (layer "B.SilkS"))
    (fp_rect (start -0.8 1.5) (end 0.8 -1.499)
      (stroke (width 0.05) (type solid)) (fill none) (layer "B.CrtYd"))
    (fp_line (start -0.5 -1.249) (end 0.498 -1.249)
      (stroke (width 0.15) (type solid)) (layer "B.Fab"))
    (fp_line (start -0.5 1) (end -0.5 -1.249)
      (stroke (width 0.15) (type solid)) (layer "B.Fab"))
    (fp_line (start -0.25 1.25) (end -0.5 1)
      (stroke (width 0.15) (type solid)) (layer "B.Fab"))
    (fp_line (start 0.498 1.25) (end -0.25 1.25)
      (stroke (width 0.15) (type solid)) (layer "B.Fab"))
    (fp_line (start 0.498 1.25) (end 0.498 -1.249)
      (stroke (width 0.15) (type solid)) (layer "B.Fab"))
    (pad "1" smd roundrect (at -0.387 1) (size 0.25 0.55) (layers "B.Cu" "B.Paste" "B.Mask") (roundrect_rratio 0.25)
      (net 83 "/USB/USB1_RX_N") (pintype "passive"))
    (pad "2" smd roundrect (at -0.387 0.5) (size 0.25 0.55) (layers "B.Cu" "B.Paste" "B.Mask") (roundrect_rratio 0.25)
      (net 84 "/USB/USB1_RX_P") (pintype "passive"))
    (pad "3" smd roundrect (at -0.387 0) (size 0.4 0.55) (layers "B.Cu" "B.Paste" "B.Mask") (roundrect_rratio 0.25)
      (net 1 "GND") (pintype "power_in"))
    (pad "4" smd roundrect (at -0.387 -0.498) (size 0.25 0.55) (layers "B.Cu" "B.Paste" "B.Mask") (roundrect_rratio 0.25)
      (net 278 "/USB/USB1_TX_C_N") (pintype "passive"))
    (pad "5" smd roundrect (at -0.387 -0.998) (size 0.25 0.55) (layers "B.Cu" "B.Paste" "B.Mask") (roundrect_rratio 0.25)
      (net 279 "/USB/USB1_TX_C_P") (pintype "passive"))
    (pad "6" smd roundrect (at 0.385 -0.998) (size 0.25 0.55) (layers "B.Cu" "B.Paste" "B.Mask") (roundrect_rratio 0.25)
      (net 279 "/USB/USB1_TX_C_P") (pintype "passive"))
    (pad "7" smd roundrect (at 0.385 -0.498) (size 0.25 0.55) (layers "B.Cu" "B.Paste" "B.Mask") (roundrect_rratio 0.25)
      (net 278 "/USB/USB1_TX_C_N") (pintype "passive"))
    (pad "8" smd roundrect (at 0.385 0) (size 0.4 0.55) (layers "B.Cu" "B.Paste" "B.Mask") (roundrect_rratio 0.25)
      (net 1 "GND") (pintype "passive"))
    (pad "9" smd roundrect (at 0.385 0.5) (size 0.25 0.55) (layers "B.Cu" "B.Paste" "B.Mask") (roundrect_rratio 0.25)
      (net 84 "/USB/USB1_RX_P") (pintype "passive"))
    (pad "10" smd roundrect (at 0.385 1) (size 0.25 0.55) (layers "B.Cu" "B.Paste" "B.Mask") (roundrect_rratio 0.25)
      (net 83 "/USB/USB1_RX_N") (pintype "passive"))
  )

  (footprint "kria-k26-devboard-footprints:USON-10_2.5x1mm_P0.5mm" (layer "B.Cu")
    (at 110.4 73.3 -90)
    (descr "USON-10 2.5x1mm_ Pitch 0.5mm")
    (tags "USON-10 2.5x1mm Pitch 0.5mm")
    (property "Author" "Antmicro")
    (property "License" "Apache-2.0")
    (property "MPN" "TPD4E05U06QDQARQ1")
    (property "Manufacturer" "Texas Instruments")
    (property "Sheetfile" "usb.kicad_sch")
    (property "Sheetname" "USB")
    (property "ki_description" "ESD protection")
    (property "ki_keywords" "SMT, DIODE, IC, TVS, ESD")
    (attr smd)
    (fp_text reference "U28" (at 0.018 1.7 90) (layer "B.SilkS")
        (effects (font (size 0.7 0.7) (thickness 0.15)) (justify left bottom mirror))
    )
    (fp_text value "TPD4E05U06QDQARQ1" (at 0.018 -2.499 90) (layer "B.Fab")
        (effects (font (size 0.7 0.7) (thickness 0.15)) (justify left bottom mirror))
    )
    (fp_text user "${REFERENCE}" (at -0.802 -4.498 90) (layer "B.Fab") hide
        (effects (font (size 0.7 0.7) (thickness 0.15)) (justify left bottom mirror))
    )
    (fp_text user "License: Apache-2.0" (at -0.802 -6.9 90) (layer "B.Fab") hide
        (effects (font (size 0.7 0.7) (thickness 0.15)) (justify left bottom mirror))
    )
    (fp_text user "Author: Antmicro" (at -0.802 -5.7 90) (layer "B.Fab") hide
        (effects (font (size 0.7 0.7) (thickness 0.15)) (justify left bottom mirror))
    )
    (fp_line (start 0.498 -1.398) (end -0.5 -1.398)
      (stroke (width 0.15) (type solid)) (layer "B.SilkS"))
    (fp_line (start 0.498 1.401) (end -0.5 1.401)
      (stroke (width 0.15) (type solid)) (layer "B.SilkS"))
    (fp_circle (center -0.68 1.27) (end -0.63 1.27)
      (stroke (width 0.15) (type solid)) (fill solid) (layer "B.SilkS"))
    (fp_rect (start -0.8 1.5) (end 0.8 -1.499)
      (stroke (width 0.05) (type solid)) (fill none) (layer "B.CrtYd"))
    (fp_line (start -0.5 -1.249) (end 0.498 -1.249)
      (stroke (width 0.15) (type solid)) (layer "B.Fab"))
    (fp_line (start -0.5 1) (end -0.5 -1.249)
      (stroke (width 0.15) (type solid)) (layer "B.Fab"))
    (fp_line (start -0.25 1.25) (end -0.5 1)
      (stroke (width 0.15) (type solid)) (layer "B.Fab"))
    (fp_line (start 0.498 1.25) (end -0.25 1.25)
      (stroke (width 0.15) (type solid)) (layer "B.Fab"))
    (fp_line (start 0.498 1.25) (end 0.498 -1.249)
      (stroke (width 0.15) (type solid)) (layer "B.Fab"))
    (pad "1" smd roundrect (at -0.387 1) (size 0.25 0.55) (layers "B.Cu" "B.Paste" "B.Mask") (roundrect_rratio 0.25)
      (net 79 "/USB/USB3_RX_N") (pintype "passive"))
    (pad "2" smd roundrect (at -0.387 0.5) (size 0.25 0.55) (layers "B.Cu" "B.Paste" "B.Mask") (roundrect_rratio 0.25)
      (net 80 "/USB/USB3_RX_P") (pintype "passive"))
    (pad "3" smd roundrect (at -0.387 0) (size 0.4 0.55) (layers "B.Cu" "B.Paste" "B.Mask") (roundrect_rratio 0.25)
      (net 1 "GND") (pintype "power_in"))
    (pad "4" smd roundrect (at -0.387 -0.498) (size 0.25 0.55) (layers "B.Cu" "B.Paste" "B.Mask") (roundrect_rratio 0.25)
      (net 282 "/USB/USB3_TX_C_N") (pintype "passive"))
    (pad "5" smd roundrect (at -0.387 -0.998) (size 0.25 0.55) (layers "B.Cu" "B.Paste" "B.Mask") (roundrect_rratio 0.25)
      (net 283 "/USB/USB3_TX_C_P") (pintype "passive"))
    (pad "6" smd roundrect (at 0.385 -0.998) (size 0.25 0.55) (layers "B.Cu" "B.Paste" "B.Mask") (roundrect_rratio 0.25)
      (net 283 "/USB/USB3_TX_C_P") (pintype "passive"))
    (pad "7" smd roundrect (at 0.385 -0.498) (size 0.25 0.55) (layers "B.Cu" "B.Paste" "B.Mask") (roundrect_rratio 0.25)
      (net 282 "/USB/USB3_TX_C_N") (pintype "passive"))
    (pad "8" smd roundrect (at 0.385 0) (size 0.4 0.55) (layers "B.Cu" "B.Paste" "B.Mask") (roundrect_rratio 0.25)
      (net 1 "GND") (pintype "passive"))
    (pad "9" smd roundrect (at 0.385 0.5) (size 0.25 0.55) (layers "B.Cu" "B.Paste" "B.Mask") (roundrect_rratio 0.25)
      (net 80 "/USB/USB3_RX_P") (pintype "passive"))
    (pad "10" smd roundrect (at 0.385 1) (size 0.25 0.55) (layers "B.Cu" "B.Paste" "B.Mask") (roundrect_rratio 0.25)
      (net 79 "/USB/USB3_RX_N") (pintype "passive"))
  )

  (footprint "kria-k26-devboard-footprints:C_0603_1608Metric" (layer "B.Cu")
    (at 152 107.15)
    (descr "Capacitor SMD 0603")
    (tags "capacitor 0603")
    (property "Author" "Antmicro")
    (property "Dielectric" "")
    (property "License" "Apache-2.0")
    (property "MPN" "CL10A105KA8NNNC")
    (property "Manufacturer" "Samsung")
    (property "Sheetfile" "debug.kicad_sch")
    (property "Sheetname" "Debug and JTAG")
    (property "Val" "1u/25V")
    (property "Voltage" "")
    (property "ki_description" " ")
    (attr smd)
    (fp_text reference "C158" (at 4.03 0.35 180) (layer "B.SilkS")
        (effects (font (size 0.7 0.7) (thickness 0.15)) (justify left bottom mirror))
    )
    (fp_text value "C_1u_25V_0603" (at 0 -1.6 180) (layer "B.Fab") hide
        (effects (font (size 0.7 0.7) (thickness 0.15)) (justify left bottom mirror))
    )
    (fp_text user "${REFERENCE}" (at -1.682 -3.895 180) (layer "B.Fab") hide
        (effects (font (size 0.7 0.7) (thickness 0.15)) (justify left bottom mirror))
    )
    (fp_text user "Author: Antmicro" (at -1.682 -4.894 180) (layer "B.Fab") hide
        (effects (font (size 0.7 0.7) (thickness 0.15)) (justify left bottom mirror))
    )
    (fp_text user "License: Apache-2.0" (at -1.682 -5.895 180) (layer "B.Fab") hide
        (effects (font (size 0.7 0.7) (thickness 0.15)) (justify left bottom mirror))
    )
    (fp_line (start -0.3 -0.3) (end 0.3 -0.3)
      (stroke (width 0.15) (type solid)) (layer "B.SilkS"))
    (fp_line (start -0.3 0.3) (end 0.3 0.3)
      (stroke (width 0.15) (type solid)) (layer "B.SilkS"))
    (fp_rect (start -1.24 0.7) (end 1.24 -0.7)
      (stroke (width 0.05) (type solid)) (fill none) (layer "B.CrtYd"))
    (fp_rect (start -0.8 0.4) (end 0.8 -0.4)
      (stroke (width 0.15) (type solid)) (fill none) (layer "B.Fab"))
    (pad "1" smd roundrect (at -0.7 0) (size 0.6 0.8) (layers "B.Cu" "B.Paste" "B.Mask") (roundrect_rratio 0.2)
      (net 313 "/Debug and JTAG/USB_VBUS") (pintype "passive"))
    (pad "2" smd roundrect (at 0.7 0) (size 0.6 0.8) (layers "B.Cu" "B.Paste" "B.Mask") (roundrect_rratio 0.2)
      (net 1 "GND") (pintype "passive"))
  )

  (footprint "kria-k26-devboard-footprints:C_0603_1608Metric" (layer "B.Cu")
    (at 152 110.25)
    (descr "Capacitor SMD 0603")
    (tags "capacitor 0603")
    (property "Author" "Antmicro")
    (property "Dielectric" "")
    (property "License" "Apache-2.0")
    (property "MPN" "CL10A105KA8NNNC")
    (property "Manufacturer" "Samsung")
    (property "Sheetfile" "debug.kicad_sch")
    (property "Sheetname" "Debug and JTAG")
    (property "Val" "1u/25V")
    (property "Voltage" "")
    (property "ki_description" " ")
    (attr smd)
    (fp_text reference "C155" (at 4 0.43 180) (layer "B.SilkS")
        (effects (font (size 0.7 0.7) (thickness 0.15)) (justify left bottom mirror))
    )
    (fp_text value "C_1u_25V_0603" (at 0 -1.6 180) (layer "B.Fab") hide
        (effects (font (size 0.7 0.7) (thickness 0.15)) (justify left bottom mirror))
    )
    (fp_text user "Author: Antmicro" (at -1.682 -4.894 180) (layer "B.Fab") hide
        (effects (font (size 0.7 0.7) (thickness 0.15)) (justify left bottom mirror))
    )
    (fp_text user "${REFERENCE}" (at -1.682 -3.895 180) (layer "B.Fab") hide
        (effects (font (size 0.7 0.7) (thickness 0.15)) (justify left bottom mirror))
    )
    (fp_text user "License: Apache-2.0" (at -1.682 -5.895 180) (layer "B.Fab") hide
        (effects (font (size 0.7 0.7) (thickness 0.15)) (justify left bottom mirror))
    )
    (fp_line (start -0.3 -0.3) (end 0.3 -0.3)
      (stroke (width 0.15) (type solid)) (layer "B.SilkS"))
    (fp_line (start -0.3 0.3) (end 0.3 0.3)
      (stroke (width 0.15) (type solid)) (layer "B.SilkS"))
    (fp_rect (start -1.24 0.7) (end 1.24 -0.7)
      (stroke (width 0.05) (type solid)) (fill none) (layer "B.CrtYd"))
    (fp_rect (start -0.8 0.4) (end 0.8 -0.4)
      (stroke (width 0.15) (type solid)) (fill none) (layer "B.Fab"))
    (pad "1" smd roundrect (at -0.7 0) (size 0.6 0.8) (layers "B.Cu" "B.Paste" "B.Mask") (roundrect_rratio 0.2)
      (net 313 "/Debug and JTAG/USB_VBUS") (pintype "passive"))
    (pad "2" smd roundrect (at 0.7 0) (size 0.6 0.8) (layers "B.Cu" "B.Paste" "B.Mask") (roundrect_rratio 0.2)
      (net 1 "GND") (pintype "passive"))
  )

  (footprint "kria-k26-devboard-footprints:C_0402_1005Metric" (layer "B.Cu")
    (at 151.85 111.75)
    (descr "Capacitor SMD 0402")
    (tags "capacitor SMD 0402")
    (property "Author" "Antmicro")
    (property "Dielectric" "")
    (property "License" "Apache-2.0")
    (property "MPN" "C1005X6S1A105K050BC")
    (property "Manufacturer" "TDK")
    (property "Sheetfile" "debug.kicad_sch")
    (property "Sheetname" "Debug and JTAG")
    (property "Val" "1u")
    (property "Voltage" "")
    (property "ki_description" " ")
    (attr smd)
    (fp_text reference "C159" (at 3.832 0.35 180) (layer "B.SilkS")
        (effects (font (size 0.7 0.7) (thickness 0.15)) (justify left bottom mirror))
    )
    (fp_text value "C_1u_0402" (at 0 -1.4 180) (layer "B.Fab") hide
        (effects (font (size 0.7 0.7) (thickness 0.15)) (justify left bottom mirror))
    )
    (fp_text user "${REFERENCE}" (at -0.932 -3.168 180) (layer "B.Fab") hide
        (effects (font (size 0.7 0.7) (thickness 0.15)) (justify left bottom mirror))
    )
    (fp_text user "Author: Antmicro" (at -0.932 -4.17 180) (layer "B.Fab") hide
        (effects (font (size 0.7 0.7) (thickness 0.15)) (justify left bottom mirror))
    )
    (fp_text user "License: Apache-2.0" (at -0.932 -5.17 180) (layer "B.Fab") hide
        (effects (font (size 0.7 0.7) (thickness 0.15)) (justify left bottom mirror))
    )
    (fp_rect (start -0.94 0.47) (end 0.94 -0.47)
      (stroke (width 0.05) (type solid)) (fill none) (layer "B.CrtYd"))
    (fp_rect (start -0.499 0.249) (end 0.499 -0.249)
      (stroke (width 0.15) (type solid)) (fill none) (layer "B.Fab"))
    (pad "1" smd roundrect (at -0.484 0) (size 0.59 0.64) (layers "B.Cu" "B.Paste" "B.Mask") (roundrect_rratio 0.25)
      (net 138 "/Debug and JTAG/USB_3V3") (pintype "passive"))
    (pad "2" smd roundrect (at 0.484 0) (size 0.59 0.64) (layers "B.Cu" "B.Paste" "B.Mask") (roundrect_rratio 0.25)
      (net 1 "GND") (pintype "passive"))
  )

  (footprint "kria-k26-devboard-footprints:L_0805_2012Metric" (layer "B.Cu")
    (at 138.4046 83.7946 180)
    (descr "Inductor  SMD 0805")
    (tags "inductor SMD 0805")
    (property "Author" "Antmicro")
    (property "IMax" "")
    (property "ISat" "")
    (property "License" "Apache-2.0")
    (property "MPN" "TFM201208ALD-1R0MTCA")
    (property "Manufacturer" "TDK")
    (property "Sheetfile" "dc-dc-conventers.kicad_sch")
    (property "Sheetname" "DC/DC conventers")
    (property "Size" "1.25x0.8")
    (property "Val" "1u/2.5A")
    (attr smd)
    (fp_text reference "L4" (at -1.0354 -1.7954) (layer "B.SilkS")
        (effects (font (size 0.7 0.7) (thickness 0.15)) (justify left bottom mirror))
    )
    (fp_text value "L_1u_2.5A_0805" (at 0 -1.947) (layer "B.Fab") hide
        (effects (font (size 0.7 0.7) (thickness 0.15)) (justify left bottom mirror))
    )
    (fp_text user "Author: Antmicro" (at -1.9 -5.947) (layer "B.Fab") hide
        (effects (font (size 0.7 0.7) (thickness 0.15)) (justify left bottom mirror))
    )
    (fp_text user "${REFERENCE}" (at -1.9 -3.947) (layer "B.Fab") hide
        (effects (font (size 0.7 0.7) (thickness 0.15)) (justify left bottom mirror))
    )
    (fp_text user "License: Apache-2.0" (at -1.9 -4.947) (layer "B.Fab") hide
        (effects (font (size 0.7 0.7) (thickness 0.15)) (justify left bottom mirror))
    )
    (fp_line (start -0.3 -0.8) (end 0.3 -0.8)
      (stroke (width 0.15) (type solid)) (layer "B.SilkS"))
    (fp_line (start -0.3 0.8) (end 0.3 0.8)
      (stroke (width 0.15) (type solid)) (layer "B.SilkS"))
    (fp_rect (start -1.9 0.93) (end 1.9 -0.93)
      (stroke (width 0.05) (type solid)) (fill none) (layer "B.CrtYd"))
    (fp_rect (start -0.95 0.675) (end 0.95 -0.675)
      (stroke (width 0.15) (type solid)) (fill none) (layer "B.Fab"))
    (pad "1" smd rect (at -1.05 0 180) (size 1.2 1.2) (layers "B.Cu" "B.Paste" "B.Mask")
      (net 310 "/Power Supply/DC/DC conventers/SW_PS_2V5") (pintype "passive"))
    (pad "2" smd rect (at 1.05 0 180) (size 1.2 1.2) (layers "B.Cu" "B.Paste" "B.Mask")
      (net 766 "/Power Supply/DC/DC conventers/PS_2V5_OUT") (pintype "passive"))
  )

  (footprint "kria-k26-devboard-footprints:L_0805_2012Metric" (layer "B.Cu")
    (at 136.54 94.81 -90)
    (descr "Inductor  SMD 0805")
    (tags "inductor SMD 0805")
    (property "Author" "Antmicro")
    (property "IMax" "")
    (property "ISat" "")
    (property "License" "Apache-2.0")
    (property "MPN" "TFM201208ALD-1R0MTCA")
    (property "Manufacturer" "TDK")
    (property "Sheetfile" "dc-dc-conventers.kicad_sch")
    (property "Sheetname" "DC/DC conventers")
    (property "Size" "1.25x0.8")
    (property "Val" "1u/2.5A")
    (attr smd)
    (fp_text reference "L7" (at 1.845 -0.436 90) (layer "B.SilkS")
        (effects (font (size 0.7 0.7) (thickness 0.15)) (justify left bottom mirror))
    )
    (fp_text value "L_1u_2.5A_0805" (at 0 -1.947 90) (layer "B.Fab") hide
        (effects (font (size 0.7 0.7) (thickness 0.15)) (justify left bottom mirror))
    )
    (fp_text user "License: Apache-2.0" (at -1.9 -4.947 90) (layer "B.Fab") hide
        (effects (font (size 0.7 0.7) (thickness 0.15)) (justify left bottom mirror))
    )
    (fp_text user "Author: Antmicro" (at -1.9 -5.947 90) (layer "B.Fab") hide
        (effects (font (size 0.7 0.7) (thickness 0.15)) (justify left bottom mirror))
    )
    (fp_text user "${REFERENCE}" (at -1.9 -3.947 90) (layer "B.Fab") hide
        (effects (font (size 0.7 0.7) (thickness 0.15)) (justify left bottom mirror))
    )
    (fp_line (start -0.3 -0.8) (end 0.3 -0.8)
      (stroke (width 0.15) (type solid)) (layer "B.SilkS"))
    (fp_line (start -0.3 0.8) (end 0.3 0.8)
      (stroke (width 0.15) (type solid)) (layer "B.SilkS"))
    (fp_rect (start -1.9 0.93) (end 1.9 -0.93)
      (stroke (width 0.05) (type solid)) (fill none) (layer "B.CrtYd"))
    (fp_rect (start -0.95 0.675) (end 0.95 -0.675)
      (stroke (width 0.15) (type solid)) (fill none) (layer "B.Fab"))
    (pad "1" smd rect (at -1.05 0 270) (size 1.2 1.2) (layers "B.Cu" "B.Paste" "B.Mask")
      (net 256 "/Power Supply/DC/DC conventers/SW_PS_1V0") (pintype "passive"))
    (pad "2" smd rect (at 1.05 0 270) (size 1.2 1.2) (layers "B.Cu" "B.Paste" "B.Mask")
      (net 769 "/Power Supply/DC/DC conventers/PS_1V0_OUT") (pintype "passive"))
  )

  (footprint "kria-k26-devboard-footprints:SOT-416" (layer "B.Cu")
    (at 138.756 95.849 180)
    (descr "SOT-416")
    (tags "SOT-416")
    (property "Author" "Antmicro")
    (property "License" "Apache-2.0")
    (property "MPN" "DTC014TEBTL")
    (property "Manufacturer" "ROHM Semiconductor")
    (property "Sheetfile" "dc-dc-conventers.kicad_sch")
    (property "Sheetname" "DC/DC conventers")
    (property "ki_description" "Digital NPN Transistor, 10k/NONE, EMT-3")
    (attr smd)
    (fp_text reference "Q14" (at -1.244 -4.761) (layer "B.SilkS")
        (effects (font (size 0.7 0.7) (thickness 0.15)) (justify left bottom mirror))
    )
    (fp_text value "DTC014T_SOT-416" (at 0 -2) (layer "B.Fab") hide
        (effects (font (size 0.7 0.7) (thickness 0.15)) (justify left bottom mirror))
    )
    (fp_text user "License: Apache-2.0" (at -1 -5.802) (layer "B.Fab") hide
        (effects (font (size 0.7 0.7) (thickness 0.15)) (justify left bottom mirror))
    )
    (fp_text user "Author: Antmicro" (at -1 -4.602) (layer "B.Fab") hide
        (effects (font (size 0.7 0.7) (thickness 0.15)) (justify left bottom mirror))
    )
    (fp_text user "${REFERENCE}" (at -1 -3.4) (layer "B.Fab") hide
        (effects (font (size 0.7 0.7) (thickness 0.15)) (justify left bottom mirror))
    )
    (fp_line (start -0.5 0.15) (end -0.5 -0.15)
      (stroke (width 0.15) (type solid)) (layer "B.SilkS"))
    (fp_line (start 0.5 -0.9) (end -0.5 -0.9)
      (stroke (width 0.15) (type solid)) (layer "B.SilkS"))
    (fp_line (start 0.5 -0.9) (end 0.5 -0.7)
      (stroke (width 0.15) (type solid)) (layer "B.SilkS"))
    (fp_line (start 0.508 0.9) (end -0.5 0.9)
      (stroke (width 0.15) (type solid)) (layer "B.SilkS"))
    (fp_line (start 0.508 0.9) (end 0.508 0.592)
      (stroke (width 0.15) (type solid)) (layer "B.SilkS"))
    (fp_rect (start -1 1.05) (end 1 -1.05)
      (stroke (width 0.05) (type solid)) (fill none) (layer "B.CrtYd"))
    (fp_line (start -0.05 0.9) (end -0.45 0.5)
      (stroke (width 0.15) (type solid)) (layer "B.Fab"))
    (fp_rect (start 0.45 -0.9) (end -0.45 0.9)
      (stroke (width 0.15) (type solid)) (fill none) (layer "B.Fab"))
    (pad "1" smd rect (at -0.652 0.5 180) (size 0.6 0.5) (layers "B.Cu" "B.Paste" "B.Mask")
      (net 769 "/Power Supply/DC/DC conventers/PS_1V0_OUT") (pinfunction "B") (pintype "input"))
    (pad "2" smd rect (at -0.652 -0.498 180) (size 0.6 0.5) (layers "B.Cu" "B.Paste" "B.Mask")
      (net 1 "GND") (pinfunction "E") (pintype "passive"))
    (pad "3" smd rect (at 0.65 0 180) (size 0.6 0.5) (layers "B.Cu" "B.Paste" "B.Mask")
      (net 339 "Net-(Q14-C)") (pinfunction "C") (pintype "passive"))
  )

  (footprint "kria-k26-devboard-footprints:C_0402_1005Metric" (layer "B.Cu")
    (at 108.95 87.55)
    (descr "Capacitor SMD 0402")
    (tags "capacitor SMD 0402")
    (property "Author" "Antmicro")
    (property "Dielectric" "X5R")
    (property "License" "Apache-2.0")
    (property "MPN" "GRM155R61H104KE14D")
    (property "Manufacturer" "Murata")
    (property "Sheetfile" "k26_som.kicad_sch")
    (property "Sheetname" "Xilinx K26 SOM")
    (property "Val" "100n")
    (property "Voltage" "50V")
    (property "ki_description" " ")
    (attr smd)
    (fp_text reference "C250" (at 3.68 1.56 180) (layer "B.SilkS")
        (effects (font (size 0.7 0.7) (thickness 0.15)) (justify left bottom mirror))
    )
    (fp_text value "C_100n_0402" (at 0 -1.4 180) (layer "B.Fab") hide
        (effects (font (size 0.7 0.7) (thickness 0.15)) (justify left bottom mirror))
    )
    (fp_text user "License: Apache-2.0" (at -0.932 -5.17 180) (layer "B.Fab") hide
        (effects (font (size 0.7 0.7) (thickness 0.15)) (justify left bottom mirror))
    )
    (fp_text user "Author: Antmicro" (at -0.932 -4.17 180) (layer "B.Fab") hide
        (effects (font (size 0.7 0.7) (thickness 0.15)) (justify left bottom mirror))
    )
    (fp_text user "${REFERENCE}" (at -0.932 -3.168 180) (layer "B.Fab") hide
        (effects (font (size 0.7 0.7) (thickness 0.15)) (justify left bottom mirror))
    )
    (fp_rect (start -0.94 0.47) (end 0.94 -0.47)
      (stroke (width 0.05) (type solid)) (fill none) (layer "B.CrtYd"))
    (fp_rect (start -0.499 0.249) (end 0.499 -0.249)
      (stroke (width 0.15) (type solid)) (fill none) (layer "B.Fab"))
    (pad "1" smd roundrect (at -0.484 0) (size 0.59 0.64) (layers "B.Cu" "B.Paste" "B.Mask") (roundrect_rratio 0.25)
      (net 243 "Net-(Q6-D)") (pintype "passive"))
    (pad "2" smd roundrect (at 0.484 0) (size 0.59 0.64) (layers "B.Cu" "B.Paste" "B.Mask") (roundrect_rratio 0.25)
      (net 1 "GND") (pintype "passive"))
  )

  (footprint "kria-k26-devboard-footprints:R_0402_1005Metric" (layer "B.Cu")
    (at 99 87.45 180)
    (descr "Resistor SMD 0402")
    (tags "resistor SMD 0402")
    (property "Author" "Antmicro")
    (property "License" "Apache-2.0")
    (property "MPN" "CR0402-FX-1002GLF")
    (property "Manufacturer" "Bourns")
    (property "Sheetfile" "k26_som.kicad_sch")
    (property "Sheetname" "Xilinx K26 SOM")
    (property "Tolerance" "1%")
    (property "Val" "10k")
    (property "ki_description" "10k resistor in 0402 package with 1% tolerance")
    (attr smd)
    (fp_text reference "R177" (at -0.98 0.63) (layer "B.SilkS")
        (effects (font (size 0.7 0.7) (thickness 0.15)) (justify left bottom mirror))
    )
    (fp_text value "R_10k_0402" (at 0 -1.4) (layer "B.Fab") hide
        (effects (font (size 0.7 0.7) (thickness 0.15)) (justify left bottom mirror))
    )
    (fp_text user "${REFERENCE}" (at -0.95 -3.168) (layer "B.Fab") hide
        (effects (font (size 0.7 0.7) (thickness 0.15)) (justify left bottom mirror))
    )
    (fp_text user "License: Apache-2.0" (at -0.95 -5.169) (layer "B.Fab") hide
        (effects (font (size 0.7 0.7) (thickness 0.15)) (justify left bottom mirror))
    )
    (fp_text user "Author: Antmicro" (at -0.95 -4.169) (layer "B.Fab") hide
        (effects (font (size 0.7 0.7) (thickness 0.15)) (justify left bottom mirror))
    )
    (fp_rect (start -0.93 0.47) (end 0.93 -0.47)
      (stroke (width 0.05) (type solid)) (fill none) (layer "B.CrtYd"))
    (fp_rect (start -0.5 0.25) (end 0.5 -0.25)
      (stroke (width 0.15) (type solid)) (fill none) (layer "B.Fab"))
    (pad "1" smd roundrect (at -0.485 0 180) (size 0.59 0.64) (layers "B.Cu" "B.Paste" "B.Mask") (roundrect_rratio 0.25)
      (net 306 "USB_5V") (pintype "passive"))
    (pad "2" smd roundrect (at 0.485 0 180) (size 0.59 0.64) (layers "B.Cu" "B.Paste" "B.Mask") (roundrect_rratio 0.25)
      (net 431 "Net-(Q19-C)") (pintype "passive"))
  )

  (footprint "kria-k26-devboard-footprints:Fiducial_1mm_Mask2mm" (layer "B.Cu")
    (at 183.3 55.4 180)
    (descr "Circular Fiducial, 1mm bare copper, 3mm soldermask opening")
    (tags "fiducial")
    (attr smd board_only exclude_from_bom)
    (fp_text reference "FID6" (at -0.07 -3.21 90) (layer "B.SilkS")
        (effects (font (size 1 1) (thickness 0.15)) (justify mirror))
    )
    (fp_text value "Fiducial_1mm_Mask2mm" (at 0 -2.6035) (layer "B.Fab") hide
        (effects (font (size 1 1) (thickness 0.15)) (justify mirror))
    )
    (fp_text user "License: Apache-2.0" (at -1.25 -7.003) (layer "B.Fab") hide
        (effects (font (size 0.7 0.7) (thickness 0.15)) (justify left bottom mirror))
    )
    (fp_text user "${REFERENCE}" (at 0 0) (layer "B.Fab")
        (effects (font (size 0.4 0.4) (thickness 0.06)) (justify mirror))
    )
    (fp_text user "Author: Antmicro" (at -1.25 -5.803) (layer "B.Fab") hide
        (effects (font (size 0.7 0.7) (thickness 0.15)) (justify left bottom mirror))
    )
    (fp_circle (center 0 0) (end 1.24 0)
      (stroke (width 0.05) (type solid)) (fill none) (layer "B.CrtYd"))
    (fp_circle (center 0 0) (end 0.999 0)
      (stroke (width 0.15) (type solid)) (fill none) (layer "B.Fab"))
    (pad "" smd circle (at 0 0 180) (size 1 1) (layers "B.Cu" "B.Mask")
      (solder_mask_margin 0.5) (clearance 0.5))
  )

  (footprint "kria-k26-devboard-footprints:R_0603_1608Metric" (layer "B.Cu")
    (at 149.86 79.07 180)
    (descr "Resistor SMD 0603")
    (tags "resistor SMD 0603")
    (property "Author" "Antmicro")
    (property "License" "Apache-2.0")
    (property "MPN" "PMR03EZPJ000")
    (property "Manufacturer" "ROHM Semiconductor")
    (property "Max. Curr." "22.4A")
    (property "Sheetfile" "dc-dc-conventers.kicad_sch")
    (property "Sheetname" "DC/DC conventers")
    (property "Val" "0R")
    (property "ki_description" "Metal strip 0Ohm jumper 22.4A")
    (property "ki_keywords" "Metal strip 0Ohm jumper 22.4A high power hpwr current")
    (attr smd)
    (fp_text reference "R160" (at -1.57 -1.55) (layer "B.SilkS")
        (effects (font (size 0.7 0.7) (thickness 0.15)) (justify left bottom mirror))
    )
    (fp_text value "R_0R_22.4A_0603" (at 0 -1.6) (layer "B.Fab") hide
        (effects (font (size 0.7 0.7) (thickness 0.15)) (justify left bottom mirror))
    )
    (fp_text user "Author: Antmicro" (at -1.25 -4.9) (layer "B.Fab") hide
        (effects (font (size 0.7 0.7) (thickness 0.15)) (justify left bottom mirror))
    )
    (fp_text user "License: Apache-2.0" (at -1.25 -5.9) (layer "B.Fab") hide
        (effects (font (size 0.7 0.7) (thickness 0.15)) (justify left bottom mirror))
    )
    (fp_text user "${REFERENCE}" (at -1.25 -3.898) (layer "B.Fab") hide
        (effects (font (size 0.7 0.7) (thickness 0.15)) (justify left bottom mirror))
    )
    (fp_line (start -0.3 -0.3) (end 0.3 -0.3)
      (stroke (width 0.15) (type solid)) (layer "B.SilkS"))
    (fp_line (start -0.3 0.3) (end 0.3 0.3)
      (stroke (width 0.15) (type solid)) (layer "B.SilkS"))
    (fp_rect (start -1.25 0.7) (end 1.25 -0.7)
      (stroke (width 0.05) (type solid)) (fill none) (layer "B.CrtYd"))
    (fp_rect (start -0.8 0.4) (end 0.8 -0.4)
      (stroke (width 0.15) (type solid)) (fill none) (layer "B.Fab"))
    (pad "1" smd roundrect (at -0.7 0 180) (size 0.6 0.8) (layers "B.Cu" "B.Paste" "B.Mask") (roundrect_rratio 0.2)
      (net 772 "/Power Supply/DC/DC conventers/USB_5V_OUT") (pintype "passive"))
    (pad "2" smd roundrect (at 0.7 0 180) (size 0.6 0.8) (layers "B.Cu" "B.Paste" "B.Mask") (roundrect_rratio 0.2)
      (net 306 "USB_5V") (pintype "passive"))
  )

  (footprint "kria-k26-devboard-footprints:R_0402_1005Metric" (layer "B.Cu")
    (at 140.475 120.35 180)
    (descr "Resistor SMD 0402")
    (tags "resistor SMD 0402")
    (property "Author" "Antmicro")
    (property "License" "Apache-2.0")
    (property "MPN" "CR0402-FX-1002GLF")
    (property "Manufacturer" "Bourns")
    (property "Sheetfile" "debug.kicad_sch")
    (property "Sheetname" "Debug and JTAG")
    (property "Tolerance" "1%")
    (property "Val" "10k")
    (property "ki_description" "10k resistor in 0402 package with 1% tolerance")
    (attr smd)
    (fp_text reference "R169" (at -3.685 -0.4) (layer "B.SilkS")
        (effects (font (size 0.7 0.7) (thickness 0.15)) (justify left bottom mirror))
    )
    (fp_text value "R_10k_0402" (at 0 -1.4) (layer "B.Fab") hide
        (effects (font (size 0.7 0.7) (thickness 0.15)) (justify left bottom mirror))
    )
    (fp_text user "License: Apache-2.0" (at -0.95 -5.169) (layer "B.Fab") hide
        (effects (font (size 0.7 0.7) (thickness 0.15)) (justify left bottom mirror))
    )
    (fp_text user "${REFERENCE}" (at -0.95 -3.168) (layer "B.Fab") hide
        (effects (font (size 0.7 0.7) (thickness 0.15)) (justify left bottom mirror))
    )
    (fp_text user "Author: Antmicro" (at -0.95 -4.169) (layer "B.Fab") hide
        (effects (font (size 0.7 0.7) (thickness 0.15)) (justify left bottom mirror))
    )
    (fp_rect (start -0.93 0.47) (end 0.93 -0.47)
      (stroke (width 0.05) (type solid)) (fill none) (layer "B.CrtYd"))
    (fp_rect (start -0.5 0.25) (end 0.5 -0.25)
      (stroke (width 0.15) (type solid)) (fill none) (layer "B.Fab"))
    (pad "1" smd roundrect (at -0.485 0 180) (size 0.59 0.64) (layers "B.Cu" "B.Paste" "B.Mask") (roundrect_rratio 0.25)
      (net 169 "/Debug and JTAG/JTAG_VCCO_ON") (pintype "passive"))
    (pad "2" smd roundrect (at 0.485 0 180) (size 0.59 0.64) (layers "B.Cu" "B.Paste" "B.Mask") (roundrect_rratio 0.25)
      (net 1 "GND") (pintype "passive"))
  )

  (footprint "kria-k26-devboard-footprints:SOT-416" (layer "B.Cu")
    (at 98 89.2)
    (descr "SOT-416")
    (tags "SOT-416")
    (property "Author" "Antmicro")
    (property "License" "Apache-2.0")
    (property "MPN" "DTC014TEBTL")
    (property "Manufacturer" "ROHM Semiconductor")
    (property "Sheetfile" "k26_som.kicad_sch")
    (property "Sheetname" "Xilinx K26 SOM")
    (property "ki_description" "Digital NPN Transistor, 10k/NONE, EMT-3")
    (attr smd)
    (fp_text reference "Q19" (at -0.91 0.36 180) (layer "B.SilkS")
        (effects (font (size 0.7 0.7) (thickness 0.15)) (justify left bottom mirror))
    )
    (fp_text value "DTC014T_SOT-416" (at 0 -2 180) (layer "B.Fab") hide
        (effects (font (size 0.7 0.7) (thickness 0.15)) (justify left bottom mirror))
    )
    (fp_text user "${REFERENCE}" (at -1 -3.4 180) (layer "B.Fab") hide
        (effects (font (size 0.7 0.7) (thickness 0.15)) (justify left bottom mirror))
    )
    (fp_text user "License: Apache-2.0" (at -1 -5.802 180) (layer "B.Fab") hide
        (effects (font (size 0.7 0.7) (thickness 0.15)) (justify left bottom mirror))
    )
    (fp_text user "Author: Antmicro" (at -1 -4.602 180) (layer "B.Fab") hide
        (effects (font (size 0.7 0.7) (thickness 0.15)) (justify left bottom mirror))
    )
    (fp_line (start -0.5 0.15) (end -0.5 -0.15)
      (stroke (width 0.15) (type solid)) (layer "B.SilkS"))
    (fp_line (start 0.5 -0.9) (end -0.5 -0.9)
      (stroke (width 0.15) (type solid)) (layer "B.SilkS"))
    (fp_line (start 0.5 -0.9) (end 0.5 -0.7)
      (stroke (width 0.15) (type solid)) (layer "B.SilkS"))
    (fp_line (start 0.508 0.9) (end -0.5 0.9)
      (stroke (width 0.15) (type solid)) (layer "B.SilkS"))
    (fp_line (start 0.508 0.9) (end 0.508 0.592)
      (stroke (width 0.15) (type solid)) (layer "B.SilkS"))
    (fp_rect (start -1 1.05) (end 1 -1.05)
      (stroke (width 0.05) (type solid)) (fill none) (layer "B.CrtYd"))
    (fp_line (start -0.05 0.9) (end -0.45 0.5)
      (stroke (width 0.15) (type solid)) (layer "B.Fab"))
    (fp_rect (start 0.45 -0.9) (end -0.45 0.9)
      (stroke (width 0.15) (type solid)) (fill none) (layer "B.Fab"))
    (pad "1" smd rect (at -0.652 0.5) (size 0.6 0.5) (layers "B.Cu" "B.Paste" "B.Mask")
      (net 6 "/Xilinx K26 SOM/HDA20") (pinfunction "B") (pintype "input"))
    (pad "2" smd rect (at -0.652 -0.498) (size 0.6 0.5) (layers "B.Cu" "B.Paste" "B.Mask")
      (net 1 "GND") (pinfunction "E") (pintype "passive"))
    (pad "3" smd rect (at 0.65 0) (size 0.6 0.5) (layers "B.Cu" "B.Paste" "B.Mask")
      (net 431 "Net-(Q19-C)") (pinfunction "C") (pintype "passive"))
  )

  (footprint "kria-k26-devboard-footprints:R_0402_1005Metric" (layer "B.Cu")
    (at 130.33 63.75 -90)
    (descr "Resistor SMD 0402")
    (tags "resistor SMD 0402")
    (property "Author" "Antmicro")
    (property "License" "Apache-2.0")
    (property "MPN" "CR0402-FX-4302GLF")
    (property "Manufacturer" "Bourns")
    (property "Sheetfile" "usb.kicad_sch")
    (property "Sheetname" "USB")
    (property "Tolerance" "1%")
    (property "Val" "43k")
    (property "ki_description" "43k resistor in 0402 package with 1% tolerance")
    (attr smd)
    (fp_text reference "R174" (at -3.780421 -0.38 90) (layer "B.SilkS")
        (effects (font (size 0.7 0.7) (thickness 0.15)) (justify left bottom mirror))
    )
    (fp_text value "R_43k_0402" (at 0 -1.4 90) (layer "B.Fab") hide
        (effects (font (size 0.7 0.7) (thickness 0.15)) (justify left bottom mirror))
    )
    (fp_text user "License: Apache-2.0" (at -0.95 -5.169 90) (layer "B.Fab") hide
        (effects (font (size 0.7 0.7) (thickness 0.15)) (justify left bottom mirror))
    )
    (fp_text user "${REFERENCE}" (at -0.95 -3.168 90) (layer "B.Fab") hide
        (effects (font (size 0.7 0.7) (thickness 0.15)) (justify left bottom mirror))
    )
    (fp_text user "Author: Antmicro" (at -0.95 -4.169 90) (layer "B.Fab") hide
        (effects (font (size 0.7 0.7) (thickness 0.15)) (justify left bottom mirror))
    )
    (fp_rect (start -0.93 0.47) (end 0.93 -0.47)
      (stroke (width 0.05) (type solid)) (fill none) (layer "B.CrtYd"))
    (fp_rect (start -0.5 0.25) (end 0.5 -0.25)
      (stroke (width 0.15) (type solid)) (fill none) (layer "B.Fab"))
    (pad "1" smd roundrect (at -0.485 0 270) (size 0.59 0.64) (layers "B.Cu" "B.Paste" "B.Mask") (roundrect_rratio 0.25)
      (net 697 "Net-(U17-DP1_VBUS_MON)") (pintype "passive"))
    (pad "2" smd roundrect (at 0.485 0 270) (size 0.59 0.64) (layers "B.Cu" "B.Paste" "B.Mask") (roundrect_rratio 0.25)
      (net 64 "/USB/USB1_VBUS") (pintype "passive"))
  )

  (footprint "kria-k26-devboard-footprints:R_0402_1005Metric" (layer "B.Cu")
    (at 174.95 129.025 -90)
    (descr "Resistor SMD 0402")
    (tags "resistor SMD 0402")
    (property "Author" "Antmicro")
    (property "Current" "1A")
    (property "License" "Apache-2.0")
    (property "MPN" "ERJ2GE0R00X")
    (property "Manufacturer" "Panasonic")
    (property "Sheetfile" "dc-dc-conventers.kicad_sch")
    (property "Sheetname" "DC/DC conventers")
    (property "Tolerance" "")
    (property "Val" "0R")
    (property "ki_description" "0R resistor in 0402 package with unspecified tolerance")
    (attr smd)
    (fp_text reference "R165" (at 0.815 -0.37 90) (layer "B.SilkS")
        (effects (font (size 0.7 0.7) (thickness 0.15)) (justify left bottom mirror))
    )
    (fp_text value "R_0R_0402" (at 0 -1.4 90) (layer "B.Fab") hide
        (effects (font (size 0.7 0.7) (thickness 0.15)) (justify left bottom mirror))
    )
    (fp_text user "Author: Antmicro" (at -0.95 -4.169 90) (layer "B.Fab") hide
        (effects (font (size 0.7 0.7) (thickness 0.15)) (justify left bottom mirror))
    )
    (fp_text user "License: Apache-2.0" (at -0.95 -5.169 90) (layer "B.Fab") hide
        (effects (font (size 0.7 0.7) (thickness 0.15)) (justify left bottom mirror))
    )
    (fp_text user "${REFERENCE}" (at -0.95 -3.168 90) (layer "B.Fab") hide
        (effects (font (size 0.7 0.7) (thickness 0.15)) (justify left bottom mirror))
    )
    (fp_rect (start -0.93 0.47) (end 0.93 -0.47)
      (stroke (width 0.05) (type solid)) (fill none) (layer "B.CrtYd"))
    (fp_rect (start -0.5 0.25) (end 0.5 -0.25)
      (stroke (width 0.15) (type solid)) (fill none) (layer "B.Fab"))
    (pad "1" smd roundrect (at -0.485 0 270) (size 0.59 0.64) (layers "B.Cu" "B.Paste" "B.Mask") (roundrect_rratio 0.25)
      (net 774 "/Power Supply/DC/DC conventers/SOM_5V_FB") (pintype "passive"))
    (pad "2" smd roundrect (at 0.485 0 270) (size 0.59 0.64) (layers "B.Cu" "B.Paste" "B.Mask") (roundrect_rratio 0.25)
      (net 773 "/Power Supply/DC/DC conventers/SOM_5V_OUT") (pintype "passive"))
  )

  (footprint "kria-k26-devboard-footprints:R_0603_1608Metric" (layer "B.Cu")
    (at 136.3 85.55)
    (descr "Resistor SMD 0603")
    (tags "resistor SMD 0603")
    (property "Author" "Antmicro")
    (property "License" "Apache-2.0")
    (property "MPN" "PMR03EZPJ000")
    (property "Manufacturer" "ROHM Semiconductor")
    (property "Max. Curr." "22.4A")
    (property "Sheetfile" "dc-dc-conventers.kicad_sch")
    (property "Sheetname" "DC/DC conventers")
    (property "Val" "0R")
    (property "ki_description" "Metal strip 0Ohm jumper 22.4A")
    (property "ki_keywords" "Metal strip 0Ohm jumper 22.4A high power hpwr current")
    (attr smd)
    (fp_text reference "R163" (at 1.39 1.56 180) (layer "B.SilkS")
        (effects (font (size 0.7 0.7) (thickness 0.15)) (justify left bottom mirror))
    )
    (fp_text value "R_0R_22.4A_0603" (at 0 -1.6 180) (layer "B.Fab") hide
        (effects (font (size 0.7 0.7) (thickness 0.15)) (justify left bottom mirror))
    )
    (fp_text user "Author: Antmicro" (at -1.25 -4.9 180) (layer "B.Fab") hide
        (effects (font (size 0.7 0.7) (thickness 0.15)) (justify left bottom mirror))
    )
    (fp_text user "License: Apache-2.0" (at -1.25 -5.9 180) (layer "B.Fab") hide
        (effects (font (size 0.7 0.7) (thickness 0.15)) (justify left bottom mirror))
    )
    (fp_text user "${REFERENCE}" (at -1.25 -3.898 180) (layer "B.Fab") hide
        (effects (font (size 0.7 0.7) (thickness 0.15)) (justify left bottom mirror))
    )
    (fp_line (start -0.3 -0.3) (end 0.3 -0.3)
      (stroke (width 0.15) (type solid)) (layer "B.SilkS"))
    (fp_line (start -0.3 0.3) (end 0.3 0.3)
      (stroke (width 0.15) (type solid)) (layer "B.SilkS"))
    (fp_rect (start -1.25 0.7) (end 1.25 -0.7)
      (stroke (width 0.05) (type solid)) (fill none) (layer "B.CrtYd"))
    (fp_rect (start -0.8 0.4) (end 0.8 -0.4)
      (stroke (width 0.15) (type solid)) (fill none) (layer "B.Fab"))
    (pad "1" smd roundrect (at -0.7 0) (size 0.6 0.8) (layers "B.Cu" "B.Paste" "B.Mask") (roundrect_rratio 0.2)
      (net 766 "/Power Supply/DC/DC conventers/PS_2V5_OUT") (pintype "passive"))
    (pad "2" smd roundrect (at 0.7 0) (size 0.6 0.8) (layers "B.Cu" "B.Paste" "B.Mask") (roundrect_rratio 0.2)
      (net 16 "PS_2V5") (pintype "passive"))
  )

  (footprint "kria-k26-devboard-footprints:C_0402_1005Metric" (layer "B.Cu")
    (at 151.85 108.7)
    (descr "Capacitor SMD 0402")
    (tags "capacitor SMD 0402")
    (property "Author" "Antmicro")
    (property "Dielectric" "")
    (property "License" "Apache-2.0")
    (property "MPN" "C1005X6S1A105K050BC")
    (property "Manufacturer" "TDK")
    (property "Sheetfile" "debug.kicad_sch")
    (property "Sheetname" "Debug and JTAG")
    (property "Val" "1u")
    (property "Voltage" "")
    (property "ki_description" " ")
    (attr smd)
    (fp_text reference "C243" (at 3.832 0.35 180) (layer "B.SilkS")
        (effects (font (size 0.7 0.7) (thickness 0.15)) (justify left bottom mirror))
    )
    (fp_text value "C_1u_0402" (at 0 -1.4 180) (layer "B.Fab") hide
        (effects (font (size 0.7 0.7) (thickness 0.15)) (justify left bottom mirror))
    )
    (fp_text user "${REFERENCE}" (at -0.932 -3.168 180) (layer "B.Fab") hide
        (effects (font (size 0.7 0.7) (thickness 0.15)) (justify left bottom mirror))
    )
    (fp_text user "License: Apache-2.0" (at -0.932 -5.17 180) (layer "B.Fab") hide
        (effects (font (size 0.7 0.7) (thickness 0.15)) (justify left bottom mirror))
    )
    (fp_text user "Author: Antmicro" (at -0.932 -4.17 180) (layer "B.Fab") hide
        (effects (font (size 0.7 0.7) (thickness 0.15)) (justify left bottom mirror))
    )
    (fp_rect (start -0.94 0.47) (end 0.94 -0.47)
      (stroke (width 0.05) (type solid)) (fill none) (layer "B.CrtYd"))
    (fp_rect (start -0.499 0.249) (end 0.499 -0.249)
      (stroke (width 0.15) (type solid)) (fill none) (layer "B.Fab"))
    (pad "1" smd roundrect (at -0.484 0) (size 0.59 0.64) (layers "B.Cu" "B.Paste" "B.Mask") (roundrect_rratio 0.25)
      (net 187 "/Debug and JTAG/PD_3V3") (pintype "passive"))
    (pad "2" smd roundrect (at 0.484 0) (size 0.59 0.64) (layers "B.Cu" "B.Paste" "B.Mask") (roundrect_rratio 0.25)
      (net 1 "GND") (pintype "passive"))
  )

  (footprint "kria-k26-devboard-footprints:R_0402_1005Metric" (layer "B.Cu")
    (at 129.3 63.75 90)
    (descr "Resistor SMD 0402")
    (tags "resistor SMD 0402")
    (property "Author" "Antmicro")
    (property "License" "Apache-2.0")
    (property "MPN" "CR0402-FX-4992GLF")
    (property "Manufacturer" "Bourns")
    (property "Sheetfile" "usb.kicad_sch")
    (property "Sheetname" "USB")
    (property "Tolerance" "1%")
    (property "Val" "49k9")
    (property "ki_description" "49k9 resistor in 0402 package with 1% tolerance")
    (attr smd)
    (fp_text reference "R175" (at 3.780421 0.36 270) (layer "B.SilkS")
        (effects (font (size 0.7 0.7) (thickness 0.15)) (justify left bottom mirror))
    )
    (fp_text value "R_49k9_0402" (at 0 -1.4 270) (layer "B.Fab") hide
        (effects (font (size 0.7 0.7) (thickness 0.15)) (justify left bottom mirror))
    )
    (fp_text user "Author: Antmicro" (at -0.95 -4.169 270) (layer "B.Fab") hide
        (effects (font (size 0.7 0.7) (thickness 0.15)) (justify left bottom mirror))
    )
    (fp_text user "${REFERENCE}" (at -0.95 -3.168 270) (layer "B.Fab") hide
        (effects (font (size 0.7 0.7) (thickness 0.15)) (justify left bottom mirror))
    )
    (fp_text user "License: Apache-2.0" (at -0.95 -5.169 270) (layer "B.Fab") hide
        (effects (font (size 0.7 0.7) (thickness 0.15)) (justify left bottom mirror))
    )
    (fp_rect (start -0.93 0.47) (end 0.93 -0.47)
      (stroke (width 0.05) (type solid)) (fill none) (layer "B.CrtYd"))
    (fp_rect (start -0.5 0.25) (end 0.5 -0.25)
      (stroke (width 0.15) (type solid)) (fill none) (layer "B.Fab"))
    (pad "1" smd roundrect (at -0.485 0 90) (size 0.59 0.64) (layers "B.Cu" "B.Paste" "B.Mask") (roundrect_rratio 0.25)
      (net 1 "GND") (pintype "passive"))
    (pad "2" smd roundrect (at 0.485 0 90) (size 0.59 0.64) (layers "B.Cu" "B.Paste" "B.Mask") (roundrect_rratio 0.25)
      (net 697 "Net-(U17-DP1_VBUS_MON)") (pintype "passive"))
  )

  (footprint "kria-k26-devboard-footprints:R_0402_1005Metric" (layer "B.Cu")
    (at 93.575 136.35 -90)
    (descr "Resistor SMD 0402")
    (tags "resistor SMD 0402")
    (property "Author" "Antmicro")
    (property "Current" "1A")
    (property "License" "Apache-2.0")
    (property "MPN" "ERJ2GE0R00X")
    (property "Manufacturer" "Panasonic")
    (property "Sheetfile" "k26_som.kicad_sch")
    (property "Sheetname" "Xilinx K26 SOM")
    (property "Tolerance" "")
    (property "Val" "0R")
    (property "ki_description" "0R resistor in 0402 package with unspecified tolerance")
    (attr smd)
    (fp_text reference "R170" (at -1.36 0.615 90) (layer "B.SilkS")
        (effects (font (size 0.7 0.7) (thickness 0.15)) (justify left bottom mirror))
    )
    (fp_text value "R_0R_0402" (at 0 -1.4 90) (layer "B.Fab") hide
        (effects (font (size 0.7 0.7) (thickness 0.15)) (justify left bottom mirror))
    )
    (fp_text user "Author: Antmicro" (at -0.95 -4.169 90) (layer "B.Fab") hide
        (effects (font (size 0.7 0.7) (thickness 0.15)) (justify left bottom mirror))
    )
    (fp_text user "${REFERENCE}" (at -0.95 -3.168 90) (layer "B.Fab") hide
        (effects (font (size 0.7 0.7) (thickness 0.15)) (justify left bottom mirror))
    )
    (fp_text user "License: Apache-2.0" (at -0.95 -5.169 90) (layer "B.Fab") hide
        (effects (font (size 0.7 0.7) (thickness 0.15)) (justify left bottom mirror))
    )
    (fp_rect (start -0.93 0.47) (end 0.93 -0.47)
      (stroke (width 0.05) (type solid)) (fill none) (layer "B.CrtYd"))
    (fp_rect (start -0.5 0.25) (end 0.5 -0.25)
      (stroke (width 0.15) (type solid)) (fill none) (layer "B.Fab"))
    (pad "1" smd roundrect (at -0.485 0 270) (size 0.59 0.64) (layers "B.Cu" "B.Paste" "B.Mask") (roundrect_rratio 0.25)
      (net 1 "GND") (pintype "passive"))
    (pad "2" smd roundrect (at 0.485 0 270) (size 0.59 0.64) (layers "B.Cu" "B.Paste" "B.Mask") (roundrect_rratio 0.25)
      (net 438 "/Xilinx K26 SOM/VCC_BATT") (pintype "passive"))
  )

  (footprint "kria-k26-devboard-footprints:C_0402_1005Metric" (layer "B.Cu")
    (at 95.754999 67.675)
    (descr "Capacitor SMD 0402")
    (tags "capacitor SMD 0402")
    (property "Author" "Antmicro")
    (property "Dielectric" "")
    (property "License" "Apache-2.0")
    (property "MPN" "CC0402MRX5R5BB106")
    (property "Manufacturer" "Yaego")
    (property "Sheetfile" "dp.kicad_sch")
    (property "Sheetname" "Display Port")
    (property "Val" "10u")
    (property "Voltage" "")
    (property "ki_description" " ")
    (attr smd)
    (fp_text reference "C249" (at 3.705001 0.355 180) (layer "B.SilkS")
        (effects (font (size 0.7 0.7) (thickness 0.15)) (justify left bottom mirror))
    )
    (fp_text value "C_10u_0402" (at 0 -1.4 180) (layer "B.Fab") hide
        (effects (font (size 0.7 0.7) (thickness 0.15)) (justify left bottom mirror))
    )
    (fp_text user "${REFERENCE}" (at -0.932 -3.168 180) (layer "B.Fab") hide
        (effects (font (size 0.7 0.7) (thickness 0.15)) (justify left bottom mirror))
    )
    (fp_text user "Author: Antmicro" (at -0.932 -4.17 180) (layer "B.Fab") hide
        (effects (font (size 0.7 0.7) (thickness 0.15)) (justify left bottom mirror))
    )
    (fp_text user "License: Apache-2.0" (at -0.932 -5.17 180) (layer "B.Fab") hide
        (effects (font (size 0.7 0.7) (thickness 0.15)) (justify left bottom mirror))
    )
    (fp_rect (start -0.94 0.47) (end 0.94 -0.47)
      (stroke (width 0.05) (type solid)) (fill none) (layer "B.CrtYd"))
    (fp_rect (start -0.499 0.249) (end 0.499 -0.249)
      (stroke (width 0.15) (type solid)) (fill none) (layer "B.Fab"))
    (pad "1" smd roundrect (at -0.484 0) (size 0.59 0.64) (layers "B.Cu" "B.Paste" "B.Mask") (roundrect_rratio 0.25)
      (net 334 "Net-(J1-DP_PWR)") (pintype "passive"))
    (pad "2" smd roundrect (at 0.484 0) (size 0.59 0.64) (layers "B.Cu" "B.Paste" "B.Mask") (roundrect_rratio 0.25)
      (net 1 "GND") (pintype "passive"))
  )

  (footprint "kria-k26-devboard-footprints:C_0402_1005Metric" (layer "B.Cu")
    (at 145.95 121.65 90)
    (descr "Capacitor SMD 0402")
    (tags "capacitor SMD 0402")
    (property "Author" "Antmicro")
    (property "Dielectric" "")
    (property "License" "Apache-2.0")
    (property "MPN" "GRM155R61A475MEAAD")
    (property "Manufacturer" "Murata")
    (property "Sheetfile" "debug.kicad_sch")
    (property "Sheetname" "Debug and JTAG")
    (property "Val" "4u7")
    (property "Voltage" "")
    (property "ki_description" " ")
    (attr smd)
    (fp_text reference "C242" (at -1.31 -0.61 90) (layer "B.SilkS")
        (effects (font (size 0.7 0.7) (thickness 0.15)) (justify right bottom mirror))
    )
    (fp_text value "C_4u7_0402" (at 0 -1.4 90) (layer "B.Fab") hide
        (effects (font (size 0.7 0.7) (thickness 0.15)) (justify right bottom mirror))
    )
    (fp_text user "Author: Antmicro" (at -0.932 -4.17 90) (layer "B.Fab") hide
        (effects (font (size 0.7 0.7) (thickness 0.15)) (justify right bottom mirror))
    )
    (fp_text user "License: Apache-2.0" (at -0.932 -5.17 90) (layer "B.Fab") hide
        (effects (font (size 0.7 0.7) (thickness 0.15)) (justify right bottom mirror))
    )
    (fp_text user "${REFERENCE}" (at -0.932 -3.168 90) (layer "B.Fab") hide
        (effects (font (size 0.7 0.7) (thickness 0.15)) (justify right bottom mirror))
    )
    (fp_rect (start -0.94 0.47) (end 0.94 -0.47)
      (stroke (width 0.05) (type solid)) (fill none) (layer "B.CrtYd"))
    (fp_rect (start -0.499 0.249) (end 0.499 -0.249)
      (stroke (width 0.15) (type solid)) (fill none) (layer "B.Fab"))
    (pad "1" smd roundrect (at -0.484 0 90) (size 0.59 0.64) (layers "B.Cu" "B.Paste" "B.Mask") (roundrect_rratio 0.25)
      (net 132 "/Debug and JTAG/USB_1V2") (pintype "passive"))
    (pad "2" smd roundrect (at 0.484 0 90) (size 0.59 0.64) (layers "B.Cu" "B.Paste" "B.Mask") (roundrect_rratio 0.25)
      (net 1 "GND") (pintype "passive"))
  )

  (footprint "kria-k26-devboard-footprints:Fiducial_1mm_Mask2mm" (layer "B.Cu")
    (at 182.9 149.2 90)
    (descr "Circular Fiducial, 1mm bare copper, 3mm soldermask opening")
    (tags "fiducial")
    (attr smd board_only exclude_from_bom)
    (fp_text reference "FID5" (at -0.07 -3.21) (layer "B.SilkS")
        (effects (font (size 1 1) (thickness 0.15)) (justify mirror))
    )
    (fp_text value "Fiducial_1mm_Mask2mm" (at 0 -2.6035 90) (layer "B.Fab") hide
        (effects (font (size 1 1) (thickness 0.15)) (justify mirror))
    )
    (fp_text user "Author: Antmicro" (at -1.25 -5.803 270) (layer "B.Fab") hide
        (effects (font (size 0.7 0.7) (thickness 0.15)) (justify left bottom mirror))
    )
    (fp_text user "License: Apache-2.0" (at -1.25 -7.003 270) (layer "B.Fab") hide
        (effects (font (size 0.7 0.7) (thickness 0.15)) (justify left bottom mirror))
    )
    (fp_text user "${REFERENCE}" (at 0 0 90) (layer "B.Fab")
        (effects (font (size 0.4 0.4) (thickness 0.06)) (justify mirror))
    )
    (fp_circle (center 0 0) (end 1.24 0)
      (stroke (width 0.05) (type solid)) (fill none) (layer "B.CrtYd"))
    (fp_circle (center 0 0) (end 0.999 0)
      (stroke (width 0.15) (type solid)) (fill none) (layer "B.Fab"))
    (pad "" smd circle (at 0 0 90) (size 1 1) (layers "B.Cu" "B.Mask")
      (solder_mask_margin 0.5) (clearance 0.5))
  )

  (footprint "kria-k26-devboard-footprints:R_0805_2012Metric" (layer "B.Cu")
    (at 187.2 75.5 90)
    (property "Author" "Antmicro")
    (property "License" "Apache-2.0")
    (property "MPN" "CR0805-FX-3242ELF")
    (property "Manufacturer" "Bourns")
    (property "Sheetfile" "PoE.kicad_sch")
    (property "Sheetname" "PoE")
    (property "Tolerance" "1%")
    (property "Val" "32k4")
    (property "ki_description" "32k4 resistor in 0805 package with 1% tolerance")
    (attr smd)
    (fp_text reference "R117" (at 1.5 1.89 270) (layer "B.SilkS")
        (effects (font (size 0.7 0.7) (thickness 0.15)) (justify left bottom mirror))
    )
    (fp_text value "R_32k4_0805" (at 0 -1.8 270) (layer "B.Fab") hide
        (effects (font (size 0.7 0.7) (thickness 0.15)) (justify left bottom mirror))
    )
    (fp_text user "License: Apache-2.0" (at -1.9 -5.75 270) (layer "B.Fab") hide
        (effects (font (size 0.7 0.7) (thickness 0.15)) (justify left bottom mirror))
    )
    (fp_text user "${REFERENCE}" (at -1.9 -3.1 270) (layer "B.Fab") hide
        (effects (font (size 0.7 0.7) (thickness 0.15)) (justify left bottom mirror))
    )
    (fp_text user "Author: Antmicro" (at -1.9 -4.4 270) (layer "B.Fab") hide
        (effects (font (size 0.7 0.7) (thickness 0.15)) (justify left bottom mirror))
    )
    (fp_line (start -0.32 -0.699) (end 0.28 -0.699)
      (stroke (width 0.15) (type solid)) (layer "B.SilkS"))
    (fp_line (start -0.3 0.701) (end 0.298 0.701)
      (stroke (width 0.15) (type solid)) (layer "B.SilkS"))
    (fp_rect (start -1.75 0.85) (end 1.75 -0.85)
      (stroke (width 0.05) (type solid)) (fill none) (layer "B.CrtYd"))
    (fp_line (start -0.951 -0.68) (end 0.949 -0.68)
      (stroke (width 0.15) (type solid)) (layer "B.Fab"))
    (fp_line (start -0.951 0.677) (end -0.951 -0.675)
      (stroke (width 0.15) (type solid)) (layer "B.Fab"))
    (fp_line (start -0.951 0.682) (end 0.949 0.682)
      (stroke (width 0.15) (type solid)) (layer "B.Fab"))
    (fp_line (start 0.949 0.677) (end 0.949 -0.675)
      (stroke (width 0.15) (type solid)) (layer "B.Fab"))
    (pad "1" smd roundrect (at -1.1 0.001 90) (size 1 1.4) (layers "B.Cu" "B.Paste" "B.Mask") (roundrect_rratio 0.15)
      (net 7 "Net-(D11-Pad1)") (pintype "passive"))
    (pad "2" smd roundrect (at 1.1 0.001 90) (size 1 1.4) (layers "B.Cu" "B.Paste" "B.Mask") (roundrect_rratio 0.15)
      (net 9 "/Power Supply/PoE/VDD_POE_IN") (pintype "passive"))
  )

  (footprint "kria-k26-devboard-footprints:R_0402_1005Metric" (layer "B.Cu")
    (at 173.925 129.025 90)
    (descr "Resistor SMD 0402")
    (tags "resistor SMD 0402")
    (property "Author" "Antmicro")
    (property "Current" "1A")
    (property "DNP" "DNP")
    (property "License" "Apache-2.0")
    (property "MPN" "ERJ2GE0R00X")
    (property "Manufacturer" "Panasonic")
    (property "Sheetfile" "dc-dc-conventers.kicad_sch")
    (property "Sheetname" "DC/DC conventers")
    (property "Tolerance" "")
    (property "Val" "0R")
    (property "dnp" "")
    (property "exclude_from_bom" "")
    (property "ki_description" "0R resistor in 0402 package with unspecified tolerance")
    (attr exclude_from_pos_files exclude_from_bom)
    (fp_text reference "R166" (at -0.805 0.385 270) (layer "B.SilkS")
        (effects (font (size 0.7 0.7) (thickness 0.15)) (justify left bottom mirror))
    )
    (fp_text value "R_0R_0402" (at 0 -1.4 270) (layer "B.Fab") hide
        (effects (font (size 0.7 0.7) (thickness 0.15)) (justify left bottom mirror))
    )
    (fp_text user "${REFERENCE}" (at -0.95 -3.168 270) (layer "B.Fab") hide
        (effects (font (size 0.7 0.7) (thickness 0.15)) (justify left bottom mirror))
    )
    (fp_text user "License: Apache-2.0" (at -0.95 -5.169 270) (layer "B.Fab") hide
        (effects (font (size 0.7 0.7) (thickness 0.15)) (justify left bottom mirror))
    )
    (fp_text user "Author: Antmicro" (at -0.95 -4.169 270) (layer "B.Fab") hide
        (effects (font (size 0.7 0.7) (thickness 0.15)) (justify left bottom mirror))
    )
    (fp_rect (start -0.93 0.47) (end 0.93 -0.47)
      (stroke (width 0.05) (type solid)) (fill none) (layer "B.CrtYd"))
    (fp_rect (start -0.5 0.25) (end 0.5 -0.25)
      (stroke (width 0.15) (type solid)) (fill none) (layer "B.Fab"))
    (pad "1" smd roundrect (at -0.485 0 90) (size 0.59 0.64) (layers "B.Cu" "B.Paste" "B.Mask") (roundrect_rratio 0.25)
      (net 8 "SOM_5V0") (pintype "passive"))
    (pad "2" smd roundrect (at 0.485 0 90) (size 0.59 0.64) (layers "B.Cu" "B.Paste" "B.Mask") (roundrect_rratio 0.25)
      (net 774 "/Power Supply/DC/DC conventers/SOM_5V_FB") (pintype "passive"))
  )

  (footprint "kria-k26-devboard-footprints:C_0402_1005Metric" (layer "B.Cu")
    (at 95.75 66.525)
    (descr "Capacitor SMD 0402")
    (tags "capacitor SMD 0402")
    (property "Author" "Antmicro")
    (property "Dielectric" "X5R")
    (property "License" "Apache-2.0")
    (property "MPN" "GRM155R61H104KE14D")
    (property "Manufacturer" "Murata")
    (property "Sheetfile" "dp.kicad_sch")
    (property "Sheetname" "Display Port")
    (property "Val" "100n")
    (property "Voltage" "50V")
    (property "ki_description" " ")
    (attr smd)
    (fp_text reference "C248" (at 3.705001 0.355 180) (layer "B.SilkS")
        (effects (font (size 0.7 0.7) (thickness 0.15)) (justify left bottom mirror))
    )
    (fp_text value "C_100n_0402" (at 0 -1.4 180) (layer "B.Fab") hide
        (effects (font (size 0.7 0.7) (thickness 0.15)) (justify left bottom mirror))
    )
    (fp_text user "License: Apache-2.0" (at -0.932 -5.17 180) (layer "B.Fab") hide
        (effects (font (size 0.7 0.7) (thickness 0.15)) (justify left bottom mirror))
    )
    (fp_text user "Author: Antmicro" (at -0.932 -4.17 180) (layer "B.Fab") hide
        (effects (font (size 0.7 0.7) (thickness 0.15)) (justify left bottom mirror))
    )
    (fp_text user "${REFERENCE}" (at -0.932 -3.168 180) (layer "B.Fab") hide
        (effects (font (size 0.7 0.7) (thickness 0.15)) (justify left bottom mirror))
    )
    (fp_rect (start -0.94 0.47) (end 0.94 -0.47)
      (stroke (width 0.05) (type solid)) (fill none) (layer "B.CrtYd"))
    (fp_rect (start -0.499 0.249) (end 0.499 -0.249)
      (stroke (width 0.15) (type solid)) (fill none) (layer "B.Fab"))
    (pad "1" smd roundrect (at -0.484 0) (size 0.59 0.64) (layers "B.Cu" "B.Paste" "B.Mask") (roundrect_rratio 0.25)
      (net 334 "Net-(J1-DP_PWR)") (pintype "passive"))
    (pad "2" smd roundrect (at 0.484 0) (size 0.59 0.64) (layers "B.Cu" "B.Paste" "B.Mask") (roundrect_rratio 0.25)
      (net 1 "GND") (pintype "passive"))
  )

  (footprint "kria-k26-devboard-footprints:C_0402_1005Metric" (layer "B.Cu")
    (at 107 87.6 180)
    (descr "Capacitor SMD 0402")
    (tags "capacitor SMD 0402")
    (property "Author" "Antmicro")
    (property "Dielectric" "X5R")
    (property "License" "Apache-2.0")
    (property "MPN" "GRM155R61H104KE14D")
    (property "Manufacturer" "Murata")
    (property "Sheetfile" "k26_som.kicad_sch")
    (property "Sheetname" "Xilinx K26 SOM")
    (property "Val" "100n")
    (property "Voltage" "50V")
    (property "ki_description" " ")
    (attr smd)
    (fp_text reference "C252" (at 0.13 -3.55) (layer "B.SilkS")
        (effects (font (size 0.7 0.7) (thickness 0.15)) (justify left bottom mirror))
    )
    (fp_text value "C_100n_0402" (at 0 -1.4) (layer "B.Fab") hide
        (effects (font (size 0.7 0.7) (thickness 0.15)) (justify left bottom mirror))
    )
    (fp_text user "Author: Antmicro" (at -0.932 -4.17) (layer "B.Fab") hide
        (effects (font (size 0.7 0.7) (thickness 0.15)) (justify left bottom mirror))
    )
    (fp_text user "License: Apache-2.0" (at -0.932 -5.17) (layer "B.Fab") hide
        (effects (font (size 0.7 0.7) (thickness 0.15)) (justify left bottom mirror))
    )
    (fp_text user "${REFERENCE}" (at -0.932 -3.168) (layer "B.Fab") hide
        (effects (font (size 0.7 0.7) (thickness 0.15)) (justify left bottom mirror))
    )
    (fp_rect (start -0.94 0.47) (end 0.94 -0.47)
      (stroke (width 0.05) (type solid)) (fill none) (layer "B.CrtYd"))
    (fp_rect (start -0.499 0.249) (end 0.499 -0.249)
      (stroke (width 0.15) (type solid)) (fill none) (layer "B.Fab"))
    (pad "1" smd roundrect (at -0.484 0 180) (size 0.59 0.64) (layers "B.Cu" "B.Paste" "B.Mask") (roundrect_rratio 0.25)
      (net 243 "Net-(Q6-D)") (pintype "passive"))
    (pad "2" smd roundrect (at 0.484 0 180) (size 0.59 0.64) (layers "B.Cu" "B.Paste" "B.Mask") (roundrect_rratio 0.25)
      (net 1 "GND") (pintype "passive"))
  )

  (footprint "kria-k26-devboard-footprints:C_0402_1005Metric" (layer "B.Cu")
    (at 107 88.6 180)
    (descr "Capacitor SMD 0402")
    (tags "capacitor SMD 0402")
    (property "Author" "Antmicro")
    (property "Dielectric" "X5R")
    (property "License" "Apache-2.0")
    (property "MPN" "GRM155R61H104KE14D")
    (property "Manufacturer" "Murata")
    (property "Sheetfile" "k26_som.kicad_sch")
    (property "Sheetname" "Xilinx K26 SOM")
    (property "Val" "100n")
    (property "Voltage" "50V")
    (property "ki_description" " ")
    (attr smd)
    (fp_text reference "C253" (at 0.13 -3.55) (layer "B.SilkS")
        (effects (font (size 0.7 0.7) (thickness 0.15)) (justify left bottom mirror))
    )
    (fp_text value "C_100n_0402" (at 0 -1.4) (layer "B.Fab") hide
        (effects (font (size 0.7 0.7) (thickness 0.15)) (justify left bottom mirror))
    )
    (fp_text user "License: Apache-2.0" (at -0.932 -5.17) (layer "B.Fab") hide
        (effects (font (size 0.7 0.7) (thickness 0.15)) (justify left bottom mirror))
    )
    (fp_text user "Author: Antmicro" (at -0.932 -4.17) (layer "B.Fab") hide
        (effects (font (size 0.7 0.7) (thickness 0.15)) (justify left bottom mirror))
    )
    (fp_text user "${REFERENCE}" (at -0.932 -3.168) (layer "B.Fab") hide
        (effects (font (size 0.7 0.7) (thickness 0.15)) (justify left bottom mirror))
    )
    (fp_rect (start -0.94 0.47) (end 0.94 -0.47)
      (stroke (width 0.05) (type solid)) (fill none) (layer "B.CrtYd"))
    (fp_rect (start -0.499 0.249) (end 0.499 -0.249)
      (stroke (width 0.15) (type solid)) (fill none) (layer "B.Fab"))
    (pad "1" smd roundrect (at -0.484 0 180) (size 0.59 0.64) (layers "B.Cu" "B.Paste" "B.Mask") (roundrect_rratio 0.25)
      (net 243 "Net-(Q6-D)") (pintype "passive"))
    (pad "2" smd roundrect (at 0.484 0 180) (size 0.59 0.64) (layers "B.Cu" "B.Paste" "B.Mask") (roundrect_rratio 0.25)
      (net 1 "GND") (pintype "passive"))
  )

  (footprint "kria-k26-devboard-footprints:R_0603_1608Metric" (layer "B.Cu")
    (at 134.85 96.95 -90)
    (descr "Resistor SMD 0603")
    (tags "resistor SMD 0603")
    (property "Author" "Antmicro")
    (property "License" "Apache-2.0")
    (property "MPN" "PMR03EZPJ000")
    (property "Manufacturer" "ROHM Semiconductor")
    (property "Max. Curr." "22.4A")
    (property "Sheetfile" "dc-dc-conventers.kicad_sch")
    (property "Sheetname" "DC/DC conventers")
    (property "Val" "0R")
    (property "ki_description" "Metal strip 0Ohm jumper 22.4A")
    (property "ki_keywords" "Metal strip 0Ohm jumper 22.4A high power hpwr current")
    (attr smd)
    (fp_text reference "R157" (at -1.33 0.84 90) (layer "B.SilkS")
        (effects (font (size 0.7 0.7) (thickness 0.15)) (justify left bottom mirror))
    )
    (fp_text value "R_0R_22.4A_0603" (at 0 -1.6 90) (layer "B.Fab") hide
        (effects (font (size 0.7 0.7) (thickness 0.15)) (justify left bottom mirror))
    )
    (fp_text user "License: Apache-2.0" (at -1.25 -5.9 90) (layer "B.Fab") hide
        (effects (font (size 0.7 0.7) (thickness 0.15)) (justify left bottom mirror))
    )
    (fp_text user "${REFERENCE}" (at -1.25 -3.898 90) (layer "B.Fab") hide
        (effects (font (size 0.7 0.7) (thickness 0.15)) (justify left bottom mirror))
    )
    (fp_text user "Author: Antmicro" (at -1.25 -4.9 90) (layer "B.Fab") hide
        (effects (font (size 0.7 0.7) (thickness 0.15)) (justify left bottom mirror))
    )
    (fp_line (start -0.3 -0.3) (end 0.3 -0.3)
      (stroke (width 0.15) (type solid)) (layer "B.SilkS"))
    (fp_line (start -0.3 0.3) (end 0.3 0.3)
      (stroke (width 0.15) (type solid)) (layer "B.SilkS"))
    (fp_rect (start -1.25 0.7) (end 1.25 -0.7)
      (stroke (width 0.05) (type solid)) (fill none) (layer "B.CrtYd"))
    (fp_rect (start -0.8 0.4) (end 0.8 -0.4)
      (stroke (width 0.15) (type solid)) (fill none) (layer "B.Fab"))
    (pad "1" smd roundrect (at -0.7 0 270) (size 0.6 0.8) (layers "B.Cu" "B.Paste" "B.Mask") (roundrect_rratio 0.2)
      (net 769 "/Power Supply/DC/DC conventers/PS_1V0_OUT") (pintype "passive"))
    (pad "2" smd roundrect (at 0.7 0 270) (size 0.6 0.8) (layers "B.Cu" "B.Paste" "B.Mask") (roundrect_rratio 0.2)
      (net 19 "PS_1V0") (pintype "passive"))
  )

  (footprint "kria-k26-devboard-footprints:R_0402_1005Metric" (layer "B.Cu")
    (at 110.425 96.45 -90)
    (descr "Resistor SMD 0402")
    (tags "resistor SMD 0402")
    (property "Author" "Antmicro")
    (property "DNP" "DNP")
    (property "License" "Apache-2.0")
    (property "MPN" "CR0402-FX-1003GLF")
    (property "Manufacturer" "Bourns")
    (property "Sheetfile" "clock.kicad_sch")
    (property "Sheetname" "Clock distribution")
    (property "Tolerance" "1%")
    (property "Val" "100k")
    (property "dnp" "")
    (property "exclude_from_bom" "")
    (property "ki_description" "100k resistor in 0402 package with 1% tolerance")
    (attr exclude_from_pos_files exclude_from_bom)
    (fp_text reference "R176" (at -1.32 0.625 90) (layer "B.SilkS")
        (effects (font (size 0.7 0.7) (thickness 0.15)) (justify left bottom mirror))
    )
    (fp_text value "R_100k_0402" (at 0 -1.4 90) (layer "B.Fab") hide
        (effects (font (size 0.7 0.7) (thickness 0.15)) (justify left bottom mirror))
    )
    (fp_text user "License: Apache-2.0" (at -0.95 -5.169 90) (layer "B.Fab") hide
        (effects (font (size 0.7 0.7) (thickness 0.15)) (justify left bottom mirror))
    )
    (fp_text user "Author: Antmicro" (at -0.95 -4.169 90) (layer "B.Fab") hide
        (effects (font (size 0.7 0.7) (thickness 0.15)) (justify left bottom mirror))
    )
    (fp_text user "${REFERENCE}" (at -0.95 -3.168 90) (layer "B.Fab") hide
        (effects (font (size 0.7 0.7) (thickness 0.15)) (justify left bottom mirror))
    )
    (fp_rect (start -0.93 0.47) (end 0.93 -0.47)
      (stroke (width 0.05) (type solid)) (fill none) (layer "B.CrtYd"))
    (fp_rect (start -0.5 0.25) (end 0.5 -0.25)
      (stroke (width 0.15) (type solid)) (fill none) (layer "B.Fab"))
    (pad "1" smd roundrect (at -0.485 0 270) (size 0.59 0.64) (layers "B.Cu" "B.Paste" "B.Mask") (roundrect_rratio 0.25)
      (net 1 "GND") (pintype "passive"))
    (pad "2" smd roundrect (at 0.485 0 270) (size 0.59 0.64) (layers "B.Cu" "B.Paste" "B.Mask") (roundrect_rratio 0.25)
      (net 698 "Net-(U8-IN)") (pintype "passive"))
  )

  (footprint "kria-k26-devboard-footprints:R_0402_1005Metric" (layer "B.Cu")
    (at 129.97 81.91 90)
    (descr "Resistor SMD 0402")
    (tags "resistor SMD 0402")
    (property "Author" "Antmicro")
    (property "DNP" "DNP")
    (property "License" "Apache-2.0")
    (property "MPN" "CR0402-FX-5111GLF")
    (property "Manufacturer" "Bourns")
    (property "Sheetfile" "usb.kicad_sch")
    (property "Sheetname" "USB")
    (property "Tolerance" "1%")
    (property "Val" "5k11")
    (property "dnp" "")
    (property "exclude_from_bom" "")
    (property "ki_description" "5k11 resistor in 0402 package with 1% tolerance")
    (attr exclude_from_pos_files exclude_from_bom)
    (fp_text reference "R171" (at 1.29 1.37 270) (layer "B.SilkS")
        (effects (font (size 0.7 0.7) (thickness 0.15)) (justify left bottom mirror))
    )
    (fp_text value "R_5k11_0402" (at 0 -1.4 270) (layer "B.Fab") hide
        (effects (font (size 0.7 0.7) (thickness 0.15)) (justify left bottom mirror))
    )
    (fp_text user "Author: Antmicro" (at -0.95 -4.169 270) (layer "B.Fab") hide
        (effects (font (size 0.7 0.7) (thickness 0.15)) (justify left bottom mirror))
    )
    (fp_text user "${REFERENCE}" (at -0.95 -3.168 270) (layer "B.Fab") hide
        (effects (font (size 0.7 0.7) (thickness 0.15)) (justify left bottom mirror))
    )
    (fp_text user "License: Apache-2.0" (at -0.95 -5.169 270) (layer "B.Fab") hide
        (effects (font (size 0.7 0.7) (thickness 0.15)) (justify left bottom mirror))
    )
    (fp_rect (start -0.93 0.47) (end 0.93 -0.47)
      (stroke (width 0.05) (type solid)) (fill none) (layer "B.CrtYd"))
    (fp_rect (start -0.5 0.25) (end 0.5 -0.25)
      (stroke (width 0.15) (type solid)) (fill none) (layer "B.Fab"))
    (pad "1" smd roundrect (at -0.485 0 90) (size 0.59 0.64) (layers "B.Cu" "B.Paste" "B.Mask") (roundrect_rratio 0.25)
      (net 696 "Net-(U17-DP1_CC2)") (pintype "passive"))
    (pad "2" smd roundrect (at 0.485 0 90) (size 0.59 0.64) (layers "B.Cu" "B.Paste" "B.Mask") (roundrect_rratio 0.25)
      (net 1 "GND") (pintype "passive"))
  )

  (footprint "kria-k26-devboard-footprints:R_0402_1005Metric" (layer "B.Cu")
    (at 97.8 91)
    (descr "Resistor SMD 0402")
    (tags "resistor SMD 0402")
    (property "Author" "Antmicro")
    (property "Current" "1A")
    (property "DNP" "DNP")
    (property "License" "Apache-2.0")
    (property "MPN" "ERJ2GE0R00X")
    (property "Manufacturer" "Panasonic")
    (property "Sheetfile" "k26_som.kicad_sch")
    (property "Sheetname" "Xilinx K26 SOM")
    (property "Tolerance" "")
    (property "Val" "0R")
    (property "dnp" "")
    (property "exclude_from_bom" "")
    (property "ki_description" "0R resistor in 0402 package with unspecified tolerance")
    (attr exclude_from_pos_files exclude_from_bom)
    (fp_text reference "R178" (at 1.42 1.33 180) (layer "B.SilkS")
        (effects (font (size 0.7 0.7) (thickness 0.15)) (justify left bottom mirror))
    )
    (fp_text value "R_0R_0402" (at 0 -1.4 180) (layer "B.Fab") hide
        (effects (font (size 0.7 0.7) (thickness 0.15)) (justify left bottom mirror))
    )
    (fp_text user "License: Apache-2.0" (at -0.95 -5.169 180) (layer "B.Fab") hide
        (effects (font (size 0.7 0.7) (thickness 0.15)) (justify left bottom mirror))
    )
    (fp_text user "${REFERENCE}" (at -0.95 -3.168 180) (layer "B.Fab") hide
        (effects (font (size 0.7 0.7) (thickness 0.15)) (justify left bottom mirror))
    )
    (fp_text user "Author: Antmicro" (at -0.95 -4.169 180) (layer "B.Fab") hide
        (effects (font (size 0.7 0.7) (thickness 0.15)) (justify left bottom mirror))
    )
    (fp_rect (start -0.93 0.47) (end 0.93 -0.47)
      (stroke (width 0.05) (type solid)) (fill none) (layer "B.CrtYd"))
    (fp_rect (start -0.5 0.25) (end 0.5 -0.25)
      (stroke (width 0.15) (type solid)) (fill none) (layer "B.Fab"))
    (pad "1" smd roundrect (at -0.485 0) (size 0.59 0.64) (layers "B.Cu" "B.Paste" "B.Mask") (roundrect_rratio 0.25)
      (net 6 "/Xilinx K26 SOM/HDA20") (pintype "passive"))
    (pad "2" smd roundrect (at 0.485 0) (size 0.59 0.64) (layers "B.Cu" "B.Paste" "B.Mask") (roundrect_rratio 0.25)
      (net 431 "Net-(Q19-C)") (pintype "passive"))
  )

  (footprint "kria-k26-devboard-footprints:Fiducial_1mm_Mask2mm" (layer "B.Cu")
    (at 82 150.4 -90)
    (descr "Circular Fiducial, 1mm bare copper, 3mm soldermask opening")
    (tags "fiducial")
    (attr smd board_only exclude_from_bom)
    (fp_text reference "FID4" (at -0.07 -3.21) (layer "B.SilkS")
        (effects (font (size 1 1) (thickness 0.15)) (justify mirror))
    )
    (fp_text value "Fiducial_1mm_Mask2mm" (at 0 -2.6035 90) (layer "B.Fab") hide
        (effects (font (size 1 1) (thickness 0.15)) (justify mirror))
    )
    (fp_text user "${REFERENCE}" (at 0 0 90) (layer "B.Fab")
        (effects (font (size 0.4 0.4) (thickness 0.06)) (justify mirror))
    )
    (fp_text user "Author: Antmicro" (at -1.25 -5.803 90) (layer "B.Fab") hide
        (effects (font (size 0.7 0.7) (thickness 0.15)) (justify left bottom mirror))
    )
    (fp_text user "License: Apache-2.0" (at -1.25 -7.003 90) (layer "B.Fab") hide
        (effects (font (size 0.7 0.7) (thickness 0.15)) (justify left bottom mirror))
    )
    (fp_circle (center 0 0) (end 1.24 0)
      (stroke (width 0.05) (type solid)) (fill none) (layer "B.CrtYd"))
    (fp_circle (center 0 0) (end 0.999 0)
      (stroke (width 0.15) (type solid)) (fill none) (layer "B.Fab"))
    (pad "" smd circle (at 0 0 270) (size 1 1) (layers "B.Cu" "B.Mask")
      (solder_mask_margin 0.5) (clearance 0.5))
  )

  (footprint "kria-k26-devboard-footprints:C_0402_1005Metric" (layer "B.Cu")
    (at 108.95 86.55)
    (descr "Capacitor SMD 0402")
    (tags "capacitor SMD 0402")
    (property "Author" "Antmicro")
    (property "Dielectric" "X5R")
    (property "License" "Apache-2.0")
    (property "MPN" "GRM155R61H104KE14D")
    (property "Manufacturer" "Murata")
    (property "Sheetfile" "k26_som.kicad_sch")
    (property "Sheetname" "Xilinx K26 SOM")
    (property "Val" "100n")
    (property "Voltage" "50V")
    (property "ki_description" " ")
    (attr smd)
    (fp_text reference "C251" (at 3.68 1.56 180) (layer "B.SilkS")
        (effects (font (size 0.7 0.7) (thickness 0.15)) (justify left bottom mirror))
    )
    (fp_text value "C_100n_0402" (at 0 -1.4 180) (layer "B.Fab") hide
        (effects (font (size 0.7 0.7) (thickness 0.15)) (justify left bottom mirror))
    )
    (fp_text user "${REFERENCE}" (at -0.932 -3.168 180) (layer "B.Fab") hide
        (effects (font (size 0.7 0.7) (thickness 0.15)) (justify left bottom mirror))
    )
    (fp_text user "License: Apache-2.0" (at -0.932 -5.17 180) (layer "B.Fab") hide
        (effects (font (size 0.7 0.7) (thickness 0.15)) (justify left bottom mirror))
    )
    (fp_text user "Author: Antmicro" (at -0.932 -4.17 180) (layer "B.Fab") hide
        (effects (font (size 0.7 0.7) (thickness 0.15)) (justify left bottom mirror))
    )
    (fp_rect (start -0.94 0.47) (end 0.94 -0.47)
      (stroke (width 0.05) (type solid)) (fill none) (layer "B.CrtYd"))
    (fp_rect (start -0.499 0.249) (end 0.499 -0.249)
      (stroke (width 0.15) (type solid)) (fill none) (layer "B.Fab"))
    (pad "1" smd roundrect (at -0.484 0) (size 0.59 0.64) (layers "B.Cu" "B.Paste" "B.Mask") (roundrect_rratio 0.25)
      (net 243 "Net-(Q6-D)") (pintype "passive"))
    (pad "2" smd roundrect (at 0.484 0) (size 0.59 0.64) (layers "B.Cu" "B.Paste" "B.Mask") (roundrect_rratio 0.25)
      (net 1 "GND") (pintype "passive"))
  )

  (footprint "kria-k26-devboard-footprints:R_0402_1005Metric" (layer "B.Cu")
    (at 145.566648 76.145761 90)
    (descr "Resistor SMD 0402")
    (tags "resistor SMD 0402")
    (property "Author" "Antmicro")
    (property "License" "Apache-2.0")
    (property "MPN" "CR0402-FX-1473GLF")
    (property "Manufacturer" "Bourns")
    (property "Sheetfile" "dc-dc-conventers.kicad_sch")
    (property "Sheetname" "DC/DC conventers")
    (property "Tolerance" "1%")
    (property "Val" "147k")
    (property "ki_description" "147k resistor in 0402 package with 1% tolerance")
    (attr smd)
    (fp_text reference "R122" (at 1.5 -2.44 270) (layer "B.SilkS")
        (effects (font (size 0.7 0.7) (thickness 0.15)) (justify left bottom mirror))
    )
    (fp_text value "R_147k_0402" (at 0 -1.4 270) (layer "B.Fab") hide
        (effects (font (size 0.7 0.7) (thickness 0.15)) (justify left bottom mirror))
    )
    (fp_text user "${REFERENCE}" (at -0.95 -3.168 270) (layer "B.Fab") hide
        (effects (font (size 0.7 0.7) (thickness 0.15)) (justify left bottom mirror))
    )
    (fp_text user "Author: Antmicro" (at -0.95 -4.169 270) (layer "B.Fab") hide
        (effects (font (size 0.7 0.7) (thickness 0.15)) (justify left bottom mirror))
    )
    (fp_text user "License: Apache-2.0" (at -0.95 -5.169 270) (layer "B.Fab") hide
        (effects (font (size 0.7 0.7) (thickness 0.15)) (justify left bottom mirror))
    )
    (fp_rect (start -0.93 0.47) (end 0.93 -0.47)
      (stroke (width 0.05) (type solid)) (fill none) (layer "B.CrtYd"))
    (fp_rect (start -0.5 0.25) (end 0.5 -0.25)
      (stroke (width 0.15) (type solid)) (fill none) (layer "B.Fab"))
    (pad "1" smd roundrect (at -0.485 0 90) (size 0.59 0.64) (layers "B.Cu" "B.Paste" "B.Mask") (roundrect_rratio 0.25)
      (net 772 "/Power Supply/DC/DC conventers/USB_5V_OUT") (pintype "passive"))
    (pad "2" smd roundrect (at 0.485 0 90) (size 0.59 0.64) (layers "B.Cu" "B.Paste" "B.Mask") (roundrect_rratio 0.25)
      (net 254 "Net-(U47-FB)") (pintype "passive"))
  )
  (gr_line (start 74 52) (end 192 52)
    (stroke (width 0.12) (type solid)) (layer "Edge.Cuts"))
  (gr_line (start 192 52) (end 192 152)
    (stroke (width 0.12) (type solid)) (layer "Edge.Cuts"))
  (gr_line (start 74 152) (end 74 52)
    (stroke (width 0.12) (type solid)) (layer "Edge.Cuts"))
  (gr_line (start 192 152) (end 74 152)
    (stroke (width 0.12) (type solid)) (layer "Edge.Cuts"))
  (gr_text "Rev. 1.2.5 03/2024" (at 92.1 82.7) (layer "F.Cu")
    (effects (font (size 1 1) (thickness 0.15)))
  )
  (gr_text "KRIA K26 devboard" (at 91.8 81.3) (layer "F.Cu")
    (effects (font (size 1 1) (thickness 0.15)))
  )

  (segment (start 144.35 142.85) (end 144.35 142.3) (width 0.109) (layer "F.Cu") (net 1))
  (segment (start 111.115 143.55) (end 111.115 142.915) (width 0.4) (layer "F.Cu") (net 1))
  (segment (start 104.975 139.975) (end 105 139.95) (width 0.182) (layer "F.Cu") (net 1))
  (segment (start 107.13 143.775) (end 106.4 143.775) (width 0.182) (layer "F.Cu") (net 1))
  (segment (start 104.175 139.975) (end 104.975 139.975) (width 0.182) (layer "F.Cu") (net 1))
  (segment (start 159.927001 130.6375) (end 159.440001 130.9495) (width 0.2) (layer "F.Cu") (net 1))
  (segment (start 158.967001 130.0025) (end 159.460001 129.6795) (width 0.2) (layer "F.Cu") (net 1))
  (segment (start 157.387 128.733) (end 157.88 128.41) (width 0.2) (layer "F.Cu") (net 1))
  (segment (start 156.427001 128.0975) (end 155.940001 128.4095) (width 0.2) (layer "F.Cu") (net 1))
  (segment (start 158.967001 110.9525) (end 158.480001 111.2645) (width 0.2) (layer "F.Cu") (net 1))
  (segment (start 159.927 111.588) (end 160.42 111.265) (width 0.2) (layer "F.Cu") (net 1))
  (segment (start 157.387 109.683) (end 157.88 109.36) (width 0.2) (layer "F.Cu") (net 1))
  (segment (start 156.427 109.683) (end 155.94 109.995) (width 0.2) (layer "F.Cu") (net 1))
  (segment (start 159.927 109.683) (end 160.42 109.36) (width 0.2) (layer "F.Cu") (net 1))
  (segment (start 158.967 109.683) (end 158.48 109.995) (width 0.2) (layer "F.Cu") (net 1))
  (segment (start 159.927 108.413) (end 160.42 108.09) (width 0.2) (layer "F.Cu") (net 1))
  (segment (start 158.967 107.143) (end 158.48 107.455) (width 0.2) (layer "F.Cu") (net 1))
  (segment (start 158.967 102.063) (end 158.48 102.375) (width 0.2) (layer "F.Cu") (net 1))
  (segment (start 159.927 100.793) (end 160.42 100.47) (width 0.2) (layer "F.Cu") (net 1))
  (segment (start 95.585 132.165) (end 95.705 132.045) (width 0.4) (layer "F.Cu") (net 1))
  (segment (start 95.705 132.045) (end 96.95 132.045) (width 0.4) (layer "F.Cu") (net 1))
  (segment (start 95.2 132.165) (end 95.585 132.165) (width 0.4) (layer "F.Cu") (net 1))
  (segment (start 98.66 145.14) (end 98.65 145.15) (width 0.182) (layer "F.Cu") (net 1))
  (segment (start 94.564999 143.664999) (end 94.55 143.65) (width 0.4) (layer "F.Cu") (net 1))
  (segment (start 94.564999 144.525) (end 94.564999 143.664999) (width 0.4) (layer "F.Cu") (net 1))
  (segment (start 139.05176 111.829792) (end 139.047758 111.833794) (width 0.182) (layer "F.Cu") (net 1))
  (segment (start 139.047758 111.833794) (end 138.299122 111.833794) (width 0.182) (layer "F.Cu") (net 1))
  (segment (start 140.401076 129.031874) (end 140.39047 129.021267) (width 0.182) (layer "F.Cu") (net 1))
  (segment (start 149.6 119.628) (end 148.253 118.281) (width 0.4) (layer "F.Cu") (net 1))
  (segment (start 150.5 120.55) (end 150.5 120.528) (width 0.4) (layer "F.Cu") (net 1))
  (segment (start 146.73 116.02) (end 146.73 116.758) (width 0.4) (layer "F.Cu") (net 1))
  (segment (start 149.6 120.550002) (end 149.6 119.628) (width 0.4) (layer "F.Cu") (net 1))
  (segment (start 145.97 117.84) (end 147.812 117.84) (width 0.4) (layer "F.Cu") (net 1))
  (segment (start 147.812 117.84) (end 148.253 118.281) (width 0.4) (layer "F.Cu") (net 1))
  (segment (start 147.58 118.954) (end 148.253 118.281) (width 0.4) (layer "F.Cu") (net 1))
  (segment (start 146.73 116.758) (end 148.253 118.281) (width 0.4) (layer "F.Cu") (net 1))
  (segment (start 147.58 120.55) (end 147.58 118.954) (width 0.4) (layer "F.Cu") (net 1))
  (segment (start 148.882843 128.533095) (end 148.282843 128.533095) (width 0.182) (layer "F.Cu") (net 1))
  (segment (start 150.5 119.87) (end 149.842 119.87) (width 0.4) (layer "F.Cu") (net 1))
  (segment (start 149.842 119.87) (end 148.253 118.281) (width 0.4) (layer "F.Cu") (net 1))
  (segment (start 150.5 117.86) (end 148.674 117.86) (width 0.4) (layer "F.Cu") (net 1))
  (segment (start 145.95 118.76) (end 147.774 118.76) (width 0.4) (layer "F.Cu") (net 1))
  (segment (start 147.774 118.76) (end 148.253 118.281) (width 0.4) (layer "F.Cu") (net 1))
  (segment (start 149.48 116.03) (end 149.48 117.054) (width 0.4) (layer "F.Cu") (net 1))
  (segment (start 149.48 117.054) (end 148.253 118.281) (width 0.4) (layer "F.Cu") (net 1))
  (segment (start 150.61 115.924) (end 148.253 118.281) (width 0.4) (layer "F.Cu") (net 1))
  (segment (start 148.674 117.86) (end 148.253 118.281) (width 0.4) (layer "F.Cu") (net 1))
  (segment (start 150.61 115.53) (end 150.61 115.924) (width 0.4) (layer "F.Cu") (net 1))
  (segment (start 150.5 120.528) (end 148.253 118.281) (width 0.4) (layer "F.Cu") (net 1))
  (segment (start 148.48 118.508) (end 148.253 118.281) (width 0.4) (layer "F.Cu") (net 1))
  (segment (start 148.250001 116.03) (end 148.250001 118.278001) (width 0.4) (layer "F.Cu") (net 1))
  (segment (start 148.250001 118.278001) (end 148.253 118.281) (width 0.4) (layer "F.Cu") (net 1))
  (segment (start 88.263 65.618) (end 88.263 67.187) (width 0.182) (layer "F.Cu") (net 1))
  (segment (start 88.263 67.187) (end 88.25 67.2) (width 0.182) (layer "F.Cu") (net 1))
  (segment (start 93.3265 108.414) (end 93.48 108.096) (width 0.4) (layer "F.Cu") (net 1))
  (segment (start 93.48 108.096) (end 93.89 108.096) (width 0.4) (layer "F.Cu") (net 1))
  (segment (start 93.3265 107.779) (end 93.48 108.096) (width 0.4) (layer "F.Cu") (net 1))
  (segment (start 113.189 75.017) (end 113.189 75.791) (width 0.182) (layer "F.Cu") (net 1))
  (segment (start 91.9815 109.994) (end 92.3665 109.684) (width 0.182) (layer "F.Cu") (net 1))
  (segment (start 90.7865 113.494) (end 91.1715 113.183999) (width 0.182) (layer "F.Cu") (net 1))
  (segment (start 89.8265 112.224) (end 90.3 111.91) (width 0.182) (layer "F.Cu") (net 1))
  (segment (start 93.3265 125.559) (end 93.7115 125.249) (width 0.182) (layer "F.Cu") (net 1))
  (segment (start 93.3265 113.494) (end 93.7115 113.183999) (width 0.182) (layer "F.Cu") (net 1))
  (segment (start 90.7865 116.034) (end 91.1715 115.724) (width 0.182) (layer "F.Cu") (net 1))
  (segment (start 92.84 111.27) (end 93.3265 110.954) (width 0.182) (layer "F.Cu") (net 1))
  (segment (start 89.4415 115.074) (end 89.8265 114.764) (width 0.182) (layer "F.Cu") (net 1))
  (segment (start 90.3 111.27) (end 90.7865 110.954) (width 0.182) (layer "F.Cu") (net 1))
  (segment (start 89.4415 109.994) (end 89.8265 109.684) (width 0.182) (layer "F.Cu") (net 1))
  (segment (start 91.9815 115.074) (end 92.3665 114.764) (width 0.182) (layer "F.Cu") (net 1))
  (segment (start 92.3665 112.224) (end 92.84 111.91) (width 0.182) (layer "F.Cu") (net 1))
  (segment (start 173.65 117.65) (end 173.55 117.65) (width 0.182) (layer "F.Cu") (net 1))
  (segment (start 174 117) (end 174 117.3) (width 0.182) (layer "F.Cu") (net 1))
  (segment (start 174 117.3) (end 173.65 117.65) (width 0.182) (layer "F.Cu") (net 1))
  (segment (start 173.575 117.625) (end 173.55 117.65) (width 0.182) (layer "F.Cu") (net 1))
  (segment (start 174.535 120.95) (end 174.535 120.31) (width 0.182) (layer "F.Cu") (net 1))
  (segment (start 174.535 120.31) (end 174.525 120.3) (width 0.182) (layer "F.Cu") (net 1))
  (segment (start 180.1 121.875) (end 180.1 122.2) (width 0.182) (layer "F.Cu") (net 1))
  (segment (start 180.275 122.375) (end 180.715 122.375) (width 0.182) (layer "F.Cu") (net 1))
  (segment (start 180.1 122.2) (end 180.275 122.375) (width 0.182) (layer "F.Cu") (net 1))
  (segment (start 157.377 100.793) (end 157.87 100.47) (width 0.2) (layer "F.Cu") (net 1))
  (segment (start 180 127.95) (end 180 128.7) (width 0.2) (layer "F.Cu") (net 1))
  (segment (start 113.29 87.72) (end 113.444861 87.874861) (width 0.182) (layer "F.Cu") (net 1))
  (segment (start 113.444861 87.874861) (end 113.841942 87.874861) (width 0.182) (layer "F.Cu") (net 1))
  (segment (start 113.29 87.45) (end 113.29 87.72) (width 0.182) (layer "F.Cu") (net 1))
  (segment (start 92.84 136.029) (end 93.3265 135.719) (width 0.182) (layer "F.Cu") (net 1))
  (segment (start 92.238 104.287) (end 92.3665 103.969) (width 0.4) (layer "F.Cu") (net 1))
  (segment (start 92.238 104.287) (end 92.3665 104.604) (width 0.4) (layer "F.Cu") (net 1))
  (segment (start 89.698 104.287) (end 89.8265 103.969) (width 0.4) (layer "F.Cu") (net 1))
  (segment (start 91.86 104.2865) (end 92.238 104.287) (width 0.4) (layer "F.Cu") (net 1))
  (segment (start 89.698 104.287) (end 89.8265 104.604) (width 0.4) (layer "F.Cu") (net 1))
  (segment (start 90.9 105.5565) (end 91.278 105.557) (width 0.4) (layer "F.Cu") (net 1))
  (segment (start 93.44 105.5565) (end 93.3265 105.874) (width 0.4) (layer "F.Cu") (net 1))
  (segment (start 93.3265 105.239) (end 93.44 105.5565) (width 0.4) (layer "F.Cu") (net 1))
  (segment (start 89.698 106.827) (end 89.8265 106.509) (width 0.4) (layer "F.Cu") (net 1))
  (segment (start 90.9 103.0165) (end 91.278 103.017) (width 0.4) (layer "F.Cu") (net 1))
  (segment (start 89.32 106.8265) (end 89.698 106.827) (width 0.4) (layer "F.Cu") (net 1))
  (segment (start 89.698 106.827) (end 89.8265 107.144) (width 0.4) (layer "F.Cu") (net 1))
  (segment (start 93.44 103.0165) (end 93.818 103.017) (width 0.4) (layer "F.Cu") (net 1))
  (segment (start 89.8265 102.064) (end 90.3 101.75) (width 0.182) (layer "F.Cu") (net 1))
  (segment (start 89.34 101.745) (end 89.8265 101.429) (width 0.182) (layer "F.Cu") (net 1))
  (segment (start 92.3665 102.064) (end 92.84 101.75) (width 0.182) (layer "F.Cu") (net 1))
  (segment (start 91.88 101.745) (end 92.3665 101.429) (width 0.182) (layer "F.Cu") (net 1))
  (segment (start 90.3 126.51) (end 90.7865 126.194) (width 0.182) (layer "F.Cu") (net 1))
  (segment (start 128.97 91.48) (end 128.98 91.47) (width 0.4) (layer "F.Cu") (net 1))
  (segment (start 130.395 79.75) (end 130.395 80.621803) (width 0.182) (layer "F.Cu") (net 1))
  (segment (start 82.325 121.725) (end 82.35 121.75) (width 0.182) (layer "F.Cu") (net 1))
  (segment (start 143.2 67.75) (end 144.0796 67.75) (width 0.182) (layer "F.Cu") (net 1))
  (segment (start 82.28 118.755) (end 82.575 119.05) (width 0.4) (layer "F.Cu") (net 1))
  (segment (start 150.8 62.2) (end 151.73 62.2) (width 0.4) (layer "F.Cu") (net 1))
  (segment (start 90.3 136.664) (end 90.7865 136.354) (width 0.182) (layer "F.Cu") (net 1))
  (segment (start 109.115 117.66) (end 109.125 117.65) (width 0.4) (layer "F.Cu") (net 1))
  (segment (start 156.427001 122.3825) (end 155.940001 122.6945) (width 0.2) (layer "F.Cu") (net 1))
  (segment (start 103.899999 133.2046) (end 103.899999 132.490001) (width 0.182) (layer "F.Cu") (net 1))
  (segment (start 167.37 75.9) (end 168.075 75.9) (width 0.182) (layer "F.Cu") (net 1))
  (segment (start 112.6 139.64) (end 112.6 139.025) (width 0.25) (layer "F.Cu") (net 1))
  (segment (start 135.2 135.915) (end 135.565 135.55) (width 0.4) (layer "F.Cu") (net 1))
  (segment (start 159.927 117.303) (end 160.42 116.98) (width 0.2) (layer "F.Cu") (net 1))
  (segment (start 108.3 136.95) (end 108.3 137.4) (width 0.182) (layer "F.Cu") (net 1))
  (segment (start 93.45 105.5565) (end 93.9285 105.5565) (width 0.4) (layer "F.Cu") (net 1))
  (segment (start 107.25 121.925) (end 108.175 121.925) (width 0.4) (layer "F.Cu") (net 1))
  (segment (start 90.7 68.925) (end 90.72 68.905) (width 0.4) (layer "F.Cu") (net 1))
  (segment (start 121.183 75.073) (end 120.32 74.21) (width 0.182) (layer "F.Cu") (net 1))
  (segment (start 116.750189 122.050189) (end 116.2946 122.050189) (width 0.182) (layer "F.Cu") (net 1))
  (segment (start 156.427001 112.8575) (end 155.940001 113.1695) (width 0.2) (layer "F.Cu") (net 1))
  (segment (start 122.85 114.9) (end 122.85 114.285) (width 0.4) (layer "F.Cu") (net 1))
  (segment (start 104.9 133.2046) (end 104.9 132.501681) (width 0.182) (layer "F.Cu") (net 1))
  (segment (start 129.75 73.6675) (end 129.75 72.8325) (width 0.4) (layer "F.Cu") (net 1))
  (segment (start 139.971787 127.228213) (end 139.971787 126.869767) (width 0.182) (layer "F.Cu") (net 1))
  (segment (start 146.73 116.02) (end 146.73 116.77) (width 0.4) (layer "F.Cu") (net 1))
  (segment (start 158.967001 118.5725) (end 158.480001 118.8845) (width 0.2) (layer "F.Cu") (net 1))
  (segment (start 129.514999 90.700001) (end 129.515 90.7) (width 0.4) (layer "F.Cu") (net 1))
  (segment (start 174.3 142.3175) (end 174.3 142.75) (width 0.4) (layer "F.Cu") (net 1))
  (segment (start 129.275 82.95) (end 129.96 82.95) (width 0.4) (layer "F.Cu") (net 1))
  (segment (start 152.55 111.975) (end 152.975 111.975) (width 0.2) (layer "F.Cu") (net 1))
  (segment (start 120.778803 85.875) (end 122.118942 84.534861) (width 0.4) (layer "F.Cu") (net 1))
  (segment (start 175.3 137.825) (end 175.275 137.8) (width 0.182) (layer "F.Cu") (net 1))
  (segment (start 157.387 119.208) (end 157.88 118.885) (width 0.2) (layer "F.Cu") (net 1))
  (segment (start 90.82 71.417) (end 90.267 71.417) (width 0.4) (layer "F.Cu") (net 1))
  (segment (start 86.763 65.618) (end 86.763 67.187) (width 0.182) (layer "F.Cu") (net 1))
  (segment (start 86.725 118.7) (end 86.1 118.7) (width 0.4) (layer "F.Cu") (net 1))
  (segment (start 108.25 97.275) (end 108.3 97.225) (width 0.4) (layer "F.Cu") (net 1))
  (segment (start 89.8265 133.179) (end 90.3 132.865) (width 0.182) (layer "F.Cu") (net 1))
  (segment (start 159.927 126.828) (end 160.42 126.505) (width 0.2) (layer "F.Cu") (net 1))
  (segment (start 148.345911 94.224035) (end 148.4 94.278124) (width 0.182) (layer "F.Cu") (net 1))
  (segment (start 122.215474 84.631393) (end 122.118942 84.534861) (width 0.4) (layer "F.Cu") (net 1))
  (segment (start 158.967001 131.9075) (end 158.480001 132.2195) (width 0.2) (layer "F.Cu") (net 1))
  (segment (start 128.225 137.175) (end 128.15 137.25) (width 0.2) (layer "F.Cu") (net 1))
  (segment (start 92.84 134.13) (end 93.3265 133.814) (width 0.182) (layer "F.Cu") (net 1))
  (segment (start 190.95 69.15) (end 190.95 68.55) (width 0.2) (layer "F.Cu") (net 1))
  (segment (start 127.7875 92.662501) (end 128.462501 92.662501) (width 0.4) (layer "F.Cu") (net 1))
  (segment (start 188.5 58.67) (end 189.78 59.95) (width 0.4) (layer "F.Cu") (net 1))
  (segment (start 93.3265 100.794) (end 93.44 100.4765) (width 0.4) (layer "F.Cu") (net 1))
  (segment (start 138.185 137.246005) (end 138.185 138) (width 0.4) (layer "F.Cu") (net 1))
  (segment (start 143.980001 82.399999) (end 143.99 82.39) (width 0.182) (layer "F.Cu") (net 1))
  (segment (start 139.25 120.33) (end 139.225 120.355) (width 0.182) (layer "F.Cu") (net 1))
  (segment (start 141.138 74.223) (end 142.313 74.223) (width 0.4) (layer "F.Cu") (net 1))
  (segment (start 105.015 137.95) (end 104.424982 137.95) (width 0.4) (layer "F.Cu") (net 1))
  (segment (start 139.115 136.485) (end 139.4 136.2) (width 0.4) (layer "F.Cu") (net 1))
  (segment (start 141.9 75.575) (end 141.965 75.575) (width 0.4) (layer "F.Cu") (net 1))
  (segment (start 115.3 148.4) (end 115.3 147.2) (width 0.182) (layer "F.Cu") (net 1))
  (segment (start 123.85 75.004) (end 124.04603 75.004) (width 0.4) (layer "F.Cu") (net 1))
  (segment (start 108.175 142.763263) (end 108.17627 142.761993) (width 0.182) (layer "F.Cu") (net 1))
  (segment (start 106.35 103.715) (end 107.01 103.715) (width 0.4) (layer "F.Cu") (net 1))
  (segment (start 93.38 68.875) (end 93.38 69.27) (width 0.4) (layer "F.Cu") (net 1))
  (segment (start 91.9815 117.614) (end 92.3665 117.304) (width 0.182) (layer "F.Cu") (net 1))
  (segment (start 115.3 146.4492) (end 115.3 147.2) (width 0.2) (layer "F.Cu") (net 1))
  (segment (start 151.325 76.9) (end 152.15 76.9) (width 0.182) (layer "F.Cu") (net 1))
  (segment (start 81.259822 121.725) (end 82.325 121.725) (width 0.182) (layer "F.Cu") (net 1))
  (segment (start 140.025 122.45) (end 140.55 122.975) (width 0.182) (layer "F.Cu") (net 1))
  (segment (start 148.48 119.505) (end 148.48 118.508) (width 0.4) (layer "F.Cu") (net 1))
  (segment (start 119.2 81.615919) (end 122.118942 84.534861) (width 0.4) (layer "F.Cu") (net 1))
  (segment (start 112.015 123.535) (end 112 123.55) (width 0.4) (layer "F.Cu") (net 1))
  (segment (start 152.55 108.875) (end 152.975 108.875) (width 0.2) (layer "F.Cu") (net 1))
  (segment (start 126.4 96.2) (end 126.4 96.954998) (width 0.4) (layer "F.Cu") (net 1))
  (segment (start 111.11 92.24) (end 110.63 91.76) (width 0.182) (layer "F.Cu") (net 1))
  (segment (start 117.4 118.3) (end 117.4 118.785) (width 0.4) (layer "F.Cu") (net 1))
  (segment (start 90.267 71.417) (end 90.25 71.4) (width 0.4) (layer "F.Cu") (net 1))
  (segment (start 108.82 143.775) (end 109.29 143.775) (width 0.182) (layer "F.Cu") (net 1))
  (segment (start 125.21 96.81) (end 125.21 97.328) (width 0.4) (layer "F.Cu") (net 1))
  (segment (start 111.455 92.24) (end 111.11 92.24) (width 0.182) (layer "F.Cu") (net 1))
  (segment (start 99.61 98.51) (end 99.6 98.5) (width 0.4) (layer "F.Cu") (net 1))
  (segment (start 129.5 89.999999) (end 129.5 90.685) (width 0.4) (layer "F.Cu") (net 1))
  (segment (start 89.213 104.287) (end 89.2 104.3) (width 0.4) (layer "F.Cu") (net 1))
  (segment (start 86.635 119.6) (end 86.1 119.6) (width 0.4) (layer "F.Cu") (net 1))
  (segment (start 104.4 133.2046) (end 104.4 132.5) (width 0.182) (layer "F.Cu") (net 1))
  (segment (start 120.1 82.515919) (end 122.118942 84.534861) (width 0.4) (layer "F.Cu") (net 1))
  (segment (start 108.995 141.2) (end 109.597168 141.2) (width 0.182) (layer "F.Cu") (net 1))
  (segment (start 126.4 96.954998) (end 126.405002 96.96) (width 0.4) (layer "F.Cu") (net 1))
  (segment (start 112.125 96.49) (end 112.125 96.025) (width 0.4) (layer "F.Cu") (net 1))
  (segment (start 143.983728 115.9) (end 143.583728 115.5) (width 0.182) (layer "F.Cu") (net 1))
  (segment (start 152.975 111.975) (end 153 111.95) (width 0.2) (layer "F.Cu") (net 1))
  (segment (start 158.967001 128.0975) (end 158.480001 128.4095) (width 0.2) (layer "F.Cu") (net 1))
  (segment (start 89.401 99.524) (end 89.4 99.525) (width 0.4) (layer "F.Cu") (net 1))
  (segment (start 126.407018 88.231393) (end 125.815474 88.231393) (width 0.4) (layer "F.Cu") (net 1))
  (segment (start 156.427001 114.7625) (end 155.940001 115.0745) (width 0.2) (layer "F.Cu") (net 1))
  (segment (start 117.7 87.575) (end 119.078803 87.575) (width 0.4) (layer "F.Cu") (net 1))
  (segment (start 143.215 92.199998) (end 143.215002 92.2) (width 0.4) (layer "F.Cu") (net 1))
  (segment (start 91.75 69.0625) (end 91.75 68.775) (width 0.2) (layer "F.Cu") (net 1))
  (segment (start 113.44486 86.87486) (end 113.32 86.75) (width 0.182) (layer "F.Cu") (net 1))
  (segment (start 93.3265 123.654) (end 93.6365 123.344) (width 0.182) (layer "F.Cu") (net 1))
  (segment (start 143.149916 125.167314) (end 143.149916 124.499916) (width 0.182) (layer "F.Cu") (net 1))
  (segment (start 159.927 124.923) (end 160.42 124.6) (width 0.2) (layer "F.Cu") (net 1))
  (segment (start 91.86 106.8265) (end 92.238 106.827) (width 0.4) (layer "F.Cu") (net 1))
  (segment (start 117.4 118.785) (end 117.385 118.8) (width 0.4) (layer "F.Cu") (net 1))
  (segment (start 142.775 87.5) (end 142.775 87.428175) (width 0.4) (layer "F.Cu") (net 1))
  (segment (start 157.387 113.493) (end 157.88 113.17) (width 0.2) (layer "F.Cu") (net 1))
  (segment (start 180 57.9) (end 182.4 55.5) (width 0.4) (layer "F.Cu") (net 1))
  (segment (start 125.815474 88.231393) (end 122.118942 84.534861) (width 0.4) (layer "F.Cu") (net 1))
  (segment (start 107.6 97.95) (end 108.295 98.645) (width 0.4) (layer "F.Cu") (net 1))
  (segment (start 125.75 113.2) (end 126.45 113.2) (width 0.4) (layer "F.Cu") (net 1))
  (segment (start 147.87 126.345) (end 147.79722 126.41778) (width 0.4) (layer "F.Cu") (net 1))
  (segment (start 156.427001 131.9075) (end 155.940001 132.2195) (width 0.2) (layer "F.Cu") (net 1))
  (segment (start 125.21 97.328) (end 125.134 97.404) (width 0.4) (layer "F.Cu") (net 1))
  (segment (start 107.2 97.95) (end 107.6 97.95) (width 0.4) (layer "F.Cu") (net 1))
  (segment (start 93.3265 100.159) (end 93.44 100.4765) (width 0.4) (layer "F.Cu") (net 1))
  (segment (start 152.975 108.875) (end 153 108.85) (width 0.2) (layer "F.Cu") (net 1))
  (segment (start 151.421142 126.638909) (end 151.41906 126.636827) (width 0.4) (layer "F.Cu") (net 1))
  (segment (start 111.103011 142.903011) (end 111.103011 142.9) (width 0.182) (layer "F.Cu") (net 1))
  (segment (start 89.4415 122.694) (end 89.8265 122.384) (width 0.182) (layer "F.Cu") (net 1))
  (segment (start 94.35 69.25) (end 94.15 69.45) (width 0.4) (layer "F.Cu") (net 1))
  (segment (start 111 123.325) (end 111 122.685) (width 0.4) (layer "F.Cu") (net 1))
  (segment (start 124.425474 86.841393) (end 122.118942 84.534861) (width 0.4) (layer "F.Cu") (net 1))
  (segment (start 145.83 116.03) (end 145.99 116.03) (width 0.4) (layer "F.Cu") (net 1))
  (segment (start 86 68.2825) (end 86 67.825) (width 0.4) (layer "F.Cu") (net 1))
  (segment (start 113.4 85.41) (end 113.4 85.15) (width 0.182) (layer "F.Cu") (net 1))
  (segment (start 139.625 119.675) (end 139.7 119.6) (width 0.182) (layer "F.Cu") (net 1))
  (segment (start 176.025 137.825) (end 175.3 137.825) (width 0.182) (layer "F.Cu") (net 1))
  (segment (start 182.4 55.5) (end 188.5 55.5) (width 0.4) (layer "F.Cu") (net 1))
  (segment (start 113.38 85.43) (end 113.4 85.41) (width 0.182) (layer "F.Cu") (net 1))
  (segment (start 140.67 121.8) (end 141.225 121.8) (width 0.182) (layer "F.Cu") (net 1))
  (segment (start 90.7865 100.159) (end 90.9 100.4765) (width 0.4) (layer "F.Cu") (net 1))
  (segment (start 159.927 119.208) (end 160.42 118.885) (width 0.2) (layer "F.Cu") (net 1))
  (segment (start 84.385 147.6) (end 84.9 147.6) (width 0.182) (layer "F.Cu") (net 1))
  (segment (start 107.55 138.996165) (end 107.44451 138.890675) (width 0.182) (layer "F.Cu") (net 1))
  (segment (start 125.125 150.48) (end 125.125 149.325) (width 0.4) (layer "F.Cu") (net 1))
  (segment (start 142.275 109.575) (end 142.7 109.575) (width 0.4) (layer "F.Cu") (net 1))
  (segment (start 148.26 118.3) (end 148.26 119.285) (width 0.4) (layer "F.Cu") (net 1))
  (segment (start 113.875 123.375) (end 113.45 123.375) (width 0.2) (layer "F.Cu") (net 1))
  (segment (start 86.763 67.187) (end 86.75 67.2) (width 0.182) (layer "F.Cu") (net 1))
  (segment (start 157.387 126.828) (end 157.88 126.505) (width 0.2) (layer "F.Cu") (net 1))
  (segment (start 135.565 135.55) (end 135.74 135.55) (width 0.4) (layer "F.Cu") (net 1))
  (segment (start 113.434862 88.874862) (end 113.826942 88.874862) (width 0.182) (layer "F.Cu") (net 1))
  (segment (start 110.91 96.465) (end 110.91 96.56) (width 0.4) (layer "F.Cu") (net 1))
  (segment (start 149 123.95) (end 149 124.717767) (width 0.4) (layer "F.Cu") (net 1))
  (segment (start 120.1 80.1) (end 120.1 82.515919) (width 0.4) (layer "F.Cu") (net 1))
  (segment (start 120.14 76.56) (end 120.45 76.25) (width 0.182) (layer "F.Cu") (net 1))
  (segment (start 122.022408 84.631395) (end 122.118942 84.534861) (width 0.4) (layer "F.Cu") (net 1))
  (segment (start 100.125 94.975) (end 100.125 94.1) (width 0.4) (layer "F.Cu") (net 1))
  (segment (start 130.864862 88.724862) (end 131.175 89.035) (width 0.4) (layer "F.Cu") (net 1))
  (segment (start 90.7865 105.239) (end 90.9 105.5565) (width 0.4) (layer "F.Cu") (net 1))
  (segment (start 129.5 91.4) (end 129.5 90.715) (width 0.4) (layer "F.Cu") (net 1))
  (segment (start 104.285001 95.714999) (end 104.3 95.7) (width 0.4) (layer "F.Cu") (net 1))
  (segment (start 149.453 122.156) (end 149.453 122.858) (width 0.182) (layer "F.Cu") (net 1))
  (segment (start 142.7 127.5) (end 143.075 127.5) (width 0.182) (layer "F.Cu") (net 1))
  (segment (start 92.84 132.225) (end 93.3265 131.909) (width 0.182) (layer "F.Cu") (net 1))
  (segment (start 150.5 117.86) (end 148.7 117.86) (width 0.4) (layer "F.Cu") (net 1))
  (segment (start 93.3265 103.334) (end 93.44 103.0165) (width 0.4) (layer "F.Cu") (net 1))
  (segment (start 90.3 128.415) (end 90.7865 128.099) (width 0.182) (layer "F.Cu") (net 1))
  (segment (start 91.9815 122.694) (end 92.3665 122.384) (width 0.182) (layer "F.Cu") (net 1))
  (segment (start 141.98 142.365) (end 141.785 142.56) (width 0.2) (layer "F.Cu") (net 1))
  (segment (start 156.427 104.603) (end 155.94 104.915) (width 0.2) (layer "F.Cu") (net 1))
  (segment (start 159.927 113.493) (end 160.42 113.17) (width 0.2) (layer "F.Cu") (net 1))
  (segment (start 128.75 137.175) (end 128.225 137.175) (width 0.2) (layer "F.Cu") (net 1))
  (segment (start 158.967 104.603) (end 158.48 104.915) (width 0.2) (layer "F.Cu") (net 1))
  (segment (start 143.583728 115.5) (end 143.149996 115.5) (width 0.182) (layer "F.Cu") (net 1))
  (segment (start 110.4 71.65) (end 110.4 72.8825) (width 0.4) (layer "F.Cu") (net 1))
  (segment (start 142.1 109.575) (end 142.275 109.575) (width 0.4) (layer "F.Cu") (net 1))
  (segment (start 125.1 96.7) (end 125.21 96.81) (width 0.4) (layer "F.Cu") (net 1))
  (segment (start 148 142.935) (end 147.985 142.95) (width 0.4) (layer "F.Cu") (net 1))
  (segment (start 126.407018 86.841393) (end 124.425474 86.841393) (width 0.4) (layer "F.Cu") (net 1))
  (segment (start 157.387 111.588) (end 157.88 111.265) (width 0.2) (layer "F.Cu") (net 1))
  (segment (start 141.225 121.8) (end 141.425 122) (width 0.182) (layer "F.Cu") (net 1))
  (segment (start 140.913175 86.85) (end 140.919953 86.843222) (width 0.182) (layer "F.Cu") (net 1))
  (segment (start 148.9 94.594946) (end 148.9 94.924998) (width 0.182) (layer "F.Cu") (net 1))
  (segment (start 113.841939 86.87486) (end 113.44486 86.87486) (width 0.182) (layer "F.Cu") (net 1))
  (segment (start 108.624998 142.069998) (end 108.624998 142.24) (width 0.182) (layer "F.Cu") (net 1))
  (segment (start 147.58 118.98) (end 148.26 118.3) (width 0.4) (layer "F.Cu") (net 1))
  (segment (start 92.3665 119.844) (end 92.84 119.53) (width 0.182) (layer "F.Cu") (net 1))
  (segment (start 138.2075 137.223505) (end 138.185 137.246005) (width 0.4) (layer "F.Cu") (net 1))
  (segment (start 92.3665 135.084) (end 92.84 134.77) (width 0.182) (layer "F.Cu") (net 1))
  (segment (start 157.387 103.333) (end 157.88 103.01) (width 0.2) (layer "F.Cu") (net 1))
  (segment (start 156.427 107.143) (end 155.94 107.455) (width 0.2) (layer "F.Cu") (net 1))
  (segment (start 154.591621 90.117588) (end 155.192588 90.117588) (width 0.2) (layer "F.Cu") (net 1))
  (segment (start 120.21241 88.822937) (end 120.21241 86.441393) (width 0.4) (layer "F.Cu") (net 1))
  (segment (start 86.805 119.77) (end 86.635 119.6) (width 0.4) (layer "F.Cu") (net 1))
  (segment (start 128.525334 150.604218) (end 128.525334 149.324666) (width 0.4) (layer "F.Cu") (net 1))
  (segment (start 159.927 136.353) (end 160.42 136.03) (width 0.2) (layer "F.Cu") (net 1))
  (segment (start 108.295 98.645) (end 108.295 99.225) (width 0.4) (layer "F.Cu") (net 1))
  (segment (start 139.872435 113.209117) (end 139.872435 113.972792) (width 0.182) (layer "F.Cu") (net 1))
  (segment (start 159.927001 133.8125) (end 160.420001 133.4895) (width 0.2) (layer "F.Cu") (net 1))
  (segment (start 120.32 74.21) (end 120.32 74.1) (width 0.182) (layer "F.Cu") (net 1))
  (segment (start 149.899 59.349) (end 149.899 60.514) (width 0.4) (layer "F.Cu") (net 1))
  (segment (start 137.05 124.374999) (end 137.474999 124.374999) (width 0.182) (layer "F.Cu") (net 1))
  (segment (start 125.5 98.9) (end 125.5 98.89) (width 0.109) (layer "F.Cu") (net 1))
  (segment (start 114.149811 122.6946) (end 114.149811 123.100189) (width 0.2) (layer "F.Cu") (net 1))
  (segment (start 139.45 127.4) (end 139.8 127.4) (width 0.182) (layer "F.Cu") (net 1))
  (segment (start 156.427001 132.5425) (end 156.920001 132.2195) (width 0.2) (layer "F.Cu") (net 1))
  (segment (start 86.805 118.78) (end 86.725 118.7) (width 0.4) (layer "F.Cu") (net 1))
  (segment (start 157.387 105.873) (end 157.88 105.55) (width 0.2) (layer "F.Cu") (net 1))
  (segment (start 90.7 69.5) (end 90.7 68.925) (width 0.4) (layer "F.Cu") (net 1))
  (segment (start 147.58 120.55) (end 147.58 118.98) (width 0.4) (layer "F.Cu") (net 1))
  (segment (start 129.75 72.8325) (end 129.75 71.7) (width 0.4) (layer "F.Cu") (net 1))
  (segment (start 107.35 97.275) (end 108.25 97.275) (width 0.4) (layer "F.Cu") (net 1))
  (segment (start 138.8 136.485) (end 139.115 136.485) (width 0.4) (layer "F.Cu") (net 1))
  (segment (start 139.825 116.08) (end 139.825 115.325) (width 0.182) (layer "F.Cu") (net 1))
  (segment (start 139.625 120.355) (end 139.625 119.675) (width 0.182) (layer "F.Cu") (net 1))
  (segment (start 118.82241 87.831393) (end 122.118942 84.534861) (width 0.4) (layer "F.Cu") (net 1))
  (segment (start 91.75 67.95) (end 91.55 67.75) (width 0.2) (layer "F.Cu") (net 1))
  (segment (start 149.453 122.858) (end 149.495 122.9) (width 0.182) (layer "F.Cu") (net 1))
  (segment (start 98.625 144.125) (end 98.8 144.3) (width 0.182) (layer "F.Cu") (net 1))
  (segment (start 126.407018 83.241393) (end 123.41241 83.241393) (width 0.4) (layer "F.Cu") (net 1))
  (segment (start 92.3665 131.274) (end 92.84 130.96) (width 0.182) (layer "F.Cu") (net 1))
  (segment (start 155.217588 89.167588) (end 155.225 89.175) (width 0.2) (layer "F.Cu") (net 1))
  (segment (start 86.71 116.9) (end 86.1 116.9) (width 0.4) (layer "F.Cu") (net 1))
  (segment (start 78.9 89.625) (end 78.385 89.625) (width 0.4) (layer "F.Cu") (net 1))
  (segment (start 92.3665 129.369) (end 92.84 129.055) (width 0.182) (layer "F.Cu") (net 1))
  (segment (start 83.425 119.314999) (end 83.389999 119.35) (width 0.2) (layer "F.Cu") (net 1))
  (segment (start 159.927 123.018) (end 160.42 122.695) (width 0.2) (layer "F.Cu") (net 1))
  (segment (start 113.4 85.15) (end 113.525138 85.024862) (width 0.182) (layer "F.Cu") (net 1))
  (segment (start 148.4 94.278124) (end 148.4 94.606802) (width 0.182) (layer "F.Cu") (net 1))
  (segment (start 139.25 119.6) (end 139.25 120.33) (width 0.182) (layer "F.Cu") (net 1))
  (segment (start 124.215474 82.438329) (end 122.118942 84.534861) (width 0.4) (layer "F.Cu") (net 1))
  (segment (start 86.8 116.81) (end 86.71 116.9) (width 0.4) (layer "F.Cu") (net 1))
  (segment (start 114 119.425) (end 113.525 119.425) (width 0.182) (layer "F.Cu") (net 1))
  (segment (start 119.903803 86.75) (end 122.118942 84.534861) (width 0.4) (layer "F.Cu") (net 1))
  (segment (start 104.424982 137.95) (end 104.424973 137.949991) (width 0.4) (layer "F.Cu") (net 1))
  (segment (start 90.7865 123.654) (end 91.111371 123.329129) (width 0.182) (layer "F.Cu") (net 1))
  (segment (start 158.967001 116.6675) (end 158.480001 116.9795) (width 0.2) (layer "F.Cu") (net 1))
  (segment (start 124.215474 80.249663) (end 124.215474 82.438329) (width 0.4) (layer "F.Cu") (net 1))
  (segment (start 138.825 119.725) (end 138.95 119.6) (width 0.182) (layer "F.Cu") (net 1))
  (segment (start 110.4 71.7) (end 110.4 71.65) (width 0.4) (layer "F.Cu") (net 1))
  (segment (start 156.427001 120.4775) (end 155.940001 120.7895) (width 0.2) (layer "F.Cu") (net 1))
  (segment (start 91.111371 123.329129) (end 91.182531 123.329129) (width 0.182) (layer "F.Cu") (net 1))
  (segment (start 158.967001 122.3825) (end 158.480001 122.6945) (width 0.2) (layer "F.Cu") (net 1))
  (segment (start 128.315 91.48) (end 128.97 91.48) (width 0.4) (layer "F.Cu") (net 1))
  (segment (start 130.391942 80.624861) (end 130.391942 81.524861) (width 0.182) (layer "F.Cu") (net 1))
  (segment (start 120.1 77.15) (end 120.1 76.57) (width 0.182) (layer "F.Cu") (net 1))
  (segment (start 93.38 69.27) (end 93.25 69.4) (width 0.4) (layer "F.Cu") (net 1))
  (segment (start 125.7 130.775) (end 126.325 130.775) (width 0.4) (layer "F.Cu") (net 1))
  (segment (start 90.9 105.5565) (end 90.7865 105.874) (width 0.4) (layer "F.Cu") (net 1))
  (segment (start 186.545355 130.496751) (end 186.545355 129.904645) (width 0.182) (layer "F.Cu") (net 1))
  (segment (start 156.427001 126.1925) (end 155.940001 126.5045) (width 0.2) (layer "F.Cu") (net 1))
  (segment (start 118.4 80.1) (end 118.4 80.815919) (width 0.4) (layer "F.Cu") (net 1))
  (segment (start 137.425 127.575) (end 137.6 127.4) (width 0.182) (layer "F.Cu") (net 1))
  (segment (start 83.425 118.375001) (end 83.425 119.314999) (width 0.2) (layer "F.Cu") (net 1))
  (segment (start 141.07637 144.25137) (end 141.07637 143.415753) (width 0.4) (layer "F.Cu") (net 1))
  (segment (start 122.468 75.073) (end 123.607 75.073) (width 0.4) (layer "F.Cu") (net 1))
  (segment (start 139.325 127.3) (end 139.35 127.3) (width 0.182) (layer "F.Cu") (net 1))
  (segment (start 93.9285 105.5565) (end 93.948 105.537) (width 0.4) (layer "F.Cu") (net 1))
  (segment (start 147.55 143.385) (end 147.985 142.95) (width 0.4) (layer "F.Cu") (net 1))
  (segment (start 119.078803 87.575) (end 122.118942 84.534861) (width 0.4) (layer "F.Cu") (net 1))
  (segment (start 156.427001 135.0825) (end 156.920001 134.7595) (width 0.2) (layer "F.Cu") (net 1))
  (segment (start 151.9 107.9) (end 151.4 107.9) (width 0.182) (layer "F.Cu") (net 1))
  (segment (start 128.525334 149.324666) (end 128.55 149.3) (width 0.4) (layer "F.Cu") (net 1))
  (segment (start 111.1 96.75) (end 111.1 97.05) (width 0.4) (layer "F.Cu") (net 1))
  (segment (start 138.18 121) (end 137.535 121) (width 0.182) (layer "F.Cu") (net 1))
  (segment (start 119.3 119.95) (end 119.875 119.95) (width 0.4) (layer "F.Cu") (net 1))
  (segment (start 121.653803 85) (end 122.118942 84.534861) (width 0.4) (layer "F.Cu") (net 1))
  (segment (start 82.575 119.45) (end 82.575 119.75) (width 0.4) (layer "F.Cu") (net 1))
  (segment (start 89.4415 117.614) (end 89.8265 117.304) (width 0.182) (layer "F.Cu") (net 1))
  (segment (start 146.7 62.65) (end 146.7 62) (width 0.182) (layer "F.Cu") (net 1))
  (segment (start 157.387001 133.8125) (end 157.880001 133.4895) (width 0.2) (layer "F.Cu") (net 1))
  (segment (start 117.7 85.875) (end 120.778803 85.875) (width 0.4) (layer "F.Cu") (net 1))
  (segment (start 139.8 127.4) (end 139.971787 127.228213) (width 0.182) (layer "F.Cu") (net 1))
  (segment (start 141.625 74.225) (end 141.375 74.475) (width 0.4) (layer "F.Cu") (net 1))
  (segment (start 133.6 137.4) (end 133.978761 137.021239) (width 0.4) (layer "F.Cu") (net 1))
  (segment (start 143.2 82.399999) (end 143.980001 82.399999) (width 0.182) (layer "F.Cu") (net 1))
  (segment (start 113.525138 85.024862) (end 113.921942 85.024862) (width 0.182) (layer "F.Cu") (net 1))
  (segment (start 90.7865 100.794) (end 90.9 100.4765) (width 0.4) (layer "F.Cu") (net 1))
  (segment (start 139.425 116.08) (end 139.425 115.275) (width 0.182) (layer "F.Cu") (net 1))
  (segment (start 85.263 65.618) (end 85.263 67.137) (width 0.182) (layer "F.Cu") (net 1))
  (segment (start 158.967001 124.2875) (end 158.480001 124.5995) (width 0.2) (layer "F.Cu") (net 1))
  (segment (start 92.3665 99.524) (end 92.8 99.225) (width 0.4) (layer "F.Cu") (net 1))
  (segment (start 123.075 129.815) (end 123.075 129.225) (width 0.4) (layer "F.Cu") (net 1))
  (segment (start 117.7 86.75) (end 119.903803 86.75) (width 0.4) (layer "F.Cu") (net 1))
  (segment (start 149.899 60.514) (end 149.985 60.6) (width 0.4) (layer "F.Cu") (net 1))
  (segment (start 158.967001 112.8575) (end 158.480001 113.1695) (width 0.2) (layer "F.Cu") (net 1))
  (segment (start 93.6365 123.344) (end 93.71049 123.344) (width 0.182) (layer "F.Cu") (net 1))
  (segment (start 141.15 144.325) (end 141.07637 144.25137) (width 0.4) (layer "F.Cu") (net 1))
  (segment (start 82.575 119.05) (end 82.575 119.45) (width 0.4) (layer "F.Cu") (net 1))
  (segment (start 136.475 150.48) (end 136.475 149.325) (width 0.4) (layer "F.Cu") (net 1))
  (segment (start 146.73 116.77) (end 148.26 118.3) (width 0.4) (layer "F.Cu") (net 1))
  (segment (start 142.775 87.428175) (end 143.357453 86.845722) (width 0.4) (layer "F.Cu") (net 1))
  (segment (start 141.375 74.475) (end 141.375 75.05) (width 0.4) (layer "F.Cu") (net 1))
  (segment (start 180 59.7) (end 180 57.9) (width 0.4) (layer "F.Cu") (net 1))
  (segment (start 178.11 130.6) (end 178.8 130.6) (width 0.182) (layer "F.Cu") (net 1))
  (segment (start 188.5 55.5) (end 188.5 58.67) (width 0.4) (layer "F.Cu") (net 1))
  (segment (start 107.13 144.175) (end 106.125 144.175) (width 0.182) (layer "F.Cu") (net 1))
  (segment (start 159.927 115.398) (end 160.42 115.075) (width 0.2) (layer "F.Cu") (net 1))
  (segment (start 78.375 88.35) (end 77.835 88.35) (width 0.4) (layer "F.Cu") (net 1))
  (segment (start 117.725 122.595) (end 117.295 122.595) (width 0.182) (layer "F.Cu") (net 1))
  (segment (start 139.7 119.6) (end 140.15 119.6) (width 0.182) (layer "F.Cu") (net 1))
  (segment (start 107.95 138.95) (end 108 138.9) (width 0.182) (layer "F.Cu") (net 1))
  (segment (start 151.85 67.2) (end 151.225 67.2) (width 0.182) (layer "F.Cu") (net 1))
  (segment (start 190.95 68.55) (end 191.2 68.3) (width 0.2) (layer "F.Cu") (net 1))
  (segment (start 173.25 133.124999) (end 173.25 133.615) (width 0.182) (layer "F.Cu") (net 1))
  (segment (start 113.285 88.435) (end 113.285 88.725) (width 0.182) (layer "F.Cu") (net 1))
  (segment (start 143.195 118.45) (end 142.875002 118.45) (width 0.182) (layer "F.Cu") (net 1))
  (segment (start 86 69.1175) (end 86 69.799976) (width 0.4) (layer "F.Cu") (net 1))
  (segment (start 157.387001 133.1775) (end 156.900001 133.4895) (width 0.2) (layer "F.Cu") (net 1))
  (segment (start 148.48 120.55) (end 148.48 119.505) (width 0.4) (layer "F.Cu") (net 1))
  (segment (start 152.15 76.9) (end 152.525 77.275) (width 0.182) (layer "F.Cu") (net 1))
  (segment (start 93.3265 102.699) (end 93.44 103.0165) (width 0.4) (layer "F.Cu") (net 1))
  (segment (start 86.05 114.15) (end 86.7894 114.8894) (width 0.182) (layer "F.Cu") (net 1))
  (segment (start 120.1 76.57) (end 120.11 76.56) (width 0.182) (layer "F.Cu") (net 1))
  (segment (start 143.215 91.514035) (end 143.215 92.199998) (width 0.4) (layer "F.Cu") (net 1))
  (segment (start 89.8265 135.084) (end 90.3 134.77) (width 0.182) (layer "F.Cu") (net 1))
  (segment (start 137.05 127.575) (end 137.425 127.575) (width 0.182) (layer "F.Cu") (net 1))
  (segment (start 128.85 90.700001) (end 129.514999 90.700001) (width 0.4) (layer "F.Cu") (net 1))
  (segment (start 124.04603 75.004) (end 125.50003 73.55) (width 0.4) (layer "F.Cu") (net 1))
  (segment (start 143.075 127.5) (end 143.149916 127.425084) (width 0.182) (layer "F.Cu") (net 1))
  (segment (start 130.395 78.9) (end 130.395 79.75) (width 0.182) (layer "F.Cu") (net 1))
  (segment (start 159.927001 131.2725) (end 160.420001 130.9495) (width 0.2) (layer "F.Cu") (net 1))
  (segment (start 119.206942 76.239861) (end 119.789861 76.239861) (width 0.182) (layer "F.Cu") (net 1))
  (segment (start 142.23732 126.212314) (end 142.075 126.049994) (width 0.182) (layer "F.Cu") (net 1))
  (segment (start 81.6 148.15) (end 81.6 149.3) (width 0.182) (layer "F.Cu") (net 1))
  (segment (start 157.387001 135.7175) (end 156.900001 136.0295) (width 0.2) (layer "F.Cu") (net 1))
  (segment (start 112.6 139.025) (end 112.725 138.9) (width 0.25) (layer "F.Cu") (net 1))
  (segment (start 112.775 120.35) (end 112.775 120.175) (width 0.182) (layer "F.Cu") (net 1))
  (segment (start 78.415 90.9) (end 77.875 90.9) (width 0.4) (layer "F.Cu") (net 1))
  (segment (start 183.7 118.15) (end 183.7 118.8) (width 0.182) (layer "F.Cu") (net 1))
  (segment (start 137.625 122.06) (end 137.265 122.06) (width 0.182) (layer "F.Cu") (net 1))
  (segment (start 146.049684 141.939684) (end 146.05 141.94) (width 0.4) (layer "F.Cu") (net 1))
  (segment (start 90.7865 103.334) (end 90.9 103.0165) (width 0.4) (layer "F.Cu") (net 1))
  (segment (start 114.149811 119.574811) (end 114 119.425) (width 0.182) (layer "F.Cu") (net 1))
  (segment (start 157.387 117.303) (end 157.88 116.98) (width 0.2) (layer "F.Cu") (net 1))
  (segment (start 89.763 65.618) (end 89.763 67.187) (width 0.182) (layer "F.Cu") (net 1))
  (segment (start 107.55 139.755) (end 107.55 138.996165) (width 0.182) (layer "F.Cu") (net 1))
  (segment (start 86.815 117.8) (end 86.1 117.8) (width 0.4) (layer "F.Cu") (net 1))
  (segment (start 186.545355 129.904645) (end 186.55 129.9) (width 0.182) (layer "F.Cu") (net 1))
  (segment (start 149.83 119.87) (end 148.26 118.3) (width 0.4) (layer "F.Cu") (net 1))
  (segment (start 137.7 124.6) (end 137.7 124.7) (width 0.182) (layer "F.Cu") (net 1))
  (segment (start 129.5 90.685) (end 129.515 90.7) (width 0.4) (layer "F.Cu") (net 1))
  (segment (start 118.82241 88.822937) (end 118.82241 87.831393) (width 0.4) (layer "F.Cu") (net 1))
  (segment (start 128.5 94.9) (end 127.785 94.9) (width 0.4) (layer "F.Cu") (net 1))
  (segment (start 136.475 149.325) (end 136.45 149.3) (width 0.4) (layer "F.Cu") (net 1))
  (segment (start 138.95 119.6) (end 139.25 119.6) (width 0.182) (layer "F.Cu") (net 1))
  (segment (start 157.387 115.398) (end 157.88 115.075) (width 0.2) (layer "F.Cu") (net 1))
  (segment (start 111.115 142.915) (end 111.103011 142.903011) (width 0.182) (layer "F.Cu") (net 1))
  (segment (start 149.985 61.385) (end 150.8 62.2) (width 0.4) (layer "F.Cu") (net 1))
  (segment (start 183.6 135.1) (end 183.6 134.425) (width 0.182) (layer "F.Cu") (net 1))
  (segment (start 97.25 149.3) (end 98.025 149.3) (width 0.4) (layer "F.Cu") (net 1))
  (segment (start 92.238 106.827) (end 92.3665 106.509) (width 0.4) (layer "F.Cu") (net 1))
  (segment (start 110.63 91.22) (end 110.62 91.21) (width 0.182) (layer "F.Cu") (net 1))
  (segment (start 141.965 76.31) (end 141.95 76.325) (width 0.4) (layer "F.Cu") (net 1))
  (segment (start 112.61 123.535) (end 112.015 123.535) (width 0.4) (layer "F.Cu") (net 1))
  (segment (start 144.385 118.3) (end 143.345 118.3) (width 0.182) (layer "F.Cu") (net 1))
  (segment (start 92.3665 127.464) (end 92.84 127.15) (width 0.182) (layer "F.Cu") (net 1))
  (segment (start 123.412408 88.822937) (end 123.412408 85.828327) (width 0.4) (layer "F.Cu") (net 1))
  (segment (start 125.125 149.325) (end 125.15 149.3) (width 0.4) (layer "F.Cu") (net 1))
  (segment (start 89.763 67.187) (end 89.75 67.2) (width 0.182) (layer "F.Cu") (net 1))
  (segment (start 108.175 143.53) (end 108.175 142.763263) (width 0.182) (layer "F.Cu") (net 1))
  (segment (start 141.98 142.0745) (end 141.98 142.365) (width 0.2) (layer "F.Cu") (net 1))
  (segment (start 90.3 118.89) (end 90.7865 118.574) (width 0.182) (layer "F.Cu") (net 1))
  (segment (start 144.491 62.649) (end 144.491 62.109) (width 0.182) (layer "F.Cu") (net 1))
  (segment (start 172.8 133.75) (end 173.115 133.75) (width 0.182) (layer "F.Cu") (net 1))
  (segment (start 106.125 144.175) (end 105.95 144) (width 0.182) (layer "F.Cu") (net 1))
  (segment (start 137.535 121) (end 137.275 120.74) (width 0.182) (layer "F.Cu") (net 1))
  (segment (start 153.577977 125.475) (end 153.591813 125.488836) (width 0.4) (layer "F.Cu") (net 1))
  (segment (start 90.3 132.225) (end 90.7865 131.909) (width 0.182) (layer "F.Cu") (net 1))
  (segment (start 81.5125 136) (end 80.7 136) (width 0.4) (layer "F.Cu") (net 1))
  (segment (start 159.927 128.733) (end 160.42 128.41) (width 0.2) (layer "F.Cu") (net 1))
  (segment (start 148.4 94.606802) (end 148.4 94.925) (width 0.182) (layer "F.Cu") (net 1))
  (segment (start 142.315 74.225) (end 141.625 74.225) (width 0.4) (layer "F.Cu") (net 1))
  (segment (start 123.412408 85.828327) (end 122.118942 84.534861) (width 0.4) (layer "F.Cu") (net 1))
  (segment (start 153.118 70.752) (end 153.2 70.834) (width 0.182) (layer "F.Cu") (net 1))
  (segment (start 137.474999 124.374999) (end 137.7 124.6) (width 0.182) (layer "F.Cu") (net 1))
  (segment (start 89.905 73.232) (end 90.482 73.232) (width 0.4) (layer "F.Cu") (net 1))
  (segment (start 110.91 96.56) (end 111.1 96.75) (width 0.4) (layer "F.Cu") (net 1))
  (segment (start 119.034081 81.45) (end 122.118942 84.534861) (width 0.4) (layer "F.Cu") (net 1))
  (segment (start 92.84 120.795) (end 93.3265 120.479) (width 0.182) (layer "F.Cu") (net 1))
  (segment (start 158.967001 114.7625) (end 158.480001 115.0745) (width 0.2) (layer "F.Cu") (net 1))
  (segment (start 158.967001 135.0825) (end 159.460001 134.7595) (width 0.2) (layer "F.Cu") (net 1))
  (segment (start 173.25 133.615) (end 173.115 133.75) (width 0.182) (layer "F.Cu") (net 1))
  (segment (start 155.228 70.752) (end 155 70.98) (width 0.182) (layer "F.Cu") (net 1))
  (segment (start 108.175 121.925) (end 108.2 121.9) (width 0.4) (layer "F.Cu") (net 1))
  (segment (start 138.18 121.8) (end 137.885 121.8) (width 0.182) (layer "F.Cu") (net 1))
  (segment (start 112.974811 120.549811) (end 112.775 120.35) (width 0.182) (layer "F.Cu") (net 1))
  (segment (start 139.825 115.325) (end 139.875 115.275) (width 0.182) (layer "F.Cu") (net 1))
  (segment (start 89.8 68.955) (end 89.75 68.905) (width 0.4) (layer "F.Cu") (net 1))
  (segment (start 117.4 76.235) (end 119.33 76.235) (width 0.182) (layer "F.Cu") (net 1))
  (segment (start 130.395 80.621803) (end 130.391942 80.624861) (width 0.182) (layer "F.Cu") (net 1))
  (segment (start 147.55 144.325) (end 147.55 143.385) (width 0.4) (layer "F.Cu") (net 1))
  (segment (start 130.75 82.115) (end 130.435 81.8) (width 0.182) (layer "F.Cu") (net 1))
  (segment (start 109.29 143.775) (end 109.595 143.47) (width 0.182) (layer "F.Cu") (net 1))
  (segment (start 126.407018 84.631393) (end 122.215474 84.631393) (width 0.4) (layer "F.Cu") (net 1))
  (segment (start 151.421142 127.55) (end 151.421142 126.638909) (width 0.4) (layer "F.Cu") (net 1))
  (segment (start 157.400001 130.6645) (end 156.913001 130.9765) (width 0.2) (layer "F.Cu") (net 1))
  (segment (start 90.9 100.4765) (end 91.278 100.477) (width 0.4) (layer "F.Cu") (net 1))
  (segment (start 103.899999 132.490001) (end 103.9 132.49) (width 0.182) (layer "F.Cu") (net 1))
  (segment (start 117.75 81.45) (end 119.034081 81.45) (width 0.4) (layer "F.Cu") (net 1))
  (segment (start 89.698 104.287) (end 89.213 104.287) (width 0.4) (layer "F.Cu") (net 1))
  (segment (start 156.427001 124.2875) (end 155.940001 124.5995) (width 0.2) (layer "F.Cu") (net 1))
  (segment (start 145.99 116.03) (end 148.26 118.3) (width 0.4) (layer "F.Cu") (net 1))
  (segment (start 148 142.2) (end 148 142.935) (width 0.4) (layer "F.Cu") (net 1))
  (segment (start 143.149916 127.425084) (end 143.149916 126.857314) (width 0.182) (layer "F.Cu") (net 1))
  (segment (start 157.400001 131.2995) (end 157.893001 130.9765) (width 0.2) (layer "F.Cu") (net 1))
  (segment (start 120.21241 86.441393) (end 122.118942 84.534861) (width 0.4) (layer "F.Cu") (net 1))
  (segment (start 122.825474 80.249663) (end 122.825474 83.828329) (width 0.4) (layer "F.Cu") (net 1))
  (segment (start 123.41241 83.241393) (end 122.118942 84.534861) (width 0.4) (layer "F.Cu") (net 1))
  (segment (start 139.35 127.3) (end 139.45 127.4) (width 0.182) (layer "F.Cu") (net 1))
  (segment (start 94.515004 132.165) (end 94.500004 132.15) (width 0.4) (layer "F.Cu") (net 1))
  (segment (start 157.387 108.413) (end 157.88 108.09) (width 0.2) (layer "F.Cu") (net 1))
  (segment (start 144.491 62.109) (end 144.6 62) (width 0.182) (layer "F.Cu") (net 1))
  (segment (start 110.4 73.7175) (end 110.4 72.8825) (width 0.4) (layer "F.Cu") (net 1))
  (segment (start 125.5 98.89) (end 125.515 98.875) (width 0.109) (layer "F.Cu") (net 1))
  (segment (start 148.795 66.43) (end 148.8 66.425) (width 0.182) (layer "F.Cu") (net 1))
  (segment (start 111 119.275) (end 111.025 119.25) (width 0.4) (layer "F.Cu") (net 1))
  (segment (start 93.3265 116.034) (end 93.642375 115.718125) (width 0.182) (layer "F.Cu") (net 1))
  (segment (start 143.149916 124.499916) (end 142.975 124.325) (width 0.182) (layer "F.Cu") (net 1))
  (segment (start 92.84 130.32) (end 93.3265 130.004) (width 0.182) (layer "F.Cu") (net 1))
  (segment (start 129.96 82.95) (end 129.975 82.965) (width 0.4) (layer "F.Cu") (net 1))
  (segment (start 91.4 69.4125) (end 91.75 69.0625) (width 0.2) (layer "F.Cu") (net 1))
  (segment (start 109.115 118.35) (end 109.115 117.66) (width 0.4) (layer "F.Cu") (net 1))
  (segment (start 119.789861 76.239861) (end 120.11 76.56) (width 0.182) (layer "F.Cu") (net 1))
  (segment (start 140.39047 129.021267) (end 140.408148 129.003589) (width 0.4) (layer "F.Cu") (net 1))
  (segment (start 122.419 96.7629) (end 122.419 96.22328) (width 0.182) (layer "F.Cu") (net 1))
  (segment (start 133.485 137.4) (end 133.6 137.4) (width 0.4) (layer "F.Cu") (net 1))
  (segment (start 149.985 60.6) (end 149.985 61.385) (width 0.4) (layer "F.Cu") (net 1))
  (segment (start 90.3 134.13) (end 90.7865 133.814) (width 0.182) (layer "F.Cu") (net 1))
  (segment (start 92.84 128.415) (end 93.3265 128.099) (width 0.182) (layer "F.Cu") (net 1))
  (segment (start 130.391942 88.724862) (end 130.864862 88.724862) (width 0.4) (layer "F.Cu") (net 1))
  (segment (start 92.263 67.187) (end 92.25 67.2) (width 0.182) (layer "F.Cu") (net 1))
  (segment (start 157.387 123.018) (end 157.88 122.695) (width 0.2) (layer "F.Cu") (net 1))
  (segment (start 120.11 76.56) (end 120.14 76.56) (width 0.182) (layer "F.Cu") (net 1))
  (segment (start 89.8265 119.844) (end 90.3 119.53) (width 0.182) (layer "F.Cu") (net 1))
  (segment (start 107.01 103.715) (end 107.010017 103.714983) (width 0.4) (layer "F.Cu") (net 1))
  (segment (start 111 119.915) (end 111 119.275) (width 0.4) (layer "F.Cu") (net 1))
  (segment (start 143.345 118.3) (end 143.195 118.45) (width 0.182) (layer "F.Cu") (net 1))
  (segment (start 98.625 143.025001) (end 98.625 144.125) (width 0.182) (layer "F.Cu") (net 1))
  (segment (start 118.4 80.815919) (end 122.118942 84.534861) (width 0.4) (layer "F.Cu") (net 1))
  (segment (start 90.3 130.32) (end 90.7865 130.004) (width 0.182) (layer "F.Cu") (net 1))
  (segment (start 93.44 100.4765) (end 93.818 100.477) (width 0.4) (layer "F.Cu") (net 1))
  (segment (start 117.725 84.15) (end 121.734081 84.15) (width 0.4) (layer "F.Cu") (net 1))
  (segment (start 89.8265 99.524) (end 89.401 99.524) (width 0.4) (layer "F.Cu") (net 1))
  (segment (start 110.4 70.68) (end 110.4 71.7) (width 0.4) (layer "F.Cu") (net 1))
  (segment (start 141.375 75.05) (end 141.9 75.575) (width 0.4) (layer "F.Cu") (net 1))
  (segment (start 130.75 83.45) (end 130.75 84.05) (width 0.182) (layer "F.Cu") (net 1))
  (segment (start 90.7865 107.779) (end 91.175 108.075) (width 0.182) (layer "F.Cu") (net 1))
  (segment (start 130.75 82.85) (end 130.75 82.115) (width 0.182) (layer "F.Cu") (net 1))
  (segment (start 90.7865 121.114) (end 91.1715 120.803999) (width 0.182) (layer "F.Cu") (net 1))
  (segment (start 139.025 116.08) (end 139.025 115.325) (width 0.182) (layer "F.Cu") (net 1))
  (segment (start 158.967001 134.4475) (end 158.480001 134.7595) (width 0.2) (layer "F.Cu") (net 1))
  (segment (start 108.35 141.445) (end 108.35 141.795) (width 0.182) (layer "F.Cu") (net 1))
  (segment (start 137.733001 136.233001) (end 137.8 136.3) (width 0.2) (layer "F.Cu") (net 1))
  (segment (start 89.4415 125.234) (end 89.8265 124.924) (width 0.182) (layer "F.Cu") (net 1))
  (segment (start 93.642375 115.718125) (end 93.715319 115.718125) (width 0.182) (layer "F.Cu") (net 1))
  (segment (start 99.61 99.85) (end 99.61 98.51) (width 0.4) (layer "F.Cu") (net 1))
  (segment (start 140.55 122.975) (end 140.575 122.975) (width 0.182) (layer "F.Cu") (net 1))
  (segment (start 153.2 70.834) (end 153.2 71.4) (width 0.182) (layer "F.Cu") (net 1))
  (segment (start 91.535 141.165) (end 92.435 141.165) (width 0.4) (layer "F.Cu") (net 1))
  (segment (start 95.2 132.165) (end 94.515004 132.165) (width 0.4) (layer "F.Cu") (net 1))
  (segment (start 92.3665 133.179) (end 92.84 132.865) (width 0.182) (layer "F.Cu") (net 1))
  (segment (start 113.5054 120.549811) (end 112.974811 120.549811) (width 0.182) (layer "F.Cu") (net 1))
  (segment (start 137.6 127.4) (end 137.6 127.1) (width 0.182) (layer "F.Cu") (net 1))
  (segment (start 108.2 136.85) (end 108.3 136.95) (width 0.182) (layer "F.Cu") (net 1))
  (segment (start 111.46 91.22) (end 110.63 91.22) (width 0.182) (layer "F.Cu") (net 1))
  (segment (start 90.3 136.029) (end 90.7865 135.719) (width 0.182) (layer "F.Cu") (net 1))
  (segment (start 122.022408 88.822937) (end 122.022408 84.631395) (width 0.4) (layer "F.Cu") (net 1))
  (segment (start 109.597168 141.2) (end 109.683871 141.286703) (width 0.182) (layer "F.Cu") (net 1))
  (segment (start 149.245911 94.249035) (end 148.9 94.594946) (width 0.182) (layer "F.Cu") (net 1))
  (segment (start 146.049684 141.550316) (end 146.049684 141.939684) (width 0.4) (layer "F.Cu") (net 1))
  (segment (start 120.45 76.25) (end 120.5 76.25) (width 0.182) (layer "F.Cu") (net 1))
  (segment (start 159.927 105.873) (end 160.42 105.55) (width 0.2) (layer "F.Cu") (net 1))
  (segment (start 113.285 88.725) (end 113.434862 88.874862) (width 0.182) (layer "F.Cu") (net 1))
  (segment (start 144.56 83.5) (end 144.595 83.465) (width 0.4) (layer "F.Cu") (net 1))
  (segment (start 148.1 66.43) (end 148.795 66.43) (width 0.4) (layer "F.Cu") (net 1))
  (segment (start 82.28 118.324) (end 82.28 118.755) (width 0.4) (layer "F.Cu") (net 1))
  (segment (start 142.15 108.575) (end 142.455 108.575) (width 0.4) (layer "F.Cu") (net 1))
  (segment (start 137.885 121.8) (end 137.625 122.06) (width 0.182) (layer "F.Cu") (net 1))
  (segment (start 89.8265 131.274) (end 90.3 130.96) (width 0.182) (layer "F.Cu") (net 1))
  (segment (start 164.89 75.9) (end 165.6 75.9) (width 0.182) (layer "F.Cu") (net 1))
  (segment (start 139.025 115.325) (end 138.975 115.275) (width 0.182) (layer "F.Cu") (net 1))
  (segment (start 126.315 99) (end 126.215 98.9) (width 0.2) (layer "F.Cu") (net 1))
  (segment (start 150.5 119.87) (end 149.83 119.87) (width 0.4) (layer "F.Cu") (net 1))
  (segment (start 91.75 68.225) (end 91.75 67.95) (width 0.2) (layer "F.Cu") (net 1))
  (segment (start 119.206942 76.239861) (end 119.217081 76.25) (width 0.182) (layer "F.Cu") (net 1))
  (segment (start 159.927 135.718) (end 159.44 136.03) (width 0.2) (layer "F.Cu") (net 1))
  (segment (start 140.408148 129.003589) (end 140.408148 128.566854) (width 0.4) (layer "F.Cu") (net 1))
  (segment (start 149 124.717767) (end 149.11906 124.836827) (width 0.4) (layer "F.Cu") (net 1))
  (segment (start 121.734081 84.15) (end 122.118942 84.534861) (width 0.4) (layer "F.Cu") (net 1))
  (segment (start 171.85 131.2) (end 172.55 131.2) (width 0.182) (layer "F.Cu") (net 1))
  (segment (start 117.385 123.55) (end 118.2 123.55) (width 0.4) (layer "F.Cu") (net 1))
  (segment (start 159.927001 133.1775) (end 159.440001 133.4895) (width 0.2) (layer "F.Cu") (net 1))
  (segment (start 89.8 69.5) (end 89.8 68.955) (width 0.4) (layer "F.Cu") (net 1))
  (segment (start 158.967001 120.4775) (end 158.480001 120.7895) (width 0.2) (layer "F.Cu") (net 1))
  (segment (start 156.427001 134.4475) (end 155.940001 134.7595) (width 0.2) (layer "F.Cu") (net 1))
  (segment (start 122.468 75.073) (end 121.183 75.073) (width 0.182) (layer "F.Cu") (net 1))
  (segment (start 158.967001 132.5425) (end 159.460001 132.2195) (width 0.2) (layer "F.Cu") (net 1))
  (segment (start 140.25 86.85) (end 140.913175 86.85) (width 0.4) (layer "F.Cu") (net 1))
  (segment (start 82.3475 136) (end 83.1 136) (width 0.4) (layer "F.Cu") (net 1))
  (segment (start 152.925 125.475) (end 153.577977 125.475) (width 0.4) (layer "F.Cu") (net 1))
  (segment (start 155 70.98) (end 155 71.4) (width 0.182) (layer "F.Cu") (net 1))
  (segment (start 154.601622 89.167588) (end 155.217588 89.167588) (width 0.2) (layer "F.Cu") (net 1))
  (segment (start 157.387 121.113) (end 157.88 120.79) (width 0.2) (layer "F.Cu") (net 1))
  (segment (start 94.35 68.895) (end 94.35 69.25) (width 0.4) (layer "F.Cu") (net 1))
  (segment (start 130.75 82.85) (end 130.75 83.45) (width 0.182) (layer "F.Cu") (net 1))
  (segment (start 98.8 145) (end 98.65 145.15) (width 0.4) (layer "F.Cu") (net 1))
  (segment (start 98.8 144.3) (end 98.8 145) (width 0.4) (layer "F.Cu") (net 1))
  (segment (start 92.263 65.618) (end 92.263 67.187) (width 0.182) (layer "F.Cu") (net 1))
  (segment (start 122.825474 83.828329) (end 122.118942 84.534861) (width 0.4) (layer "F.Cu") (net 1))
  (segment (start 85.263 67.137) (end 85.25 67.15) (width 0.182) (layer "F.Cu") (net 1))
  (segment (start 86.7894 114.8894) (end 86.7894 115.0112) (width 0.182) (layer "F.Cu") (net 1))
  (segment (start 156.427 102.063) (end 155.94 102.375) (width 0.2) (layer "F.Cu") (net 1))
  (segment (start 117.295 122.595) (end 116.750189 122.050189) (width 0.182) (layer "F.Cu") (net 1))
  (segment (start 141.965 75.575) (end 141.965 76.31) (width 0.4) (layer "F.Cu") (net 1))
  (segment (start 89.8265 129.369) (end 90.3 129.055) (width 0.182) (layer "F.Cu") (net 1))
  (segment (start 148.7 117.86) (end 148.26 118.3) (width 0.4) (layer "F.Cu") (net 1))
  (segment (start 156.427001 116.6675) (end 155.940001 116.9795) (width 0.2) (layer "F.Cu") (net 1))
  (segment (start 117.74 122.58) (end 117.725 122.595) (width 0.182) (layer "F.Cu") (net 1))
  (segment (start 108.35 141.795) (end 108.624998 142.069998) (width 0.182) (layer "F.Cu") (net 1))
  (segment (start 128.462501 92.662501) (end 128.5 92.7) (width 0.4) (layer "F.Cu") (net 1))
  (segment (start 155.192588 90.117588) (end 155.2 90.125) (width 0.2) (layer "F.Cu") (net 1))
  (segment (start 117.725 85) (end 121.653803 85) (width 0.4) (layer "F.Cu") (net 1))
  (segment (start 159.927 121.113) (end 160.42 120.79) (width 0.2) (layer "F.Cu") (net 1))
  (segment (start 104.9 132.501681) (end 104.900675 132.501006) (width 0.182) (layer "F.Cu") (net 1))
  (segment (start 156.427001 118.5725) (end 155.940001 118.8845) (width 0.2) (layer "F.Cu") (net 1))
  (segment (start 168.075 75.9) (end 168.1 75.875) (width 0.182) (layer "F.Cu") (net 1))
  (segment (start 122.419 96.22328) (end 122.615557 96.026723) (width 0.182) (layer "F.Cu") (net 1))
  (segment (start 114.149811 119.9054) (end 114.149811 119.574811) (width 0.182) (layer "F.Cu") (net 1))
  (segment (start 82.575 119.45) (end 83.289999 119.45) (width 0.2) (layer "F.Cu") (net 1))
  (segment (start 108.175 122.75) (end 108.175 121.925) (width 0.4) (layer "F.Cu") (net 1))
  (segment (start 148.26 119.285) (end 148.48 119.505) (width 0.4) (layer "F.Cu") (net 1))
  (segment (start 144.595 83.465) (end 145.367305 83.465) (width 0.4) (layer "F.Cu") (net 1))
  (segment (start 89.8265 127.464) (end 90.3 127.15) (width 0.182) (layer "F.Cu") (net 1))
  (segment (start 174.3 141.4825) (end 174.3 141.072443) (width 0.4) (layer "F.Cu") (net 1))
  (segment (start 140.025 122.045) (end 140.025 122.45) (width 0.182) (layer "F.Cu") (net 1))
  (segment (start 111.500001 136.85) (end 111.500001 137.499999) (width 0.182) (layer "F.Cu") (net 1))
  (segment (start 83.289999 119.45) (end 83.389999 119.35) (width 0.2) (layer "F.Cu") (net 1))
  (segment (start 157.387001 136.3525) (end 157.880001 136.0295) (width 0.2) (layer "F.Cu") (net 1))
  (segment (start 142.455 108.575) (end 142.73 108.3) (width 0.4) (layer "F.Cu") (net 1))
  (segment (start 119.875 119.95) (end 119.9 119.975) (width 0.4) (layer "F.Cu") (net 1))
  (segment (start 111.500001 137.499999) (end 111.5 137.5) (width 0.182) (layer "F.Cu") (net 1))
  (segment (start 103.650001 95.714999) (end 104.285001 95.714999) (width 0.4) (layer "F.Cu") (net 1))
  (segment (start 119.2 80.1) (end 119.2 81.615919) (width 0.4) (layer "F.Cu") (net 1))
  (segment (start 126.215 98.9) (end 125.5 98.9) (width 0.2) (layer "F.Cu") (net 1))
  (segment (start 174.3 141.072443) (end 174.2819 141.054343) (width 0.4) (layer "F.Cu") (net 1))
  (segment (start 113.35 85.43) (end 113.38 85.43) (width 0.182) (layer "F.Cu") (net 1))
  (segment (start 140.165 73.25) (end 141.138 74.223) (width 0.4) (layer "F.Cu") (net 1))
  (segment (start 93.15 149.3) (end 92.375 149.3) (width 0.4) (layer "F.Cu") (net 1))
  (segment (start 157.387 124.923) (end 157.88 124.6) (width 0.2) (layer "F.Cu") (net 1))
  (segment (start 113.32 86.75) (end 113.32 86.409986) (width 0.182) (layer "F.Cu") (net 1))
  (segment (start 132.559 74.973) (end 132.559 75.747) (width 0.182) (layer "F.Cu") (net 1))
  (segment (start 92.435 141.165) (end 93.335 141.165) (width 0.4) (layer "F.Cu") (net 1))
  (segment (start 147.79722 126.41778) (end 147.79722 127.755115) (width 0.4) (layer "F.Cu") (net 1))
  (segment (start 92.238 106.827) (end 92.3665 107.144) (width 0.4) (layer "F.Cu") (net 1))
  (segment (start 129.5 90.715) (end 129.515 90.7) (width 0.4) (layer "F.Cu") (net 1))
  (segment (start 85.7 149.3) (end 86.55 149.3) (width 0.178) (layer "F.Cu") (net 1))
  (segment (start 91.4 69.5) (end 91.4 69.4125) (width 0.2) (layer "F.Cu") (net 1))
  (segment (start 78.94 92.175) (end 78.425 92.175) (width 0.4) (layer "F.Cu") (net 1))
  (segment (start 90.482 73.232) (end 90.5 73.25) (width 0.4) (layer "F.Cu") (net 1))
  (segment (start 107.95 139.755) (end 107.95 138.95) (width 0.182) (layer "F.Cu") (net 1))
  (segment (start 128.690132 80.134862) (end 128.799994 80.025) (width 0.182) (layer "F.Cu") (net 1))
  (segment (start 137.733001 135.633999) (end 137.733001 136.233001) (width 0.2) (layer "F.Cu") (net 1))
  (segment (start 90.7865 102.699) (end 90.9 103.0165) (width 0.4) (layer "F.Cu") (net 1))
  (segment (start 140.50176 112.579792) (end 139.872435 113.209117) (width 0.182) (layer "F.Cu") (net 1))
  (segment (start 138.825 120.355) (end 138.825 119.725) (width 0.182) (layer "F.Cu") (net 1))
  (segment (start 133.5 136.5) (end 133.5 135.9) (width 0.4) (layer "F.Cu") (net 1))
  (segment (start 139.25 119.6) (end 139.7 119.6) (width 0.182) (layer "F.Cu") (net 1))
  (segment (start 158.967001 126.1925) (end 158.480001 126.5045) (width 0.2) (layer "F.Cu") (net 1))
  (segment (start 127.907742 80.134862) (end 128.690132 80.134862) (width 0.182) (layer "F.Cu") (net 1))
  (segment (start 155.8 150.8) (end 155.8 150.2) (width 0.182) (layer "F.Cu") (net 1))
  (segment (start 114.149811 123.100189) (end 113.875 123.375) (width 0.2) (layer "F.Cu") (net 1))
  (segment (start 144.385 115.9) (end 143.983728 115.9) (width 0.182) (layer "F.Cu") (net 1))
  (segment (start 112.12 96.495) (end 112.125 96.49) (width 0.4) (layer "F.Cu") (net 1))
  (segment (start 156.427 130.003) (end 156.92 129.68) (width 0.2) (layer "F.Cu") (net 1))
  (segment (start 142.904916 126.212314) (end 142.23732 126.212314) (width 0.182) (layer "F.Cu") (net 1))
  (segment (start 156.427001 110.9525) (end 155.940001 111.2645) (width 0.2) (layer "F.Cu") (net 1))
  (segment (start 151.225 67.2) (end 151.2 67.225) (width 0.182) (layer "F.Cu") (net 1))
  (segment (start 159.927 103.333) (end 160.42 103.01) (width 0.2) (layer "F.Cu") (net 1))
  (segment (start 91.9815 125.234) (end 92.3665 124.924) (width 0.182) (layer "F.Cu") (net 1))
  (via (at 144.35 142.3) (size 0.45) (drill 0.1) (layers "F.Cu" "B.Cu") (net 1))
  (via (at 116.8 140.25) (size 0.45) (drill 0.1) (layers "F.Cu" "B.Cu") (net 1))
  (via (at 106.6 145.525) (size 0.45) (drill 0.1) (layers "F.Cu" "B.Cu") (net 1))
  (via (at 105 139.95) (size 0.45) (drill 0.1) (layers "F.Cu" "B.Cu") (net 1))
  (via (at 108 138.9) (size 0.45) (drill 0.1) (layers "F.Cu" "B.Cu") (net 1))
  (via (at 106.4 143.775) (size 0.45) (drill 0.1) (layers "F.Cu" "B.Cu") (net 1))
  (via (at 109.35 145.525) (size 0.45) (drill 0.1) (layers "F.Cu" "B.Cu") (net 1))
  (via (at 116.8 141.95) (size 0.45) (drill 0.1) (layers "F.Cu" "B.Cu") (net 1))
  (via (at 109.45 142.075) (size 0.45) (drill 0.1) (layers "F.Cu" "B.Cu") (net 1))
  (via (at 106.175 142.225) (size 0.45) (drill 0.1) (layers "F.Cu" "B.Cu") (net 1))
  (via (at 159.460001 129.6795) (size 0.45) (drill 0.1) (layers "F.Cu" "B.Cu") (net 1))
  (via (at 159.440001 130.9495) (size 0.45) (drill 0.1) (layers "F.Cu" "B.Cu") (net 1))
  (via (at 157.88 128.41) (size 0.45) (drill 0.1) (layers "F.Cu" "B.Cu") (net 1))
  (via (at 155.940001 128.4095) (size 0.45) (drill 0.1) (layers "F.Cu" "B.Cu") (net 1))
  (via (at 158.480001 111.2645) (size 0.45) (drill 0.1) (layers "F.Cu" "B.Cu") (net 1))
  (via (at 160.42 111.265) (size 0.45) (drill 0.1) (layers "F.Cu" "B.Cu") (net 1))
  (via (at 157.88 109.36) (size 0.45) (drill 0.1) (layers "F.Cu" "B.Cu") (net 1))
  (via (at 155.94 109.995) (size 0.45) (drill 0.1) (layers "F.Cu" "B.Cu") (net 1))
  (via (at 160.42 109.36) (size 0.45) (drill 0.1) (layers "F.Cu" "B.Cu") (net 1))
  (via (at 158.48 109.995) (size 0.45) (drill 0.1) (layers "F.Cu" "B.Cu") (net 1))
  (via (at 160.42 108.09) (size 0.45) (drill 0.1) (layers "F.Cu" "B.Cu") (net 1))
  (via (at 158.48 107.455) (size 0.45) (drill 0.1) (layers "F.Cu" "B.Cu") (net 1))
  (via (at 158.48 102.375) (size 0.45) (drill 0.1) (layers "F.Cu" "B.Cu") (net 1))
  (via (at 157.88 100.47) (size 0.45) (drill 0.1) (layers "F.Cu" "B.Cu") (net 1))
  (via (at 104.95 134.95) (size 0.45) (drill 0.1) (layers "F.Cu" "B.Cu") (net 1))
  (via (at 104.25 134.15) (size 0.45) (drill 0.1) (layers "F.Cu" "B.Cu") (net 1))
  (via (at 105.05 134.15) (size 0.45) (drill 0.1) (layers "F.Cu" "B.Cu") (net 1))
  (via (at 104.15 134.95) (size 0.45) (drill 0.1) (layers "F.Cu" "B.Cu") (net 1))
  (via (at 100.515 134.35) (size 0.45) (drill 0.1) (layers "F.Cu" "B.Cu") (net 1))
  (via (at 98.65 145.15) (size 0.45) (drill 0.1) (layers "F.Cu" "B.Cu") (net 1))
  (via (at 94.55 143.65) (size 0.45) (drill 0.1) (layers "F.Cu" "B.Cu") (net 1))
  (via (at 97.375 141.025) (size 0.45) (drill 0.1) (layers "F.Cu" "B.Cu") (net 1))
  (via (at 96.45 145.85) (size 0.45) (drill 0.1) (layers "F.Cu" "B.Cu") (net 1))
  (via (at 89.4415 109.994) (size 0.45) (drill 0.1) (layers "F.Cu" "B.Cu") (net 1))
  (via (at 91.1715 115.724) (size 0.45) (drill 0.1) (layers "F.Cu" "B.Cu") (net 1))
  (via (at 89.4415 115.074) (size 0.45) (drill 0.1) (layers "F.Cu" "B.Cu") (net 1))
  (via (at 91.1715 113.183999) (size 0.45) (drill 0.1) (layers "F.Cu" "B.Cu") (net 1))
  (via (at 90.3 111.91) (size 0.45) (drill 0.1) (layers "F.Cu" "B.Cu") (net 1))
  (via (at 90.3 111.27) (size 0.45) (drill 0.1) (layers "F.Cu" "B.Cu") (net 1))
  (via (at 91.175 108.075) (size 0.45) (drill 0.1) (layers "F.Cu" "B.Cu") (net 1))
  (via (at 139.872435 113.972792) (size 0.45) (drill 0.1) (layers "F.Cu" "B.Cu") (free) (net 1))
  (via (at 138.299122 111.833794) (size 0.45) (drill 0.1) (layers "F.Cu" "B.Cu") (net 1))
  (via (at 142.7 127.5) (size 0.45) (drill 0.1) (layers "F.Cu" "B.Cu") (net 1))
  (via (at 124.215474 80.249663) (size 0.45) (drill 0.1) (layers "F.Cu" "B.Cu") (net 1))
  (via (at 122.825474 80.249663) (size 0.45) (drill 0.1) (layers "F.Cu" "B.Cu") (net 1))
  (via (at 122.025001 76.42) (size 0.45) (drill 0.1) (layers "F.Cu" "B.Cu") (net 1))
  (via (at 123.415001 76.42) (size 0.45) (drill 0.1) (layers "F.Cu" "B.Cu") (net 1))
  (via (at 123.624396 77.22) (size 0.45) (drill 0.1) (layers "F.Cu" "B.Cu") (net 1))
  (via (at 125.015 77.315) (size 0.45) (drill 0.1) (layers "F.Cu" "B.Cu") (net 1))
  (via (at 122.030864 77.3) (size 0.45) (drill 0.1) (layers "F.Cu" "B.Cu") (net 1))
  (via (at 120.630864 77.3) (size 0.45) (drill 0.1) (layers "F.Cu" "B.Cu") (net 1))
  (via (at 126.40335 76.5) (size 0.45) (drill 0.1) (layers "F.Cu" "B.Cu") (net 1))
  (via (at 125.085 76.425) (size 0.45) (drill 0.1) (layers "F.Cu" "B.Cu") (net 1))
  (via (at 139.25 119.6) (size 0.45) (drill 0.1) (layers "F.Cu" "B.Cu") (net 1))
  (via (at 139.875 115.275) (size 0.45) (drill 0.1) (layers "F.Cu" "B.Cu") (net 1))
  (via (at 150.61 115.53) (size 0.45) (drill 0.1) (layers "F.Cu" "B.Cu") (net 1))
  (via (at 146.73 116.02) (size 0.45) (drill 0.1) (layers "F.Cu" "B.Cu") (net 1))
  (via (at 145.83 116.03) (size 0.45) (drill 0.1) (layers "F.Cu" "B.Cu") (net 1))
  (via (at 147.58 120.55) (size 0.45) (drill 0.1) (layers "F.Cu" "B.Cu") (net 1))
  (via (at 148.282843 128.533095) (size 0.45) (drill 0.1) (layers "F.Cu" "B.Cu") (net 1))
  (via (at 150.5 117.86) (size 0.45) (drill 0.1) (layers "F.Cu" "B.Cu") (net 1))
  (via (at 138.975 115.275) (size 0.45) (drill 0.1) (layers "F.Cu" "B.Cu") (net 1))
  (via (at 149.48 116.03) (size 0.45) (drill 0.1) (layers "F.Cu" "B.Cu") (net 1))
  (via (at 152.775 113.2) (size 0.45) (drill 0.1) (layers "F.Cu" "B.Cu") (net 1))
  (via (at 145.95 118.76) (size 0.45) (drill 0.1) (layers "F.Cu" "B.Cu") (net 1))
  (via (at 139.425 115.275) (size 0.45) (drill 0.1) (layers "F.Cu" "B.Cu") (net 1))
  (via (at 150.5 120.55) (size 0.45) (drill 0.1) (layers "F.Cu" "B.Cu") (net 1))
  (via (at 150.5 119.87) (size 0.45) (drill 0.1) (layers "F.Cu" "B.Cu") (net 1))
  (via (at 148.48 120.55) (size 0.45) (drill 0.1) (layers "F.Cu" "B.Cu") (net 1))
  (via (at 149.6 120.550002) (size 0.45) (drill 0.1) (layers "F.Cu" "B.Cu") (net 1))
  (via (at 147.79722 127.755115) (size 0.45) (drill 0.1) (layers "F.Cu" "B.Cu") (net 1))
  (via (at 145.97 117.84) (size 0.45) (drill 0.1) (layers "F.Cu" "B.Cu") (net 1))
  (via (at 148.250001 116.03) (size 0.45) (drill 0.1) (layers "F.Cu" "B.Cu") (net 1))
  (via (at 140.15 119.6) (size 0.45) (drill 0.1) (layers "F.Cu" "B.Cu") (net 1))
  (via (at 139.7 119.6) (size 0.45) (drill 0.1) (layers "F.Cu" "B.Cu") (net 1))
  (via (at 149 123.95) (size 0.45) (drill 0.1) (layers "F.Cu" "B.Cu") (net 1))
  (via (at 151.421142 127.55) (size 0.45) (drill 0.1) (layers "F.Cu" "B.Cu") (net 1))
  (via (at 129.44 84.55) (size 0.45) (drill 0.1) (layers "F.Cu" "B.Cu") (net 1))
  (via (at 148.6 108.846) (size 0.45) (drill 0.1) (layers "F.Cu" "B.Cu") (net 1))
  (via (at 146.85 108.85) (size 0.45) (drill 0.1) (layers "F.Cu" "B.Cu") (net 1))
  (via (at 146.85 111.175) (size 0.45) (drill 0.1) (layers "F.Cu" "B.Cu") (net 1))
  (via (at 148.6 111.171) (size 0.45) (drill 0.1) (layers "F.Cu" "B.Cu") (net 1))
  (via (at 130.153803 86.229267) (size 0.45) (drill 0.1) (layers "F.Cu" "B.Cu") (net 1))
  (via (at 130.153803 87.619268) (size 0.45) (drill 0.1) (layers "F.Cu" "B.Cu") (net 1))
  (via (at 146.852 106.325) (size 0.45) (drill 0.1) (layers "F.Cu" "B.Cu") (net 1))
  (via (at 148.602 106.321) (size 0.45) (drill 0.1) (layers "F.Cu" "B.Cu") (net 1))
  (via (at 123.412408 88.822937) (size 0.45) (drill 0.1) (layers "F.Cu" "B.Cu") (net 1))
  (via (at 122.022408 88.822937) (size 0.45) (drill 0.1) (layers "F.Cu" "B.Cu") (net 1))
  (via (at 119.45 92.6) (size 0.45) (drill 0.1) (layers "F.Cu" "B.Cu") (net 1))
  (via (at 120.824535 92.569722) (size 0.45) (drill 0.1) (layers "F.Cu" "B.Cu") (net 1))
  (via (at 126.407018 86.841393) (size 0.45) (drill 0.1) (layers "F.Cu" "B.Cu") (net 1))
  (via (at 126.407018 88.231393) (size 0.45) (drill 0.1) (layers "F.Cu" "B.Cu") (net 1))
  (via (at 117.4 118.3) (size 0.45) (drill 0.1) (layers "F.Cu" "B.Cu") (net 1))
  (via (at 117.74 122.58) (size 0.45) (drill 0.1) (layers "F.Cu" "B.Cu") (net 1))
  (via (at 120.821058 95.173939) (size 0.45) (drill 0.1) (layers "F.Cu" "B.Cu") (net 1))
  (via (at 119.431058 95.173939) (size 0.45) (drill 0.1) (layers "F.Cu" "B.Cu") (net 1))
  (via (at 118.2 123.55) (size 0.45) (drill 0.1) (layers "F.Cu" "B.Cu") (net 1))
  (via (at 114.027 123.71) (size 0.45) (drill 0.1) (layers "F.Cu" "B.Cu") (net 1))
  (via (at 115.777 123.706) (size 0.45) (drill 0.1) (layers "F.Cu" "B.Cu") (net 1))
  (via (at 112.520733 77.818803) (size 0.45) (drill 0.1) (layers "F.Cu" "B.Cu") (net 1))
  (via (at 111.130732 77.835) (size 0.45) (drill 0.1) (layers "F.Cu" "B.Cu") (net 1))
  (via (at 114.027 118.889999) (size 0.45) (drill 0.1) (layers "F.Cu" "B.Cu") (net 1))
  (via (at 126.45 113.2) (size 0.45) (drill 0.1) (layers "F.Cu" "B.Cu") (net 1))
  (via (at 111.156 76.989) (size 0.45) (drill 0.1) (layers "F.Cu" "B.Cu") (net 1))
  (via (at 109.779267 77.006197) (size 0.45) (drill 0.1) (layers "F.Cu" "B.Cu") (net 1))
  (via (at 109.741466 78.037606) (size 0.45) (drill 0.1) (layers "F.Cu" "B.Cu") (net 1))
  (via (at 108.351465 78.037606) (size 0.45) (drill 0.1) (layers "F.Cu" "B.Cu") (net 1))
  (via (at 90.3 136.029) (size 0.45) (drill 0.1) (layers "F.Cu" "B.Cu") (net 1))
  (via (at 90.3 136.664) (size 0.45) (drill 0.1) (layers "F.Cu" "B.Cu") (net 1))
  (via (at 107.687607 75.6116) (size 0.45) (drill 0.1) (layers "F.Cu" "B.Cu") (net 1))
  (via (at 107.687607 77.001601) (size 0.45) (drill 0.1) (layers "F.Cu" "B.Cu") (net 1))
  (via (at 129.129267 76.956197) (size 0.45) (drill 0.1) (layers "F.Cu" "B.Cu") (net 1))
  (via (at 127.701465 77.987606) (size 0.45) (drill 0.1) (layers "F.Cu" "B.Cu") (net 1))
  (via (at 130.516 76.953) (size 0.45) (drill 0.1) (layers "F.Cu" "B.Cu") (net 1))
  (via (at 130.485 77.875) (size 0.45) (drill 0.1) (layers "F.Cu" "B.Cu") (net 1))
  (via (at 129.091466 77.987606) (size 0.45) (drill 0.1) (layers "F.Cu" "B.Cu") (net 1))
  (via (at 127.037607 76.951601) (size 0.45) (drill 0.1) (layers "F.Cu" "B.Cu") (net 1))
  (via (at 127.425 75.365) (size 0.45) (drill 0.1) (layers "F.Cu" "B.Cu") (net 1))
  (via (at 131.870733 77.768803) (size 0.45) (drill 0.1) (layers "F.Cu" "B.Cu") (net 1))
  (via (at 117.75 145.1) (size 0.45) (drill 0.1) (layers "F.Cu" "B.Cu") (net 1))
  (via (at 119.9 119.975) (size 0.45) (drill 0.1) (layers "F.Cu" "B.Cu") (net 1))
  (via (at 109.125 117.65) (size 0.45) (drill 0.1) (layers "F.Cu" "B.Cu") (net 1))
  (via (at 134.6 91.05) (size 0.45) (drill 0.1) (layers "F.Cu" "B.Cu") (net 1))
  (via (at 134.8 92.3) (size 0.45) (drill 0.1) (layers "F.Cu" "B.Cu") (net 1))
  (via (at 141.65 96.1) (size 0.45) (drill 0.1) (layers "F.Cu" "B.Cu") (net 1))
  (via (at 142.9 95.6) (size 0.45) (drill 0.1) (layers "F.Cu" "B.Cu") (net 1))
  (via (at 143.6 94.9) (size 0.45) (drill 0.1) (layers "F.Cu" "B.Cu") (net 1))
  (via (at 137.9 89.4) (size 0.45) (drill 0.1) (layers "F.Cu" "B.Cu") (net 1))
  (via (at 141.4 79.1) (size 0.45) (drill 0.1) (layers "F.Cu" "B.Cu") (net 1))
  (via (at 122.505309 94.475) (size 0.45) (drill 0.1) (layers "F.Cu" "B.Cu") (net 1))
  (via (at 123.89531 94.475) (size 0.45) (drill 0.1) (layers "F.Cu" "B.Cu") (net 1))
  (via (at 88.25 67.2) (size 0.45) (drill 0.1) (layers "F.Cu" "B.Cu") (net 1))
  (via (at 113.35 85.43) (size 0.45) (drill 0.1) (layers "F.Cu" "B.Cu") (net 1))
  (via (at 93.89 108.096) (size 0.45) (drill 0.1) (layers "F.Cu" "B.Cu") (net 1))
  (via (at 93.48 108.096) (size 0.45) (drill 0.1) (layers "F.Cu" "B.Cu") (net 1))
  (via (at 89.8 69.5) (size 0.45) (drill 0.1) (layers "F.Cu" "B.Cu") (net 1))
  (via (at 86.23 72.7) (size 0.45) (drill 0.1) (layers "F.Cu" "B.Cu") (free) (net 1))
  (via (at 87.98 72.696) (size 0.45) (drill 0.1) (layers "F.Cu" "B.Cu") (net 1))
  (via (at 113.525 119.325) (size 0.45) (drill 0.1) (layers "F.Cu" "B.Cu") (net 1))
  (via (at 96.2 84.5) (size 0.45) (drill 0.1) (layers "F.Cu" "B.Cu") (net 1))
  (via (at 94.7 84.6) (size 0.45) (drill 0.1) (layers "F.Cu" "B.Cu") (net 1))
  (via (at 94.3 87.9) (size 0.45) (drill 0.1) (layers "F.Cu" "B.Cu") (net 1))
  (via (at 91.9 86.1) (size 0.45) (drill 0.1) (layers "F.Cu" "B.Cu") (net 1))
  (via (at 182.174999 134.525) (size 0.5) (drill 0.15) (layers "F.Cu" "B.Cu") (net 1))
  (via (at 181.574999 134.525) (size 0.5) (drill 0.15) (layers "F.Cu" "B.Cu") (net 1))
  (via (at 180.975 134.525) (size 0.5) (drill 0.15) (layers "F.Cu" "B.Cu") (net 1))
  (via (at 182.175 133.924999) (size 0.5) (drill 0.15) (layers "F.Cu" "B.Cu") (net 1))
  (via (at 181.574999 133.925) (size 0.5) (drill 0.15) (layers "F.Cu" "B.Cu") (net 1))
  (via (at 182.175 133.324999) (size 0.5) (drill 0.15) (layers "F.Cu" "B.Cu") (net 1))
  (via (at 181.575 133.324999) (size 0.5) (drill 0.15) (layers "F.Cu" "B.Cu") (net 1))
  (via (at 113.85 62.675) (size 0.45) (drill 0.1) (layers "F.Cu" "B.Cu") (free) (net 1))
  (via (at 112.95 62.675) (size 0.45) (drill 0.1) (layers "F.Cu" "B.Cu") (free) (net 1))
  (via (at 112.05 62.675) (size 0.45) (drill 0.1) (layers "F.Cu" "B.Cu") (net 1))
  (via (at 119.5 65.7) (size 0.45) (drill 0.1) (layers "F.Cu" "B.Cu") (net 1))
  (via (at 119.5 67.5) (size 0.45) (drill 0.1) (layers "F.Cu" "B.Cu") (net 1))
  (via (at 119.5 66.6) (size 0.45) (drill 0.1) (layers "F.Cu" "B.Cu") (net 1))
  (via (at 191.302512 133.827512) (size 0.5) (drill 0.15) (layers "F.Cu" "B.Cu") (net 1))
  (via (at 190.702512 133.827512) (size 0.5) (drill 0.15) (layers "F.Cu" "B.Cu") (net 1))
  (via (at 191.302512 134.427512) (size 0.5) (drill 0.15) (layers "F.Cu" "B.Cu") (net 1))
  (via (at 191.302513 133.227512) (size 0.5) (drill 0.15) (layers "F.Cu" "B.Cu") (net 1))
  (via (at 190.702512 133.227513) (size 0.5) (drill 0.15) (layers "F.Cu" "B.Cu") (net 1))
  (via (at 190.702512 134.427512) (size 0.5) (drill 0.15) (layers "F.Cu" "B.Cu") (net 1))
  (via (at 190.102513 134.427513) (size 0.5) (drill 0.15) (layers "F.Cu" "B.Cu") (net 1))
  (via (at 133.25 62.6) (size 0.45) (drill 0.1) (layers "F.Cu" "B.Cu") (free) (net 1))
  (via (at 131.45 62.6) (size 0.45) (drill 0.1) (layers "F.Cu" "B.Cu") (net 1))
  (via (at 132.35 62.6) (size 0.45) (drill 0.1) (layers "F.Cu" "B.Cu") (free) (net 1))
  (via (at 138.9 65.6) (size 0.45) (drill 0.1) (layers "F.Cu" "B.Cu") (net 1))
  (via (at 138.9 66.5) (size 0.45) (drill 0.1) (layers "F.Cu" "B.Cu") (net 1))
  (via (at 138.9 67.4) (size 0.45) (drill 0.1) (layers "F.Cu" "B.Cu") (net 1))
  (via (at 142.85 61.15) (size 0.45) (drill 0.1) (layers "F.Cu" "B.Cu") (net 1))
  (via (at 143.45 61.15) (size 0.45) (drill 0.1) (layers "F.Cu" "B.Cu") (free) (net 1))
  (via (at 142.25 61.75) (size 0.45) (drill 0.1) (layers "F.Cu" "B.Cu") (net 1))
  (via (at 142.85 61.75) (size 0.45) (drill 0.1) (layers "F.Cu" "B.Cu") (net 1))
  (via (at 143.45 61.75) (size 0.45) (drill 0.1) (layers "F.Cu" "B.Cu") (net 1))
  (via (at 140.85 63.15) (size 0.45) (drill 0.1) (layers "F.Cu" "B.Cu") (net 1))
  (via (at 190.4 115.95) (size 0.6) (drill 0.25) (layers "F.Cu" "B.Cu") (net 1))
  (via (at 190.4 117.95) (size 0.6) (drill 0.25) (layers "F.Cu" "B.Cu") (net 1))
  (via (at 190.4 114.95) (size 0.6) (drill 0.25) (layers "F.Cu" "B.Cu") (net 1))
  (via (at 188.4 114.95) (size 0.6) (drill 0.25) (layers "F.Cu" "B.Cu") (net 1))
  (via (at 190.4 118.95) (size 0.6) (drill 0.25) (layers "F.Cu" "B.Cu") (net 1))
  (via (at 190.4 116.95) (size 0.6) (drill 0.25) (layers "F.Cu" "B.Cu") (net 1))
  (via (at 191.4 118.95) (size 0.6) (drill 0.25) (layers "F.Cu" "B.Cu") (net 1))
  (via (at 191.4 117.95) (size 0.6) (drill 0.25) (layers "F.Cu" "B.Cu") (net 1))
  (via (at 191.4 116.95) (size 0.6) (drill 0.25) (layers "F.Cu" "B.Cu") (net 1))
  (via (at 191.4 115.95) (size 0.6) (drill 0.25) (layers "F.Cu" "B.Cu") (net 1))
  (via (at 191.4 114.95) (size 0.6) (drill 0.25) (layers "F.Cu" "B.Cu") (net 1))
  (via (at 191.4 113.95) (size 0.6) (drill 0.25) (layers "F.Cu" "B.Cu") (net 1))
  (via (at 190.4 113.95) (size 0.6) (drill 0.25) (layers "F.Cu" "B.Cu") (net 1))
  (via (at 189.4 113.95) (size 0.6) (drill 0.25) (layers "F.Cu" "B.Cu") (net 1))
  (via (at 188.4 113.95) (size 0.6) (drill 0.25) (layers "F.Cu" "B.Cu") (net 1))
  (via (at 189.4 114.95) (size 0.6) (drill 0.25) (layers "F.Cu" "B.Cu") (net 1))
  (via (at 135.102449 75.748572) (size 0.45) (drill 0.1) (layers "F.Cu" "B.Cu") (net 1))
  (via (at 129.85 142.8) (size 0.6) (drill 0.25) (layers "F.Cu" "B.Cu") (net 1))
  (via (at 131.15 142.8) (size 0.6) (drill 0.25) (layers "F.Cu" "B.Cu") (net 1))
  (via (at 128.55 144.1) (size 0.6) (drill 0.25) (layers "F.Cu" "B.Cu") (net 1))
  (via (at 129.85 144.1) (size 0.6) (drill 0.25) (layers "F.Cu" "B.Cu") (net 1))
  (via (at 131.15 144.1) (size 0.6) (drill 0.25) (layers "F.Cu" "B.Cu") (net 1))
  (via (at 136.85 146.95) (size 0.6) (drill 0.25) (layers "F.Cu" "B.Cu") (net 1))
  (via (at 136.85 145.65) (size 0.6) (drill 0.25) (layers "F.Cu" "B.Cu") (net 1))
  (via (at 136.85 144.35) (size 0.6) (drill 0.25) (layers "F.Cu" "B.Cu") (net 1))
  (via (at 135.55 145.65) (size 0.6) (drill 0.25) (layers "F.Cu" "B.Cu") (net 1))
  (via (at 135.55 146.950001) (size 0.6) (drill 0.25) (layers "F.Cu" "B.Cu") (net 1))
  (via (at 135.55 144.35) (size 0.6) (drill 0.25) (layers "F.Cu" "B.Cu") (net 1))
  (via (at 123.4 144.1) (size 0.45) (drill 0.1) (layers "F.Cu" "B.Cu") (net 1))
  (via (at 123.4 142.8) (size 0.45) (drill 0.1) (layers "F.Cu" "B.Cu") (net 1))
  (via (at 120.5 76.25) (size 0.45) (drill 0.1) (layers "F.Cu" "B.Cu") (net 1))
  (via (at 120.11 76.56) (size 0.45) (drill 0.1) (layers "F.Cu" "B.Cu") (net 1))
  (via (at 120.1 77.15) (size 0.45) (drill 0.1) (layers "F.Cu" "B.Cu") (net 1))
  (via (at 113.189 75.791) (size 0.45) (drill 0.1) (layers "F.Cu" "B.Cu") (net 1))
  (via (at 115.723449 75.794571) (size 0.45) (drill 0.1) (layers "F.Cu" "B.Cu") (net 1))
  (via (at 143.2 67.75) (size 0.45) (drill 0.1) (layers "F.Cu" "B.Cu") (net 1))
  (via (at 133.4 112.8) (size 0.45) (drill 0.1) (layers "F.Cu" "B.Cu") (net 1))
  (via (at 115.3 120.9) (size 0.45) (drill 0.1) (layers "F.Cu" "B.Cu") (net 1))
  (via (at 114.45 121.6) (size 0.45) (drill 0.1) (layers "F.Cu" "B.Cu") (net 1))
  (via (at 115.3 121.6) (size 0.45) (drill 0.1) (layers "F.Cu" "B.Cu") (net 1))
  (via (at 124.356533 94.479921) (size 0.45) (drill 0.1) (layers "F.Cu" "B.Cu") (net 1))
  (via (at 125.746534 94.479921) (size 0.45) (drill 0.1) (layers "F.Cu" "B.Cu") (net 1))
  (via (at 191.025001 61.55) (size 0.6) (drill 0.25) (layers "F.Cu" "B.Cu") (net 1))
  (via (at 188.925 61.55) (size 0.6) (drill 0.25) (layers "F.Cu" "B.Cu") (net 1))
  (via (at 189.625 61.55) (size 0.6) (drill 0.25) (layers "F.Cu" "B.Cu") (net 1))
  (via (at 188.225 61.55) (size 0.6) (drill 0.25) (layers "F.Cu" "B.Cu") (net 1))
  (via (at 190.325 61.55) (size 0.6) (drill 0.25) (layers "F.Cu" "B.Cu") (net 1))
  (via (at 191.05 60.774999) (size 0.6) (drill 0.25) (layers "F.Cu" "B.Cu") (net 1))
  (via (at 191.05 60.075) (size 0.6) (drill 0.25) (layers "F.Cu" "B.Cu") (net 1))
  (via (at 191.05 59.374999) (size 0.6) (drill 0.25) (layers "F.Cu" "B.Cu") (net 1))
  (via (at 126.407018 83.241393) (size 0.45) (drill 0.1) (layers "F.Cu" "B.Cu") (net 1))
  (via (at 126.407018 84.631393) (size 0.45) (drill 0.1) (layers "F.Cu" "B.Cu") (net 1))
  (via (at 169.3 141.7) (size 0.45) (drill 0.1) (layers "F.Cu" "B.Cu") (net 1))
  (via (at 104.4 132.5) (size 0.45) (drill 0.1) (layers "F.Cu" "B.Cu") (net 1))
  (via (at 134.15 129.849723) (size 0.45) (drill 0.1) (layers "F.Cu" "B.Cu") (net 1))
  (via (at 134.15 131.174723) (size 0.45) (drill 0.1) (layers "F.Cu" "B.Cu") (net 1))
  (via (at 134.775 119.7) (size 0.45) (drill 0.1) (layers "F.Cu" "B.Cu") (net 1))
  (via (at 134.775 118.6) (size 0.45) (drill 0.1) (layers "F.Cu" "B.Cu") (net 1))
  (via (at 83.175 114.07) (size 0.45) (drill 0.1) (layers "F.Cu" "B.Cu") (net 1))
  (via (at 117.725 85) (size 0.45) (drill 0.1) (layers "F.Cu" "B.Cu") (net 1))
  (via (at 117.7 87.575) (size 0.45) (drill 0.1) (layers "F.Cu" "B.Cu") (net 1))
  (via (at 118.5 89.25) (size 0.45) (drill 0.1) (layers "F.Cu" "B.Cu") (net 1))
  (via (at 171.3 138.7) (size 0.45) (drill 0.1) (layers "F.Cu" "B.Cu") (net 1))
  (via (at 170.65 138.7) (size 0.45) (drill 0.1) (layers "F.Cu" "B.Cu") (net 1))
  (via (at 170.65 138.2) (size 0.45) (drill 0.1) (layers "F.Cu" "B.Cu") (net 1))
  (via (at 170.65 137.7) (size 0.45) (drill 0.1) (layers "F.Cu" "B.Cu") (net 1))
  (via (at 173.55 117.65) (size 0.45) (drill 0.1) (layers "F.Cu" "B.Cu") (net 1))
  (via (at 174.525 120.3) (size 0.45) (drill 0.1) (layers "F.Cu" "B.Cu") (net 1))
  (via (at 165.8 118.875) (size 0.5) (drill 0.15) (layers "F.Cu" "B.Cu") (net 1))
  (via (at 166.4 119.475) (size 0.5) (drill 0.15) (layers "F.Cu" "B.Cu") (net 1))
  (via (at 165.8 120.075) (size 0.5) (drill 0.15) (layers "F.Cu" "B.Cu") (net 1))
  (via (at 167 118.875) (size 0.5) (drill 0.15) (layers "F.Cu" "B.Cu") (net 1))
  (via (at 166.4 118.875) (size 0.5) (drill 0.15) (layers "F.Cu" "B.Cu") (net 1))
  (via (at 165.8 119.475) (size 0.5) (drill 0.15) (layers "F.Cu" "B.Cu") (net 1))
  (via (at 166.4 120.075) (size 0.5) (drill 0.15) (layers "F.Cu" "B.Cu") (net 1))
  (via (at 180.1 121.875) (size 0.45) (drill 0.1) (layers "F.Cu" "B.Cu") (net 1))
  (via (at 176.25 120.125) (size 0.5) (drill 0.15) (layers "F.Cu" "B.Cu") (net 1))
  (via (at 175.65 120.125) (size 0.5) (drill 0.15) (layers "F.Cu" "B.Cu") (net 1))
  (via (at 176.25 119.525) (size 0.5) (drill 0.15) (layers "F.Cu" "B.Cu") (net 1))
  (via (at 175.65 119.525) (size 0.5) (drill 0.15) (layers "F.Cu" "B.Cu") (net 1))
  (via (at 176.85 118.925) (size 0.5) (drill 0.15) (layers "F.Cu" "B.Cu") (net 1))
  (via (at 176.25 118.925) (size 0.5) (drill 0.15) (layers "F.Cu" "B.Cu") (net 1))
  (via (at 175.65 118.925) (size 0.5) (drill 0.15) (layers "F.Cu" "B.Cu") (net 1))
  (via (at 99.75 125.15) (size 0.55) (drill 0.2) (layers "F.Cu" "B.Cu") (net 1))
  (via (at 101.2 125.15) (size 0.55) (drill 0.2) (layers "F.Cu" "B.Cu") (net 1))
  (via (at 115.1 125.3) (size 0.55) (drill 0.2) (layers "F.Cu" "B.Cu") (net 1))
  (via (at 116.65 125.3) (size 0.55) (drill 0.2) (layers "F.Cu" "B.Cu") (net 1))
  (via (at 120.55 125.1) (size 0.55) (drill 0.2) (layers "F.Cu" "B.Cu") (net 1))
  (via (at 118.7 131.95) (size 0.55) (drill 0.2) (layers "F.Cu" "B.Cu") (net 1))
  (via (at 122.25 128.35) (size 0.55) (drill 0.2) (layers "F.Cu" "B.Cu") (net 1))
  (via (at 126.3 129.25) (size 0.55) (drill 0.2) (layers "F.Cu" "B.Cu") (net 1))
  (via (at 127.8 130.65) (size 0.55) (drill 0.2) (layers "F.Cu" "B.Cu") (net 1))
  (via (at 130.6 128.05) (size 0.55) (drill 0.2) (layers "F.Cu" "B.Cu") (net 1))
  (via (at 128.25 125.4) (size 0.55) (drill 0.2) (layers "F.Cu" "B.Cu") (net 1))
  (via (at 130.8 125.4) (size 0.55) (drill 0.2) (layers "F.Cu" "B.Cu") (net 1))
  (via (at 128.35 127.45) (size 0.55) (drill 0.2) (layers "F.Cu" "B.Cu") (net 1))
  (via (at 128.35 123.78) (size 0.55) (drill 0.2) (layers "F.Cu" "B.Cu") (free) (net 1))
  (via (at 130.8 123.8) (size 0.55) (drill 0.2) (layers "F.Cu" "B.Cu") (net 1))
  (via (at 128.3 120.45) (size 0.55) (drill 0.2) (layers "F.Cu" "B.Cu") (net 1))
  (via (at 130.1 115.45) (size 0.55) (drill 0.2) (layers "F.Cu" "B.Cu") (net 1))
  (via (at 130.6 113.3) (size 0.55) (drill 0.2) (layers "F.Cu" "B.Cu") (net 1))
  (via (at 135.05 111.95) (size 0.55) (drill 0.2) (layers "F.Cu" "B.Cu") (net 1))
  (via (at 120.85 116.5) (size 0.55) (drill 0.2) (layers "F.Cu" "B.Cu") (net 1))
  (via (at 127.1 110.15) (size 0.55) (drill 0.2) (layers "F.Cu" "B.Cu") (free) (net 1))
  (via (at 143.7 107.25) (size 0.55) (drill 0.2) (layers "F.Cu" "B.Cu") (net 1))
  (via (at 119.8 64.8) (size 0.55) (drill 0.2) (layers "F.Cu" "B.Cu") (net 1))
  (via (at 122 66.6) (size 0.55) (drill 0.2) (layers "F.Cu" "B.Cu") (net 1))
  (via (at 119.95 69.15) (size 0.55) (drill 0.2) (layers "F.Cu" "B.Cu") (net 1))
  (via (at 138.85 70.15) (size 0.55) (drill 0.2) (layers "F.Cu" "B.Cu") (net 1))
  (via (at 138.85 64.5) (size 0.55) (drill 0.2) (layers "F.Cu" "B.Cu") (net 1))
  (via (at 156.45 69.45) (size 0.55) (drill 0.2) (layers "F.Cu" "B.Cu") (net 1))
  (via (at 170 70.2) (size 0.55) (drill 0.2) (layers "F.Cu" "B.Cu") (net 1))
  (via (at 75.1 98.5) (size 0.55) (drill 0.2) (layers "F.Cu" "B.Cu") (net 1))
  (via (at 75.1 93.55) (size 0.55) (drill 0.2) (layers "F.Cu" "B.Cu") (net 1))
  (via (at 98.02 100.55) (size 0.55) (drill 0.2) (layers "F.Cu" "B.Cu") (net 1))
  (via (at 98.02 102.6) (size 0.55) (drill 0.2) (layers "F.Cu" "B.Cu") (net 1))
  (via (at 110.85 102) (size 0.55) (drill 0.2) (layers "F.Cu" "B.Cu") (net 1))
  (via (at 112.65 102) (size 0.55) (drill 0.2) (layers "F.Cu" "B.Cu") (free) (net 1))
  (via (at 114.4 91) (size 0.55) (drill 0.2) (layers "F.Cu" "B.Cu") (net 1))
  (via (at 136.3 110.9) (size 0.55) (drill 0.2) (layers "F.Cu" "B.Cu") (net 1))
  (via (at 154.35 131) (size 0.55) (drill 0.2) (layers "F.Cu" "B.Cu") (net 1))
  (via (at 150.95 133.3) (size 0.55) (drill 0.2) (layers "F.Cu" "B.Cu") (net 1))
  (via (at 153.9 133.1) (size 0.55) (drill 0.2) (layers "F.Cu" "B.Cu") (net 1))
  (via (at 178.45 141.95) (size 0.55) (drill 0.2) (layers "F.Cu" "B.Cu") (net 1))
  (via (at 159.5 85) (size 0.55) (drill 0.2) (layers "F.Cu" "B.Cu") (net 1))
  (via (at 133.95 77.95) (size 0.55) (drill 0.2) (layers "F.Cu" "B.Cu") (net 1))
  (via (at 133.95 76.65) (size 0.55) (drill 0.2) (layers "F.Cu" "B.Cu") (net 1))
  (via (at 133.2 86.1) (size 0.55) (drill 0.2) (layers "F.Cu" "B.Cu") (net 1))
  (via (at 133.2 79) (size 0.55) (drill 0.2) (layers "F.Cu" "B.Cu") (net 1))
  (via (at 140.3 77.85) (size 0.55) (drill 0.2) (layers "F.Cu" "B.Cu") (net 1))
  (via (at 141.6 77.55) (size 0.55) (drill 0.2) (layers "F.Cu" "B.Cu") (net 1))
  (via (at 146.01 69.62) (size 0.55) (drill 0.2) (layers "F.Cu" "B.Cu") (net 1))
  (via (at 98.02 104.7) (size 0.55) (drill 0.2) (layers "F.Cu" "B.Cu") (net 1))
  (via (at 107.45 105.35) (size 0.55) (drill 0.2) (layers "F.Cu" "B.Cu") (net 1))
  (via (at 106.1 95.9) (size 0.55) (drill 0.2) (layers "F.Cu" "B.Cu") (net 1))
  (via (at 106.15 97.25) (size 0.55) (drill 0.2) (layers "F.Cu" "B.Cu") (net 1))
  (via (at 113.65 97.55) (size 0.55) (drill 0.2) (layers "F.Cu" "B.Cu") (net 1))
  (via (at 97.25 93.25) (size 0.55) (drill 0.2) (layers "F.Cu" "B.Cu") (net 1))
  (via (at 85.775 101.575) (size 0.55) (drill 0.2) (layers "F.Cu" "B.Cu") (net 1))
  (via (at 85.775 102.4) (size 0.55) (drill 0.2) (layers "F.Cu" "B.Cu") (net 1))
  (via (at 85.8 106.65) (size 0.55) (drill 0.2) (layers "F.Cu" "B.Cu") (net 1))
  (via (at 85.8 107.95) (size 0.55) (drill 0.2) (layers "F.Cu" "B.Cu") (net 1))
  (via (at 85.8 109.6) (size 0.55) (drill 0.2) (layers "F.Cu" "B.Cu") (net 1))
  (via (at 85.85 113.15) (size 0.55) (drill 0.2) (layers "F.Cu" "B.Cu") (net 1))
  (via (at 84.9 112.15) (size 0.55) (drill 0.2) (layers "F.Cu" "B.Cu") (free) (net 1))
  (via (at 88.9 108.05) (size 0.55) (drill 0.2) (layers "F.Cu" "B.Cu") (net 1))
  (via (at 88.75 120.85) (size 0.55) (drill 0.2) (layers "F.Cu" "B.Cu") (net 1))
  (via (at 92.8 137.7) (size 0.55) (drill 0.2) (layers "F.Cu" "B.Cu") (net 1))
  (via (at 146.925 77.2) (size 0.45) (drill 0.1) (layers "F.Cu" "B.Cu") (net 1))
  (via (at 146.325 77.2) (size 0.45) (drill 0.1) (layers "F.Cu" "B.Cu") (net 1))
  (via (at 145.525 78) (size 0.45) (drill 0.1) (layers "F.Cu" "B.Cu") (net 1))
  (via (at 145.025 77.5) (size 0.45) (drill 0.1) (layers "F.Cu" "B.Cu") (net 1))
  (via (at 151.325 78.2) (size 0.55) (drill 0.2) (layers "F.Cu" "B.Cu") (net 1))
  (via (at 143.775 75.5) (size 0.45) (drill 0.1) (layers "F.Cu" "B.Cu") (net 1))
  (via (at 139.225 116.85) (size 0.45) (drill 0.1) (layers "F.Cu" "B.Cu") (net 1))
  (via (at 84.1 99.5) (size 0.45) (drill 0.1) (layers "F.Cu" "B.Cu") (net 1))
  (via (at 84.1 100.7) (size 0.45) (drill 0.1) (layers "F.Cu" "B.Cu") (free) (net 1))
  (via (at 85.325 102) (size 0.55) (drill 0.2) (layers "F.Cu" "B.Cu") (free) (net 1))
  (via (at 108.5 90.75) (size 0.45) (drill 0.1) (layers "F.Cu" "B.Cu") (net 1))
  (via (at 107.9 90.75) (size 0.45) (drill 0.1) (layers "F.Cu" "B.Cu") (net 1))
  (via (at 109.05 90.75) (size 0.45) (drill 0.1) (layers "F.Cu" "B.Cu") (net 1))
  (via (at 109.65 90.75) (size 0.45) (drill 0.1) (layers "F.Cu" "B.Cu") (net 1))
  (via (at 99.3 88.7) (size 0.45) (drill 0.1) (layers "F.Cu" "B.Cu") (net 1))
  (via (at 102.592715 82.895238) (size 0.55) (drill 0.2) (layers "F.Cu" "B.Cu") (net 1))
  (via (at 100.292715 85.695238) (size 0.55) (drill 0.2) (layers "F.Cu" "B.Cu") (net 1))
  (via (at 91.995238 151.407285) (size 0.55) (drill 0.2) (layers "F.Cu" "B.Cu") (net 1))
  (via (at 79.395238 151.407285) (size 0.55) (drill 0.2) (layers "F.Cu" "B.Cu") (net 1))
  (via (at 177.145238 151.307285) (size 0.55) (drill 0.2) (layers "F.Cu" "B.Cu") (net 1))
  (via (at 158.245238 151.307285) (size 0.55) (drill 0.2) (layers "F.Cu" "B.Cu") (net 1))
  (via (at 164.545238 151.307285) (size 0.55) (drill 0.2) (layers "F.Cu" "B.Cu") (net 1))
  (via (at 151.945238 151.307285) (size 0.55) (drill 0.2) (layers "F.Cu" "B.Cu") (net 1))
  (via (at 170.845238 151.307285) (size 0.55) (drill 0.2) (layers "F.Cu" "B.Cu") (net 1))
  (via (at 146.945238 151.107285) (size 0.55) (drill 0.2) (layers "F.Cu" "B.Cu") (net 1))
  (via (at 121.745238 151.107285) (size 0.55) (drill 0.2) (layers "F.Cu" "B.Cu") (net 1))
  (via (at 105.745238 151.307285) (size 0.55) (drill 0.2) (layers "F.Cu" "B.Cu") (net 1))
  (via (at 112.045238 151.307285) (size 0.55) (drill 0.2) (layers "F.Cu" "B.Cu") (free) (net 1))
  (via (at 99.445238 151.307285) (size 0.55) (drill 0.2) (layers "F.Cu" "B.Cu") (net 1))
  (via (at 108.495238 52.957285) (size 0.55) (drill 0.2) (layers "F.Cu" "B.Cu") (net 1))
  (via (at 89.595238 52.957285) (size 0.55) (drill 0.2) (layers "F.Cu" "B.Cu") (net 1))
  (via (at 95.895237 52.957285) (size 0.55) (drill 0.2) (layers "F.Cu" "B.Cu") (free) (net 1))
  (via (at 83.295238 52.957285) (size 0.55) (drill 0.2) (layers "F.Cu" "B.Cu") (net 1))
  (via (at 102.195238 52.957285) (size 0.55) (drill 0.2) (layers "F.Cu" "B.Cu") (net 1))
  (via (at 120.645238 52.907285) (size 0.55) (drill 0.2) (layers "F.Cu" "B.Cu") (net 1))
  (via (at 139.545238 52.907285) (size 0.55) (drill 0.2) (layers "F.Cu" "B.Cu") (net 1))
  (via (at 126.945237 52.907285) (size 0.55) (drill 0.2) (layers "F.Cu" "B.Cu") (net 1))
  (via (at 133.245238 52.907285) (size 0.55) (drill 0.2) (layers "F.Cu" "B.Cu") (net 1))
  (via (at 114.345238 52.907285) (size 0.55) (drill 0.2) (layers "F.Cu" "B.Cu") (net 1))
  (via (at 171.445238 52.907285) (size 0.55) (drill 0.2) (layers "F.Cu" "B.Cu") (net 1))
  (via (at 165.145238 52.907285) (size 0.55) (drill 0.2) (layers "F.Cu" "B.Cu") (net 1))
  (via (at 158.845237 52.907285) (size 0.55) (drill 0.2) (layers "F.Cu" "B.Cu") (net 1))
  (via (at 152.545238 52.907285) (size 0.55) (drill 0.2) (layers "F.Cu" "B.Cu") (net 1))
  (via (at 146.245238 52.907285) (size 0.55) (drill 0.2) (layers "F.Cu" "B.Cu") (net 1))
  (via (at 184.445238 52.857285) (size 0.55) (drill 0.2) (layers "F.Cu" "B.Cu") (net 1))
  (via (at 178.145238 52.857285) (size 0.55) (drill 0.2) (layers "F.Cu" "B.Cu") (free) (net 1))
  (via (at 191.007285 104.104763) (size 0.55) (drill 0.2) (layers "F.Cu" "B.Cu") (net 1))
  (via (at 191.007285 110.404762) (size 0.55) (drill 0.2) (layers "F.Cu" "B.Cu") (net 1))
  (via (at 191.007285 97.804762) (size 0.55) (drill 0.2) (layers "F.Cu" "B.Cu") (net 1))
  (via (at 183.695238 151.307285) (size 0.55) (drill 0.2) (layers "F.Cu" "B.Cu") (net 1))
  (via (at 191.107285 139.904762) (size 0.45) (drill 0.1) (layers "F.Cu" "B.Cu") (net 1))
  (via (at 191.107285 146.204762) (size 0.55) (drill 0.2) (layers "F.Cu" "B.Cu") (net 1))
  (via (at 191.257285 128) (size 0.55) (drill 0.2) (layers "F.Cu" "B.Cu") (net 1))
  (via (at 191.257285 131.404762) (size 0.55) (drill 0.2) (layers "F.Cu" "B.Cu") (net 1))
  (via (at 180 128.7) (size 0.45) (drill 0.1) (layers "F.Cu" "B.Cu") (net 1))
  (via (at 177.6 126.975) (size 0.6) (drill 0.25) (layers "F.Cu" "B.Cu") (net 1))
  (via (at 178.1 126.475) (size 0.6) (drill 0.25) (layers "F.Cu" "B.Cu") (net 1))
  (via (at 178.185 124.575) (size 0.6) (drill 0.25) (layers "F.Cu" "B.Cu") (net 1))
  (via (at 178.1 125.475) (size 0.6) (drill 0.25) (layers "F.Cu" "B.Cu") (net 1))
  (via (at 177.6 124.975) (size 0.6) (drill 0.25) (layers "F.Cu" "B.Cu") (net 1))
  (via (at 177.6 125.975) (size 0.6) (drill 0.25) (layers "F.Cu" "B.Cu") (net 1))
  (via (at 176.73 127.785) (size 0.6) (drill 0.25) (layers "F.Cu" "B.Cu") (net 1))
  (via (at 172.075 127.475) (size 0.6) (drill 0.25) (layers "F.Cu" "B.Cu") (net 1))
  (via (at 171.375 127.475) (size 0.6) (drill 0.25) (layers "F.Cu" "B.Cu") (net 1))
  (via (at 172.075 126.725) (size 0.6) (drill 0.25) (layers "F.Cu" "B.Cu") (net 1))
  (via (at 171.375 126.725) (size 0.6) (drill 0.25) (layers "F.Cu" "B.Cu") (net 1))
  (via (at 172.075 128.175) (size 0.6) (drill 0.25) (layers "F.Cu" "B.Cu") (net 1))
  (via (at 171.375 128.175) (size 0.6) (drill 0.25) (layers "F.Cu" "B.Cu") (net 1))
  (via (at 171.375 128.925) (size 0.6) (drill 0.25) (layers "F.Cu" "B.Cu") (net 1))
  (via (at 172.775 128.925) (size 0.6) (drill 0.25) (layers "F.Cu" "B.Cu") (net 1))
  (via (at 172.075 128.925) (size 0.6) (drill 0.25) (layers "F.Cu" "B.Cu") (net 1))
  (via (at 169.05 129.825) (size 0.6) (drill 0.25) (layers "F.Cu" "B.Cu") (net 1))
  (via (at 168.35 129.825) (size 0.6) (drill 0.25) (layers "F.Cu" "B.Cu") (net 1))
  (via (at 167.65 129.825) (size 0.6) (drill 0.25) (layers "F.Cu" "B.Cu") (net 1))
  (via (at 166.95 130.475) (size 0.6) (drill 0.25) (layers "F.Cu" "B.Cu") (net 1))
  (via (at 166.95 129.825) (size 0.6) (drill 0.25) (layers "F.Cu" "B.Cu") (net 1))
  (via (at 166.25 130.475) (size 0.6) (drill 0.25) (layers "F.Cu" "B.Cu") (net 1))
  (via (at 166.25 129.825) (size 0.6) (drill 0.25) (layers "F.Cu" "B.Cu") (net 1))
  (via (at 122.475 91.795) (size 0.45) (drill 0.1) (layers "F.Cu" "B.Cu") (net 1))
  (via (at 155.4 68.525) (size 0.45) (drill 0.1) (layers "F.Cu" "B.Cu") (net 1))
  (via (at 146 71.09) (size 0.55) (drill 0.2) (layers "F.Cu" "B.Cu") (net 1))
  (via (at 143.975 71.125) (size 0.45) (drill 0.1) (layers "F.Cu" "B.Cu") (net 1))
  (via (at 149.2 74.65) (size 0.45) (drill 0.1) (layers "F.Cu" "B.Cu") (net 1))
  (via (at 148.85 75) (size 0.45) (drill 0.1) (layers "F.Cu" "B.Cu") (net 1))
  (via (at 147.675 76.675) (size 0.45) (drill 0.1) (layers "F.Cu" "B.Cu") (net 1))
  (via (at 133.34 72.86) (size 0.45) (drill 0.1) (layers "F.Cu" "B.Cu") (net 1))
  (via (at 131.73 72.87) (size 0.45) (drill 0.1) (layers "F.Cu" "B.Cu") (net 1))
  (via (at 107.69 73.24) (size 0.45) (drill 0.1) (layers "F.Cu" "B.Cu") (net 1))
  (via (at 108.03 74.4) (size 0.45) (drill 0.1) (layers "F.Cu" "B.Cu") (net 1))
  (via (at 125.65 71.61) (size 0.45) (drill 0.1) (layers "F.Cu" "B.Cu") (net 1))
  (via (at 127.04 73.61) (size 0.45) (drill 0.1) (layers "F.Cu" "B.Cu") (net 1))
  (via (at 113.98 72.9) (size 0.45) (drill 0.1) (layers "F.Cu" "B.Cu") (net 1))
  (via (at 112.42 72.9) (size 0.45) (drill 0.1) (layers "F.Cu" "B.Cu") (net 1))
  (via (at 116.37 72.06) (size 0.45) (drill 0.1) (layers "F.Cu" "B.Cu") (net 1))
  (via (at 115.1 72.06) (size 0.45) (drill 0.1) (layers "F.Cu" "B.Cu") (net 1))
  (via (at 104.74 74.95) (size 0.55) (drill 0.2) (layers "F.Cu" "B.Cu") (net 1))
  (via (at 109.02 132.42) (size 0.55) (drill 0.2) (layers "F.Cu" "B.Cu") (net 1))
  (via (at 105.48 117.97) (size 0.55) (drill 0.2) (layers "F.Cu" "B.Cu") (net 1))
  (via (at 112 123.55) (size 0.5) (drill 0.15) (layers "F.Cu" "B.Cu") (net 1))
  (via (at 79.524999 109.99) (size 0.45) (drill 0.1) (layers "F.Cu" "B.Cu") (net 1))
  (via (at 78.875001 107.177514) (size 0.45) (drill 0.1) (layers "F.Cu" "B.Cu") (net 1))
  (via (at 79.374999 111.397486) (size 0.45) (drill 0.1) (layers "F.Cu" "B.Cu") (net 1))
  (via (at 78.824999 114.197486) (size 0.45) (drill 0.1) (layers "F.Cu" "B.Cu") (net 1))
  (via (at 77.8 102.31) (size 0.45) (drill 0.1) (layers "F.Cu" "B.Cu") (net 1))
  (via (at 78.749999 102.29) (size 0.45) (drill 0.1) (layers "F.Cu" "B.Cu") (net 1))
  (via (at 77.950001 99.477514) (size 0.45) (drill 0.1) (layers "F.Cu" "B.Cu") (net 1))
  (via (at 77.95 100.867514) (size 0.45) (drill 0.1) (layers "F.Cu" "B.Cu") (net 1))
  (via (at 78.85 103.7) (size 0.45) (drill 0.1) (layers "F.Cu" "B.Cu") (net 1))
  (via (at 77.8 103.7) (size 0.45) (drill 0.1) (layers "F.Cu" "B.Cu") (net 1))
  (via (at 78.75 100.9) (size 0.45) (drill 0.1) (layers "F.Cu" "B.Cu") (net 1))
  (via (at 113.29 87.45) (size 0.45) (drill 0.1) (layers "F.Cu" "B.Cu") (net 1))
  (via (at 113.285 88.435) (size 0.45) (drill 0.1) (layers "F.Cu" "B.Cu") (net 1))
  (via (at 134.8 92.8) (size 0.45) (drill 0.1) (layers "F.Cu" "B.Cu") (net 1))
  (via (at 83.3 97.3) (size 0.45) (drill 0.1) (layers "F.Cu" "B.Cu") (net 1))
  (via (at 83.275 98.75) (size 0.45) (drill 0.1) (layers "F.Cu" "B.Cu") (net 1))
  (via (at 92.84 136.029) (size 0.45) (drill 0.1) (layers "F.Cu" "B.Cu") (net 1))
  (via (at 122.11 81.84) (size 0.45) (drill 0.1) (layers "F.Cu" "B.Cu") (net 1))
  (via (at 124.81 81.84) (size 0.45) (drill 0.1) (layers "F.Cu" "B.Cu") (net 1))
  (via (at 119.41 84.54) (size 0.45) (drill 0.1) (layers "F.Cu" "B.Cu") (net 1))
  (via (at 122.11 84.54) (size 0.45) (drill 0.1) (layers "F.Cu" "B.Cu") (net 1))
  (via (at 124.81 84.54) (size 0.45) (drill 0.1) (layers "F.Cu" "B.Cu") (net 1))
  (via (at 119.41 87.24) (size 0.45) (drill 0.1) (layers "F.Cu" "B.Cu") (net 1))
  (via (at 122.11 87.24) (size 0.45) (drill 0.1) (layers "F.Cu" "B.Cu") (net 1))
  (via (at 124.81 87.24) (size 0.45) (drill 0.1) (layers "F.Cu" "B.Cu") (net 1))
  (via (at 150.7 60.6) (size 0.45) (drill 0.1) (layers "F.Cu" "B.Cu") (net 1))
  (via (at 151.3 60.6) (size 0.45) (drill 0.1) (layers "F.Cu" "B.Cu") (net 1))
  (via (at 151.9 60.6) (size 0.45) (drill 0.1) (layers "F.Cu" "B.Cu") (net 1))
  (via (at 150.7 61.2) (size 0.45) (drill 0.1) (layers "F.Cu" "B.Cu") (net 1))
  (via (at 151.3 61.2) (size 0.45) (drill 0.1) (layers "F.Cu" "B.Cu") (net 1))
  (via (at 151.9 61.2) (size 0.45) (drill 0.1) (layers "F.Cu" "B.Cu") (net 1))
  (via (at 94.4 106.8265) (size 0.45) (drill 0.1) (layers "F.Cu" "B.Cu") (net 1))
  (via (at 89.32 106.8265) (size 0.45) (drill 0.1) (layers "F.Cu" "B.Cu") (net 1))
  (via (at 91.86 104.2865) (size 0.45) (drill 0.1) (layers "F.Cu" "B.Cu") (net 1))
  (via (at 89.698 104.287) (size 0.45) (drill 0.1) (layers "F.Cu" "B.Cu") (net 1))
  (via (at 92.238 104.287) (size 0.45) (drill 0.1) (layers "F.Cu" "B.Cu") (net 1))
  (via (at 94.4 104.2865) (size 0.45) (drill 0.1) (layers "F.Cu" "B.Cu") (net 1))
  (via (at 90.9 105.5565) (size 0.45) (drill 0.1) (layers "F.Cu" "B.Cu") (net 1))
  (via (at 88.738 105.557) (size 0.45) (drill 0.1) (layers "F.Cu" "B.Cu") (net 1))
  (via (at 91.278 105.557) (size 0.45) (drill 0.1) (layers "F.Cu" "B.Cu") (net 1))
  (via (at 93.45 105.5565) (size 0.45) (drill 0.1) (layers "F.Cu" "B.Cu") (net 1))
  (via (at 90.9 103.0165) (size 0.45) (drill 0.1) (layers "F.Cu" "B.Cu") (net 1))
  (via (at 88.738 103.017) (size 0.45) (drill 0.1) (layers "F.Cu" "B.Cu") (net 1))
  (via (at 91.278 103.017) (size 0.45) (drill 0.1) (layers "F.Cu" "B.Cu") (net 1))
  (via (at 93.948 105.537) (size 0.45) (drill 0.1) (layers "F.Cu" "B.Cu") (net 1))
  (via (at 93.818 103.017) (size 0.45) (drill 0.1) (layers "F.Cu" "B.Cu") (net 1))
  (via (at 93.44 103.0165) (size 0.45) (drill 0.1) (layers "F.Cu" "B.Cu") (net 1))
  (via (at 90.3 101.75) (size 0.45) (drill 0.1) (layers "F.Cu" "B.Cu") (net 1))
  (via (at 89.34 101.745) (size 0.45) (drill 0.1) (layers "F.Cu" "B.Cu") (net 1))
  (via (at 91.88 101.745) (size 0.45) (drill 0.1) (layers "F.Cu" "B.Cu") (net 1))
  (via (at 92.84 101.75) (size 0.45) (drill 0.1) (layers "F.Cu" "B.Cu") (net 1))
  (via (at 120.130557 98.191723) (size 0.45) (drill 0.1) (layers "F.Cu" "B.Cu") (net 1))
  (via (at 121.130557 98.191723) (size 0.45) (drill 0.1) (layers "F.Cu" "B.Cu") (net 1))
  (via (at 122.130557 98.191723) (size 0.45) (drill 0.1) (layers "F.Cu" "B.Cu") (net 1))
  (via (at 120.130557 98.941723) (size 0.45) (drill 0.1) (layers "F.Cu" "B.Cu") (net 1))
  (via (at 121.130557 98.941723) (size 0.45) (drill 0.1) (layers "F.Cu" "B.Cu") (net 1))
  (via (at 122.130557 99.691723) (size 0.45) (drill 0.1) (layers "F.Cu" "B.Cu") (net 1))
  (via (at 188.2 124.3) (size 0.45) (drill 0.1) (layers "F.Cu" "B.Cu") (net 1))
  (via (at 189 124.3) (size 0.45) (drill 0.1) (layers "F.Cu" "B.Cu") (net 1))
  (via (at 135.268 93.029) (size 0.45) (drill 0.1) (layers "F.Cu" "B.Cu") (net 1))
  (via (at 140.112 96.268) (size 0.45) (drill 0.1) (layers "F.Cu" "B.Cu") (net 1))
  (via (at 83.16 105.75) (size 0.45) (drill 0.1) (layers "F.Cu" "B.Cu") (net 1))
  (via (at 172.55 131.2) (size 0.45) (drill 0.1) (layers "F.Cu" "B.Cu") (net 1))
  (via (at 101.78 97.85) (size 0.45) (drill 0.1) (layers "F.Cu" "B.Cu") (net 1))
  (via (at 112.125 96.025) (size 0.45) (drill 0.1) (layers "F.Cu" "B.Cu") (net 1))
  (via (at 93.25 69.4) (size 0.45) (drill 0.1) (layers "F.Cu" "B.Cu") (net 1))
  (via (at 135.01 120.19) (size 0.45) (drill 0.1) (layers "F.Cu" "B.Cu") (net 1))
  (via (at 139.4 136.2) (size 0.45) (drill 0.1) (layers "F.Cu" "B.Cu") (net 1))
  (via (at 160.42 122.695) (size 0.45) (drill 0.1) (layers "F.Cu" "B.Cu") (net 1))
  (via (at 74.792715 77.995238) (size 0.55) (drill 0.2) (layers "F.Cu" "B.Cu") (net 1))
  (via (at 158.480001 115.0745) (size 0.45) (drill 0.1) (layers "F.Cu" "B.Cu") (net 1))
  (via (at 138.115 82.115) (size 0.6) (drill 0.25) (layers "F.Cu" "B.Cu") (net 1))
  (via (at 183.7 118.8) (size 0.45) (drill 0.1) (layers "F.Cu" "B.Cu") (net 1))
  (via (at 108.624998 142.24) (size 0.45) (drill 0.1) (layers "F.Cu" "B.Cu") (net 1))
  (via (at 130.75 147.85) (size 0.45) (drill 0.1) (layers "F.Cu" "B.Cu") (net 1))
  (via (at 160.42 136.03) (size 0.45) (drill 0.1) (layers "F.Cu" "B.Cu") (net 1))
  (via (at 92.84 132.225) (size 0.45) (drill 0.1) (layers "F.Cu" "B.Cu") (net 1))
  (via (at 86.55 149.3) (size 0.55) (drill 0.2) (layers "F.Cu" "B.Cu") (net 1))
  (via (at 145 79.1) (size 0.45) (drill 0.1) (layers "F.Cu" "B.Cu") (net 1))
  (via (at 92.84 129.055) (size 0.45) (drill 0.1) (layers "F.Cu" "B.Cu") (net 1))
  (via (at 179.092715 103.195238) (size 0.55) (drill 0.2) (layers "F.Cu" "B.Cu") (net 1))
  (via (at 137.8 136.3) (size 0.45) (drill 0.1) (layers "F.Cu" "B.Cu") (net 1))
  (via (at 156.913001 130.9765) (size 0.45) (drill 0.1) (layers "F.Cu" "B.Cu") (net 1))
  (via (at 129.39 86.13) (size 0.45) (drill 0.1) (layers "F.Cu" "B.Cu") (net 1))
  (via (at 90.3 128.415) (size 0.45) (drill 0.1) (layers "F.Cu" "B.Cu") (net 1))
  (via (at 140.408148 128.566854) (size 0.45) (drill 0.1) (layers "F.Cu" "B.Cu") (net 1))
  (via (at 183.6 134.425) (size 0.45) (drill 0.1) (layers "F.Cu" "B.Cu") (net 1))
  (via (at 145.6 120.7) (size 0.45) (drill 0.1) (layers "F.Cu" "B.Cu") (net 1))
  (via (at 169.992715 73.795238) (size 0.55) (drill 0.2) (layers "F.Cu" "B.Cu") (free) (net 1))
  (via (at 117.75 81.45) (size 0.45) (drill 0.1) (layers "F.Cu" "B.Cu") (net 1))
  (via (at 107.2 97.95) (size 0.45) (drill 0.1) (layers "F.Cu" "B.Cu") (net 1))
  (via (at 150.6 83.6) (size 0.45) (drill 0.1) (layers "F.Cu" "B.Cu") (net 1))
  (via (at 123.85 149.3) (size 0.6) (drill 0.25) (layers "F.Cu" "B.Cu") (net 1))
  (via (at 98.025 149.3) (size 0.45) (drill 0.1) (layers "F.Cu" "B.Cu") (net 1))
  (via (at 139.725 121.08) (size 0.45) (drill 0.1) (layers "F.Cu" "B.Cu") (net 1))
  (via (at 83.09 108.76) (size 0.45) (drill 0.1) (layers "F.Cu" "B.Cu") (net 1))
  (via (at 109.595 143.47) (size 0.45) (drill 0.1) (layers "F.Cu" "B.Cu") (net 1))
  (via (at 137.275 120.74) (size 0.45) (drill 0.1) (layers "F.Cu" "B.Cu") (net 1))
  (via (at 169.292715 93.395238) (size 0.55) (drill 0.2) (layers "F.Cu" "B.Cu") (net 1))
  (via (at 149.53 88.03) (size 0.45) (drill 0.1) (layers "F.Cu" "B.Cu") (net 1))
  (via (at 93.44 100.4765) (size 0.45) (drill 0.1) (layers "F.Cu" "B.Cu") (net 1))
  (via (at 133.5 123.825) (size 0.45) (drill 0.1) (layers "F.Cu" "B.Cu") (net 1))
  (via (at 74.792715 71.695238) (size 0.55) (drill 0.2) (layers "F.Cu" "B.Cu") (net 1))
  (via (at 146.049684 141.550316) (size 0.45) (drill 0.1) (layers "F.Cu" "B.Cu") (net 1))
  (via (at 133.4 114.3) (size 0.45) (drill 0.1) (layers "F.Cu" "B.Cu") (net 1))
  (via (at 90.29971 132.227333) (size 0.45) (drill 0.1) (layers "F.Cu" "B.Cu") (net 1))
  (via (at 90.7 69.5) (size 0.45) (drill 0.1) (layers "F.Cu" "B.Cu") (net 1))
  (via (at 90.25 71.4) (size 0.45) (drill 0.1) (layers "F.Cu" "B.Cu") (net 1))
  (via (at 156.7 85.1) (size 0.45) (drill 0.1) (layers "F.Cu" "B.Cu") (net 1))
  (via (at 82.575 119.05) (size 0.45) (drill 0.1) (layers "F.Cu" "B.Cu") (net 1))
  (via (at 111.103011 142.9) (size 0.45) (drill 0.1) (layers "F.Cu" "B.Cu") (net 1))
  (via (at 138.2075 137.223505) (size 0.45) (drill 0.1) (layers "F.Cu" "B.Cu") (net 1))
  (via (at 146.2 83.5) (size 0.45) (drill 0.1) (layers "F.Cu" "B.Cu") (net 1))
  (via (at 149.53 89.39) (size 0.45) (drill 0.1) (layers "F.Cu" "B.Cu") (net 1))
  (via (at 83.08 110.26) (size 0.45) (drill 0.1) (layers "F.Cu" "B.Cu") (net 1))
  (via (at 99.92 105.39) (size 0.45) (drill 0.1) (layers "F.Cu" "B.Cu") (net 1))
  (via (at 157.88 103.01) (size 0.45) (drill 0.1) (layers "F.Cu" "B.Cu") (net 1))
  (via (at 165.792715 96.195238) (size 0.55) (drill 0.2) (layers "F.Cu" "B.Cu") (net 1))
  (via (at 173.492715 101.795238) (size 0.55) (drill 0.2) (layers "F.Cu" "B.Cu") (net 1))
  (via (at 120.93 91.86) (size 0.45) (drill 0.1) (layers "F.Cu" "B.Cu") (net 1))
  (via (at 107.44451 138.890675) (size 0.45) (drill 0.1) (layers "F.Cu" "B.Cu") (net 1))
  (via (at 91.55 67.75) (size 0.45) (drill 0.1) (layers "F.Cu" "B.Cu") (net 1))
  (via (at 157.88 105.55) (size 0.45) (drill 0.1) (layers "F.Cu" "B.Cu") (net 1))
  (via (at 90.3 129.055) (size 0.45) (drill 0.1) (layers "F.Cu" "B.Cu") (net 1))
  (via (at 81.792715 70.995238) (size 0.55) (drill 0.2) (layers "F.Cu" "B.Cu") (free) (net 1))
  (via (at 157.88 111.265) (size 0.45) (drill 0.1) (layers "F.Cu" "B.Cu") (net 1))
  (via (at 140.25 86.85) (size 0.45) (drill 0.1) (layers "F.Cu" "B.Cu") (net 1))
  (via (at 160.892715 62.595238) (size 0.55) (drill 0.2) (layers "F.Cu" "B.Cu") (net 1))
  (via (at 77.835 88.35) (size 0.45) (drill 0.1) (layers "F.Cu" "B.Cu") (net 1))
  (via (at 102.810978 141.9) (size 0.45) (drill 0.1) (layers "F.Cu" "B.Cu") (net 1))
  (via (at 160.42 124.6) (size 0.45) (drill 0.1) (layers "F.Cu" "B.Cu") (net 1))
  (via (at 93.7115 113.183999) (size 0.45) (drill 0.1) (layers "F.Cu" "B.Cu") (net 1))
  (via (at 108.3 137.5) (size 0.45) (drill 0.1) (layers "F.Cu" "B.Cu") (net 1))
  (via (at 91.44 75.02) (size 0.45) (drill 0.1) (layers "F.Cu" "B.Cu") (net 1))
  (via (at 191.2 68.3) (size 0.45) (drill 0.15) (layers "F.Cu" "B.Cu") (net 1))
  (via (at 89.94 139.93) (size 0.55) (drill 0.2) (layers "F.Cu" "B.Cu") (net 1))
  (via (at 155.940001 118.8845) (size 0.45) (drill 0.1) (layers "F.Cu" "B.Cu") (net 1))
  (via (at 141.07637 143.415753) (size 0.45) (drill 0.1) (layers "F.Cu" "B.Cu") (net 1))
  (via (at 157.88 116.98) (size 0.45) (drill 0.1) (layers "F.Cu" "B.Cu") (net 1))
  (via (at 83.2545 101.65) (size 0.45) (drill 0.1) (layers "F.Cu" "B.Cu") (net 1))
  (via (at 176.992715 98.995238) (size 0.55) (drill 0.2) (layers "F.Cu" "B.Cu") (net 1))
  (via (at 123.6 127.3) (size 0.45) (drill 0.1) (layers "F.Cu" "B.Cu") (net 1))
  (via (at 78.92 112.87) (size 0.45) (drill 0.1) (layers "F.Cu" "B.Cu") (net 1))
  (via (at 86 69.799976) (size 0.45) (drill 0.1) (layers "F.Cu" "B.Cu") (net 1))
  (via (at 157.880001 133.4895) (size 0.45) (drill 0.1) (layers "F.Cu" "B.Cu") (net 1))
  (via (at 90.3 130.32) (size 0.45) (drill 0.1) (layers "F.Cu" "B.Cu") (net 1))
  (via (at 75.492715 89.895238) (size 0.55) (drill 0.2) (layers "F.Cu" "B.Cu") (net 1))
  (via (at 152.4 84.1) (size 0.45) (drill 0.1) (layers "F.Cu" "B.Cu") (net 1))
  (via (at 92.84 130.32) (size 0.45) (drill 0.1) (layers "F.Cu" "B.Cu") (net 1))
  (via (at 74.792715 126.995238) (size 0.55) (drill 0.2) (layers "F.Cu" "B.Cu") (net 1))
  (via (at 108.17627 142.761993) (size 0.45) (drill 0.1) (layers "F.Cu" "B.Cu") (net 1))
  (via (at 155.940001 120.7895) (size 0.45) (drill 0.1) (layers "F.Cu" "B.Cu") (net 1))
  (via (at 115.777 118.85) (size 0.45) (drill 0.1) (layers "F.Cu" "B.Cu") (net 1))
  (via (at 144.5 79.6) (size 0.45) (drill 0.1) (layers "F.Cu" "B.Cu") (net 1))
  (via (at 83.1 136) (size 0.45) (drill 0.1) (layers "F.Cu" "B.Cu") (net 1))
  (via (at 112.775 120.175) (size 0.45) (drill 0.1) (layers "F.Cu" "B.Cu") (net 1))
  (via (at 136.975 81.365) (size 0.6) (drill 0.25) (layers "F.Cu" "B.Cu") (net 1))
  (via (at 120.21241 88.822937) (size 0.45) (drill 0.1) (layers "F.Cu" "B.Cu") (net 1))
  (via (at 98.25 97.25) (size 0.45) (drill 0.1) (layers "F.Cu" "B.Cu") (net 1))
  (via (at 157.88 108.09) (size 0.45) (drill 0.1) (layers "F.Cu" "B.Cu") (net 1))
  (via (at 91.4 69.5) (size 0.45) (drill 0.1) (layers "F.Cu" "B.Cu") (net 1))
  (via (at 107.25 121.925) (size 0.45) (drill 0.1) (layers "F.Cu" "B.Cu") (net 1))
  (via (at 125.515 98.875) (size 0.5) (drill 0.15) (layers "F.Cu" "B.Cu") (net 1))
  (via (at 137.265 122.06) (size 0.45) (drill 0.1) (layers "F.Cu" "B.Cu") (net 1))
  (via (at 158.092715 83.595238) (size 0.55) (drill 0.2) (layers "F.Cu" "B.Cu") (net 1))
  (via (at 122.615557 96.026723) (size 0.45) (drill 0.1) (layers "F.Cu" "B.Cu") (net 1))
  (via (at 91.9815 109.994) (size 0.45) (drill 0.1) (layers "F.Cu" "B.Cu") (net 1))
  (via (at 99.64 97.85) (size 0.45) (drill 0.1) (layers "F.Cu" "B.Cu") (net 1))
  (via (at 91.49 85.700002) (size 0.45) (drill 0.1) (layers "F.Cu" "B.Cu") (net 1))
  (via (at 85.78 72.721) (size 0.45) (drill 0.1) (layers "F.Cu" "B.Cu") (free) (net 1))
  (via (at 88.092715 68.895238) (size 0.55) (drill 0.2) (layers "F.Cu" "B.Cu") (net 1))
  (via (at 96.15 75.5) (size 0.45) (drill 0.1) (layers "F.Cu" "B.Cu") (net 1))
  (via (at 90.3 119.53) (size 0.45) (drill 0.1) (layers "F.Cu" "B.Cu") (net 1))
  (via (at 132.24 125.29) (size 0.45) (drill 0.1) (layers "F.Cu" "B.Cu") (net 1))
  (via (at 93.06 75.03) (size 0.45) (drill 0.1) (layers "F.Cu" "B.Cu") (net 1))
  (via (at 96.6 99) (size 0.45) (drill 0.1) (layers "F.Cu" "B.Cu") (net 1))
  (via (at 104.424973 137.949991) (size 0.45) (drill 0.1) (layers "F.Cu" "B.Cu") (net 1))
  (via (at 143.99 82.39) (size 0.45) (drill 0.1) (layers "F.Cu" "B.Cu") (net 1))
  (via (at 77.592715 97.595238) (size 0.55) (drill 0.2) (layers "F.Cu" "B.Cu") (net 1))
  (via (at 159.44 136.03) (size 0.45) (drill 0.1) (layers "F.Cu" "B.Cu") (net 1))
  (via (at 93.715319 115.718125) (size 0.45) (drill 0.1) (layers "F.Cu" "B.Cu") (net 1))
  (via (at 129.275 82.95) (size 0.45) (drill 0.1) (layers "F.Cu" "B.Cu") (net 1))
  (via (at 84.03 72.725) (size 0.45) (drill 0.1) (layers "F.Cu" "B.Cu") (net 1))
  (via (at 117.7 85.875) (size 0.45) (drill 0.1) (layers "F.Cu" "B.Cu") (net 1))
  (via (at 129.5 91.4) (size 0.45) (drill 0.1) (layers "F.Cu" "B.Cu") (net 1))
  (via (at 177.292715 139.595238) (size 0.55) (drill 0.2) (layers "F.Cu" "B.Cu") (net 1))
  (via (at 133.5 135.9) (size 0.45) (drill 0.1) (layers "F.Cu" "B.Cu") (net 1))
  (via (at 78.92 105.03) (size 0.45) (drill 0.1) (layers "F.Cu" "B.Cu") (net 1))
  (via (at 156.3 86.4) (size 0.45) (drill 0.1) (layers "F.Cu" "B.Cu") (net 1))
  (via (at 128.98 91.47) (size 0.45) (drill 0.1) (layers "F.Cu" "B.Cu") (net 1))
  (via (at 170.65 137.2) (size 0.45) (drill 0.1) (layers "F.Cu" "B.Cu") (net 1))
  (via (at 79.59 108.64) (size 0.45) (drill 0.1) (layers "F.Cu" "B.Cu") (net 1))
  (via (at 175.275 137.8) (size 0.45) (drill 0.1) (layers "F.Cu" "B.Cu") (net 1))
  (via (at 110.63 91.76) (size 0.45) (drill 0.1) (layers "F.Cu" "B.Cu") (net 1))
  (via (at 157.88 120.79) (size 0.45) (drill 0.1) (layers "F.Cu" "B.Cu") (net 1))
  (via (at 158.480001 126.5045) (size 0.45) (drill 0.1) (layers "F.Cu" "B.Cu") (net 1))
  (via (at 90.5 73.25) (size 0.45) (drill 0.1) (layers "F.Cu" "B.Cu") (net 1))
  (via (at 89.4 99.525) (size 0.45) (drill 0.1) (layers "F.Cu" "B.Cu") (net 1))
  (via (at 114.45 120.9) (size 0.45) (drill 0.1) (layers "F.Cu" "B.Cu") (net 1))
  (via (at 151.2 67.225) (size 0.45) (drill 0.1) (layers "F.Cu" "B.Cu") (net 1))
  (via (at 152.4 111) (size 0.45) (drill 0.1) (layers "F.Cu" "B.Cu") (net 1))
  (via (at 149.1 83.6) (size 0.45) (drill 0.1) (layers "F.Cu" "B.Cu") (net 1))
  (via (at 140.575 122.975) (size 0.45) (drill 0.1) (layers "F.Cu" "B.Cu") (net 1))
  (via (at 91.86 106.8265) (size 0.45) (drill 0.1) (layers "F.Cu" "B.Cu") (net 1))
  (via (at 132.559 75.747) (size 0.45) (drill 0.1) (layers "F.Cu" "B.Cu") (net 1))
  (via (at 142.075 126.049994) (size 0.45) (drill 0.1) (layers "F.Cu" "B.Cu") (net 1))
  (via (at 120.992715 147.295238) (size 0.55) (drill 0.2) (layers "F.Cu" "B.Cu") (net 1))
  (via (at 160.42 118.885) (size 0.45) (drill 0.1) (layers "F.Cu" "B.Cu") (net 1))
  (via (at 160.42 128.41) (size 0.45) (drill 0.1) (layers "F.Cu" "B.Cu") (net 1))
  (via (at 90.3 118.89) (size 0.45) (drill 0.1) (layers "F.Cu" "B.Cu") (net 1))
  (via (at 112.46 105.46) (size 0.45) (drill 0.1) (layers "F.Cu" "B.Cu") (net 1))
  (via (at 92.84 119.53) (size 0.45) (drill 0.1) (layers "F.Cu" "B.Cu") (net 1))
  (via (at 132.23 124.14) (size 0.45) (drill 0.1) (layers "F.Cu" "B.Cu") (net 1))
  (via (at 82.03 142.99) (size 0.55) (drill 0.2) (layers "F.Cu" "B.Cu") (net 1))
  (via (at 122.85 114.9) (size 0.45) (drill 0.1) (layers "F.Cu" "B.Cu") (net 1))
  (via (at 89.698 106.827) (size 0.45) (drill 0.1) (layers "F.Cu" "B.Cu") (net 1))
  (via (at 96.7 88.7) (size 0.45) (drill 0.1) (layers "F.Cu" "B.Cu") (net 1))
  (via (at 90.3 132.865) (size 0.45) (drill 0.1) (layers "F.Cu" "B.Cu") (net 1))
  (via (at 131.2 118.775) (size 0.45) (drill 0.1) (layers "F.Cu" "B.Cu") (net 1))
  (via (at 166.492715 108.095238) (size 0.55) (drill 0.2) (layers "F.Cu" "B.Cu") (net 1))
  (via (at 90.3 134.13) (size 0.45) (drill 0.1) (layers "F.Cu" "B.Cu") (net 1))
  (via (at 78.03 106.57) (size 0.45) (drill 0.1) (layers "F.Cu" "B.Cu") (net 1))
  (via (at 147.6 83.6) (size 0.45) (drill 0.1) (layers "F.Cu" "B.Cu") (net 1))
  (via (at 117.7 86.75) (size 0.45) (drill 0.1) (layers "F.Cu" "B.Cu") (net 1))
  (via (at 174.192715 57.695238) (size 0.55) (drill 0.2) (layers "F.Cu" "B.Cu") (net 1))
  (via (at 158.480001 118.8845) (size 0.45) (drill 0.1) (layers "F.Cu" "B.Cu") (net 1))
  (via (at 80.7 136) (size 0.45) (drill 0.1) (layers "F.Cu" "B.Cu") (net 1))
  (via (at 145.492715 106.695238) (size 0.55) (drill 0.2) (layers "F.Cu" "B.Cu") (net 1))
  (via (at 148 142.2) (size 0.45) (drill 0.1) (layers "F.Cu" "B.Cu") (net 1))
  (via (at 78.15 111.4) (size 0.45) (drill 0.1) (layers "F.Cu" "B.Cu") (net 1))
  (via (at 165.792715 102.495238) (size 0.55) (drill 0.2) (layers "F.Cu" "B.Cu") (net 1))
  (via (at 118.075 89.25) (size 0.45) (drill 0.1) (layers "F.Cu" "B.Cu") (net 1))
  (via (at 107.35 97.275) (size 0.45) (drill 0.1) (layers "F.Cu" "B.Cu") (net 1))
  (via (at 158.480001 134.7595) (size 0.45) (drill 0.1) (layers "F.Cu" "B.Cu") (net 1))
  (via (at 156.900001 133.4895) (size 0.45) (drill 0.1) (layers "F.Cu" "B.Cu") (net 1))
  (via (at 146.4 79.5) (size 0.45) (drill 0.1) (layers "F.Cu" "B.Cu") (net 1))
  (via (at 91.9815 115.074) (size 0.45) (drill 0.1) (layers "F.Cu" "B.Cu") (net 1))
  (via (at 91.9815 122.694) (size 0.45) (drill 0.1) (layers "F.Cu" "B.Cu") (net 1))
  (via (at 125.15 148) (size 0.6) (drill 0.25) (layers "F.Cu" "B.Cu") (net 1))
  (via (at 155.2 90.125) (size 0.45) (drill 0.1) (layers "F.Cu" "B.Cu") (net 1))
  (via (at 119.48 93.24) (size 0.45) (drill 0.1) (layers "F.Cu" "B.Cu") (net 1))
  (via (at 165.6 75.9) (size 0.55) (drill 0.2) (layers "F.Cu" "B.Cu") (net 1))
  (via (at 86 67.825) (size 0.45) (drill 0.1) (layers "F.Cu" "B.Cu") (net 1))
  (via (at 144.56 83.5) (size 0.45) (drill 0.1) (layers "F.Cu" "B.Cu") (net 1))
  (via (at 149.9 91.1) (size 0.45) (drill 0.1) (layers "F.Cu" "B.Cu") (net 1))
  (via (at 153 108.85) (size 0.45) (drill 0.1) (layers "F.Cu" "B.Cu") (net 1))
  (via (at 152.1 93.5) (size 0.45) (drill 0.1) (layers "F.Cu" "B.Cu") (net 1))
  (via (at 91.182531 123.329129) (size 0.45) (drill 0.1) (layers "F.Cu" "B.Cu") (net 1))
  (via (at 139.325 127.3) (size 0.45) (drill 0.1) (layers "F.Cu" "B.Cu") (net 1))
  (via (at 168.3 141.7) (size 0.45) (drill 0.1) (layers "F.Cu" "B.Cu") (net 1))
  (via (at 96.575 98) (size 0.45) (drill 0.1) (layers "F.Cu" "B.Cu") (net 1))
  (via (at 158.480001 128.4095) (size 0.45) (drill 0.1) (layers "F.Cu" "B.Cu") (net 1))
  (via (at 82.35 121.75) (size 0.45) (drill 0.1) (layers "F.Cu" "B.Cu") (net 1))
  (via (at 149.495 122.9) (size 0.45) (drill 0.1) (layers "F.Cu" "B.Cu") (net 1))
  (via (at 90.3 130.96) (size 0.45) (drill 0.1) (layers "F.Cu" "B.Cu") (net 1))
  (via (at 155.225 89.175) (size 0.45) (drill 0.1) (layers "F.Cu" "B.Cu") (net 1))
  (via (at 95.792715 65.395238) (size 0.55) (drill 0.2) (layers "F.Cu" "B.Cu") (net 1))
  (via (at 168.8 141.7) (size 0.45) (drill 0.1) (layers "F.Cu" "B.Cu") (net 1))
  (via (at 158.480001 116.9795) (size 0.45) (drill 0.1) (layers "F.Cu" "B.Cu") (net 1))
  (via (at 128.5 94.9) (size 0.45) (drill 0.1) (layers "F.Cu" "B.Cu") (net 1))
  (via (at 182.592715 99.695238) (size 0.55) (drill 0.2) (layers "F.Cu" "B.Cu") (net 1))
  (via (at 147 79.5) (size 0.45) (drill 0.1) (layers "F.Cu" "B.Cu") (net 1))
  (via (at 110.42 105.5) (size 0.45) (drill 0.1) (layers "F.Cu" "B.Cu") (net 1))
  (via (at 141.95 76.325) (size 0.45) (drill 0.1) (layers "F.Cu" "B.Cu") (net 1))
  (via (at 119.41 81.84) (size 0.45) (drill 0.1) (layers "F.Cu" "B.Cu") (net 1))
  (via (at 158.480001 120.7895) (size 0.45) (drill 0.1) (layers "F.Cu" "B.Cu") (net 1))
  (via (at 157.88 115.075) (size 0.45) (drill 0.1) (layers "F.Cu" "B.Cu") (net 1))
  (via (at 90.9 100.4765) (size 0.45) (drill 0.1) (layers "F.Cu" "B.Cu") (net 1))
  (via (at 178.8 130.6) (size 0.45) (drill 0.1) (layers "F.Cu" "B.Cu") (net 1))
  (via (at 146.7 62) (size 0.45) (drill 0.1) (layers "F.Cu" "B.Cu") (net 1))
  (via (at 108.175 122.75) (size 0.45) (drill 0.1) (layers "F.Cu" "B.Cu") (net 1))
  (via (at 184.692715 93.395238) (size 0.55) (drill 0.2) (layers "F.Cu" "B.Cu") (net 1))
  (via (at 86.1 116.9) (size 0.45) (drill 0.1) (layers "F.Cu" "B.Cu") (net 1))
  (via (at 89.4415 122.694) (size 0.45) (drill 0.1) (layers "F.Cu" "B.Cu") (net 1))
  (via (at 151.4 111) (size 0.45) (drill 0.1) (layers "F.Cu" "B.Cu") (net 1))
  (via (at 78.78 108.55) (size 0.45) (drill 0.1) (layers "F.Cu" "B.Cu") (net 1))
  (via (at 98.175 95.025) (size 0.45) (drill 0.1) (layers "F.Cu" "B.Cu") (net 1))
  (via (at 155.125 92) (size 0.45) (drill 0.1) (layers "F.Cu" "B.Cu") (net 1))
  (via (at 93.7115 125.249) (size 0.45) (drill 0.1) (layers "F.Cu" "B.Cu") (net 1))
  (via (at 104.3 95.7) (size 0.45) (drill 0.1) (layers "F.Cu" "B.Cu") (net 1))
  (via (at 74.792715 139.595238) (size 0.55) (drill 0.2) (layers "F.Cu" "B.Cu") (net 1))
  (via (at 117.725 84.15) (size 0.45) (drill 0.1) (layers "F.Cu" "B.Cu") (net 1))
  (via (at 167.8 141.7) (size 0.45) (drill 0.1) (layers "F.Cu" "B.Cu") (net 1))
  (via (at 131.175 120.275) (size 0.45) (drill 0.1) (layers "F.Cu" "B.Cu") (net 1))
  (via (at 143.149996 115.5) (size 0.45) (drill 0.1) (layers "F.Cu" "B.Cu") (net 1))
  (via (at 131.15 131.25) (size 0.45) (drill 0.1) (layers "F.Cu" "B.Cu") (net 1))
  (via (at 155.8 150.2) (size 0.45) (drill 0.1) (layers "F.Cu" "B.Cu") (net 1))
  (via (at 137.7 124.7) (size 0.45) (drill 0.1) (layers "F.Cu" "B.Cu") (net 1))
  (via (at 155.940001 116.9795) (size 0.45) (drill 0.1) (layers "F.Cu" "B.Cu") (net 1))
  (via (at 158.480001 132.2195) (size 0.45) (drill 0.1) (layers "F.Cu" "B.Cu") (net 1))
  (via (at 140.85 95.4) (size 0.45) (drill 0.1) (layers "F.Cu" "B.Cu") (net 1))
  (via (at 160.42 116.98) (size 0.45) (drill 0.1) (layers "F.Cu" "B.Cu") (net 1))
  (via (at 134.992715 114.395238) (size 0.55) (drill 0.2) (layers "F.Cu" "B.Cu") (net 1))
  (via (at 92.84 127.15) (size 0.45) (drill 0.1) (layers "F.Cu" "B.Cu") (net 1))
  (via (at 125.15 149.3) (size 0.6) (drill 0.25) (layers "F.Cu" "B.Cu") (net 1))
  (via (at 94.500004 132.15) (size 0.45) (drill 0.1) (layers "F.Cu" "B.Cu") (net 1))
  (via (at 77.875 90.9) (size 0.45) (drill 0.1) (layers "F.Cu" "B.Cu") (net 1))
  (via (at 131.15 145.45) (size 0.45) (drill 0.1) (layers "F.Cu" "B.Cu") (net 1))
  (via (at 85.15 145.47) (size 0.55) (drill 0.2) (layers "F.Cu" "B.Cu") (net 1))
  (via (at 155.940001 134.7595) (size 0.45) (drill 0.1) (layers "F.Cu" "B.Cu") (net 1))
  (via (at 155.940001 124.5995) (size 0.45) (drill 0.1) (layers "F.Cu" "B.Cu") (net 1))
  (via (at 141.98 142.0745) (size 0.45) (drill 0.1) (layers "F.Cu" "B.Cu") (net 1))
  (via (at 156.920001 134.7595) (size 0.45) (drill 0.1) (layers "F.Cu" "B.Cu") (net 1))
  (via (at 167.2 70.3) (size 0.55) (drill 0.2) (layers "F.Cu" "B.Cu") (net 1))
  (via (at 142.775 87.5) (size 0.45) (drill 0.1) (layers "F.Cu" "B.Cu") (net 1))
  (via (at 90.3 127.15) (size 0.45) (drill 0.1) (layers "F.Cu" "B.Cu") (net 1))
  (via (at 74.792715 65.395238) (size 0.55) (drill 0.2) (layers "F.Cu" "B.Cu") (net 1))
  (via (at 148.9 94.924998) (size 0.45) (drill 0.1) (layers "F.Cu" "B.Cu") (net 1))
  (via (at 93.32 141.93) (size 0.6) (drill 0.25) (layers "F.Cu" "B.Cu") (net 1))
  (via (at 94.15 69.45) (size 0.45) (drill 0.1) (layers "F.Cu" "B.Cu") (net 1))
  (via (at 139.135 121.09) (size 0.45) (drill 0.1) (layers "F.Cu" "B.Cu") (net 1))
  (via (at 160.42 126.505) (size 0.45) (drill 0.1) (layers "F.Cu" "B.Cu") (net 1))
  (via (at 158.480001 122.6945) (size 0.45) (drill 0.1) (layers "F.Cu" "B.Cu") (net 1))
  (via (at 149.692715 142.395238) (size 0.55) (drill 0.2) (layers "F.Cu" "B.Cu") (net 1))
  (via (at 138.25 143.37) (size 0.55) (drill 0.2) (layers "F.Cu" "B.Cu") (net 1))
  (via (at 160.42 120.79) (size 0.45) (drill 0.1) (layers "F.Cu" "B.Cu") (net 1))
  (via (at 155.940001 113.1695) (size 0.45) (drill 0.1) (layers "F.Cu" "B.Cu") (net 1))
  (via (at 86.75 67.2) (size 0.45) (drill 0.1) (layers "F.Cu" "B.Cu") (net 1))
  (via (at 113.45 123.375) (size 0.45) (drill 0.1) (layers "F.Cu" "B.Cu") (net 1))
  (via (at 164.9 70.3) (size 0.55) (drill 0.2) (layers "F.Cu" "B.Cu") (net 1))
  (via (at 161.75 70.3) (size 0.55) (drill 0.2) (layers "F.Cu" "B.Cu") (net 1))
  (via (at 160.42 113.17) (size 0.45) (drill 0.1) (layers "F.Cu" "B.Cu") (net 1))
  (via (at 159.460001 134.7595) (size 0.45) (drill 0.1) (layers "F.Cu" "B.Cu") (net 1))
  (via (at 109.683871 141.286703) (size 0.45) (drill 0.1) (layers "F.Cu" "B.Cu") (net 1))
  (via (at 155.940001 126.5045) (size 0.45) (drill 0.1) (layers "F.Cu" "B.Cu") (net 1))
  (via (at 92.86347 111.29347) (size 0.45) (drill 0.1) (layers "F.Cu" "B.Cu") (net 1))
  (via (at 151.4 107.9) (size 0.45) (drill 0.1) (layers "F.Cu" "B.Cu") (net 1))
  (via (at 118.4 80.1) (size 0.45) (drill 0.1) (layers "F.Cu" "B.Cu") (net 1))
  (via (at 85.25 67.15) (size 0.45) (drill 0.1) (layers "F.Cu" "B.Cu") (net 1))
  (via (at 160.42 105.55) (size 0.45) (drill 0.1) (layers "F.Cu" "B.Cu") (net 1))
  (via (at 74.792715 59.095238) (size 0.55) (drill 0.2) (layers "F.Cu" "B.Cu") (net 1))
  (via (at 78.425 92.175) (size 0.45) (drill 0.1) (layers "F.Cu" "B.Cu") (net 1))
  (via (at 157.88 113.17) (size 0.45) (drill 0.1) (layers "F.Cu" "B.Cu") (net 1))
  (via (at 128.55 142.8) (size 0.6) (drill 0.25) (layers "F.Cu" "B.Cu") (net 1))
  (via (at 118.82241 88.822937) (size 0.45) (drill 0.1) (layers "F.Cu" "B.Cu") (net 1))
  (via (at 120.1 80.1) (size 0.45) (drill 0.1) (layers "F.Cu" "B.Cu") (net 1))
  (via (at 169.992715 105.295238) (size 0.55) (drill 0.2) (layers "F.Cu" "B.Cu") (net 1))
  (via (at 92.84 132.865) (size 0.45) (drill 0.1) (layers "F.Cu" "B.Cu") (net 1))
  (via (at 113.32 86.409986) (size 0.45) (drill 0.1) (layers "F.Cu" "B.Cu") (net 1))
  (via (at 145.6 79.1) (size 0.45) (drill 0.1) (layers "F.Cu" "B.Cu") (net 1))
  (via (at 100.3 72.15) (size 0.45) (drill 0.1) (layers "F.Cu" "B.Cu") (net 1))
  (via (at 155.94 104.915) (size 0.45) (drill 0.1) (layers "F.Cu" "B.Cu") (net 1))
  (via (at 133.37 115.78) (size 0.45) (drill 0.1) (layers "F.Cu" "B.Cu") (net 1))
  (via (at 105.95 144) (size 0.45) (drill 0.1) (layers "F.Cu" "B.Cu") (net 1))
  (via (at 89.4415 117.614) (size 0.45) (drill 0.1) (layers "F.Cu" "B.Cu") (net 1))
  (via (at 133.25 111.7) (size 0.45) (drill 0.1) (layers "F.Cu" "B.Cu") (net 1))
  (via (at 174.3 142.75) (size 0.45) (drill 0.1) (layers "F.Cu" "B.Cu") (net 1))
  (via (at 81.6 148.15) (size 0.55) (drill 0.2) (layers "F.Cu" "B.Cu") (net 1))
  (via (at 106.992715 63.295238) (size 0.55) (drill 0.2) (layers "F.Cu" "B.Cu") (net 1))
  (via (at 88.738 100.477) (size 0.45) (drill 0.1) (layers "F.Cu" "B.Cu") (net 1))
  (via (at 153.192715 145.195238) (size 0.55) (drill 0.2) (layers "F.Cu" "B.Cu") (net 1))
  (via (at 128.5 92.7) (size 0.45) (drill 0.1) (layers "F.Cu" "B.Cu") (net 1))
  (via (at 85.292715 74.495238) (size 0.55) (drill 0.2) (layers "F.Cu" "B.Cu") (net 1))
  (via (at 96.8 67.65) (size 0.45) (drill 0.1) (layers "F.Cu" "B.Cu") (net 1))
  (via (at 153.591813 125.488836) (size 0.45) (drill 0.1) (layers "F.Cu" "B.Cu") (net 1))
  (via (at 101.88 105.42) (size 0.45) (drill 0.1) (layers "F.Cu" "B.Cu") (net 1))
  (via (at 175.592715 105.995238) (size 0.55) (drill 0.2) (layers "F.Cu" "B.Cu") (net 1))
  (via (at 144.6 62) (size 0.45) (drill 0.1) (layers "F.Cu" "B.Cu") (net 1))
  (via (at 96.1 87.3) (size 0.45) (drill 0.1) (layers "F.Cu" "B.Cu") (net 1))
  (via (at 148.4 94.925) (size 0.45) (drill 0.1) (layers "F.Cu" "B.Cu") (net 1))
  (via (at 77.95 105.11) (size 0.45) (drill 0.1) (layers "F.Cu" "B.Cu") (net 1))
  (via (at 186.55 129.9) (size 0.45) (drill 0.1) (layers "F.Cu" "B.Cu") (net 1))
  (via (at 133.37 117.27) (size 0.45) (drill 0.1) (layers "F.Cu" "B.Cu") (net 1))
  (via (at 158.48 104.915) (size 0.45) (drill 0.1) (layers "F.Cu" "B.Cu") (net 1))
  (via (at 74.792715 84.295238) (size 0.55) (drill 0.2) (layers "F.Cu" "B.Cu") (net 1))
  (via (at 82.575 119.75) (size 0.45) (drill 0.1) (layers "F.Cu" "B.Cu") (net 1))
  (via (at 133.978761 137.021239) (size 0.45) (drill 0.1) (layers "F.Cu" "B.Cu") (net 1))
  (via (at 148.8 66.425) (size 0.45) (drill 0.1) (layers "F.Cu" "B.Cu") (net 1))
  (via (at 91.9815 125.234) (size 0.45) (drill 0.1) (layers "F.Cu" "B.Cu") (net 1))
  (via (at 157.88 124.6) (size 0.45) (drill 0.1) (layers "F.Cu" "B.Cu") (net 1))
  (via (at 156.920001 132.2195) (size 0.45) (drill 0.1) (layers "F.Cu" "B.Cu") (net 1))
  (via (at 111.5 137.5) (size 0.45) (drill 0.1) (layers "F.Cu" "B.Cu") (net 1))
  (via (at 78.385 89.625) (size 0.45) (drill 0.1) (layers "F.Cu" "B.Cu") (net 1))
  (via (at 89.4415 125.234) (size 0.45) (drill 0.1) (layers "F.Cu" "B.Cu") (net 1))
  (via (at 159.460001 132.2195) (size 0.45) (drill 0.1) (layers "F.Cu" "B.Cu") (net 1))
  (via (at 148.17 88.03) (size 0.45) (drill 0.1) (layers "F.Cu" "B.Cu") (net 1))
  (via (at 83.192715 66.095238) (size 0.55) (drill 0.2) (layers "F.Cu" "B.Cu") (net 1))
  (via (at 156.7 85.6) (size 0.45) (drill 0.1) (layers "F.Cu" "B.Cu") (net 1))
  (via (at 131.175 89.035) (size 0.45) (drill 0.1) (layers "F.Cu" "B.Cu") (net 1))
  (via (at 142.125 127) (size 0.45) (drill 0.1) (layers "F.Cu" "B.Cu") (net 1))
  (via (at 131.125 121.775) (size 0.45) (drill 0.1) (layers "F.Cu" "B.Cu") (net 1))
  (via (at 128.57 64.23) (size 0.4) (drill 0.1) (layers "F.Cu" "B.Cu") (net 1))
  (via (at 157.88 118.885) (size 0.45) (drill 0.1) (layers "F.Cu" "B.Cu") (net 1))
  (via (at 155.940001 122.6945) (size 0.45) (drill 0.1) (layers "F.Cu" "B.Cu") (net 1))
  (via (at 155.940001 115.0745) (size 0.45) (drill 0.1) (layers "F.Cu" "B.Cu") (net 1))
  (via (at 81.092715 84.995238) (size 0.55) (drill 0.2) (layers "F.Cu" "B.Cu") (net 1))
  (via (at 176.992715 61.195238) (size 0.55) (drill 0.2) (layers "F.Cu" "B.Cu") (net 1))
  (via (at 142.15 108.575) (size 0.45) (drill 0.1) (layers "F.Cu" "B.Cu") (net 1))
  (via (at 160.42 115.075) (size 0.45) (drill 0.1) (layers "F.Cu" "B.Cu") (net 1))
  (via (at 125.892715 63.295238) (size 0.55) (drill 0.2) (layers "F.Cu" "B.Cu") (net 1))
  (via (at 92.84 130.96) (size 0.45) (drill 0.1) (layers "F.Cu" "B.Cu") (net 1))
  (via (at 158.480001 124.5995) (size 0.45) (drill 0.1) (layers "F.Cu" "B.Cu") (net 1))
  (via (at 107.010017 103.714983) (size 0.45) (drill 0.1) (layers "F.Cu" "B.Cu") (net 1))
  (via (at 152.4 107.9) (size 0.45) (drill 0.1) (layers "F.Cu" "B.Cu") (net 1))
  (via (at 99.4 72.15) (size 0.45) (drill 0.1) (layers "F.Cu" "B.Cu") (net 1))
  (via (at 157.893001 130.9765) (size 0.45) (drill 0.1) (layers "F.Cu" "B.Cu") (net 1))
  (via (at 74.792715 133.295238) (size 0.55) (drill 0.2) (layers "F.Cu" "B.Cu") (net 1))
  (via (at 86.1 117.8) (size 0.45) (drill 0.1) (layers "F.Cu" "B.Cu") (net 1))
  (via (at 91.97 141.94) (size 0.6) (drill 0.25) (layers "F.Cu" "B.Cu") (net 1))
  (via (at 92.375 149.3) (size 0.45) (drill 0.1) (layers "F.Cu" "B.Cu") (net 1))
  (via (at 131.2 129.8) (size 0.45) (drill 0.1) (layers "F.Cu" "B.Cu") (net 1))
  (via (at 130.75 84.05) (size 0.45) (drill 0.1) (layers "F.Cu" "B.Cu") (net 1))
  (via (at 128.85 90.700001) (size 0.45) (drill 0.1) (layers "F.Cu" "B.Cu") (net 1))
  (via (at 160.420001 133.4895) (size 0.45) (drill 0.1) (layers "F.Cu" "B.Cu") (net 1))
  (via (at 160.420001 130.9495) (size 0.45) (drill 0.1) (layers "F.Cu" "B.Cu") (net 1))
  (via (at 143.215002 92.2) (size 0.45) (drill 0.1) (layers "F.Cu" "B.Cu") (net 1))
  (via (at 147 80.2) (size 0.45) (drill 0.1) (layers "F.Cu" "B.Cu") (net 1))
  (via (at 99.6 98.5) (size 0.45) (drill 0.1) (layers "F.Cu" "B.Cu") (net 1))
  (via (at 137.415 82.125) (size 0.6) (drill 0.25) (layers "F.Cu" "B.Cu") (net 1))
  (via (at 115.3 147.2) (size 0.45) (drill 0.1) (layers "F.Cu" "B.Cu") (net 1))
  (via (at 156.900001 136.0295) (size 0.45) (drill 0.1) (layers "F.Cu" "B.Cu") (net 1))
  (via (at 92.238 106.827) (size 0.45) (drill 0.1) (layers "F.Cu" "B.Cu") (net 1))
  (via (at 159.440001 133.4895) (size 0.45) (drill 0.1) (layers "F.Cu" "B.Cu") (net 1))
  (via (at 92.85451 111.91) (size 0.45) (drill 0.1) (layers "F.Cu" "B.Cu") (net 1))
  (via (at 112.725 138.9) (size 0.45) (drill 0.1) (layers "F.Cu" "B.Cu") (net 1))
  (via (at 155.94 102.375) (size 0.45) (drill 0.1) (layers "F.Cu" "B.Cu") (net 1))
  (via (at 130.75 82.85) (size 0.45) (drill 0.1) (layers "F.Cu" "B.Cu") (net 1))
  (via (at 92.8 99.225) (size 0.45) (drill 0.1) (layers "F.Cu" "B.Cu") (net 1))
  (via (at 119.2 80.1) (size 0.45) (drill 0.1) (layers "F.Cu" "B.Cu") (net 1))
  (via (at 137.6 127.1) (size 0.45) (drill 0.1) (layers "F.Cu" "B.Cu") (net 1))
  (via (at 83.15 107.25) (size 0.45) (drill 0.1) (layers "F.Cu" "B.Cu") (net 1))
  (via (at 111.025 119.25) (size 0.45) (drill 0.1) (layers "F.Cu" "B.Cu") (net 1))
  (via (at 157.88 122.695) (size 0.45) (drill 0.1) (layers "F.Cu" "B.Cu") (net 1))
  (via (at 110.62 91.21) (size 0.45) (drill 0.1) (layers "F.Cu" "B.Cu") (net 1))
  (via (at 134.41 72.01) (size 0.45) (drill 0.1) (layers "F.Cu" "B.Cu") (net 1))
  (via (at 152.525 77.275) (size 0.55) (drill 0.2) (layers "F.Cu" "B.Cu") (net 1))
  (via (at 89.75 67.2) (size 0.45) (drill 0.1) (layers "F.Cu" "B.Cu") (net 1))
  (via (at 91.278 100.477) (size 0.45) (drill 0.1) (layers "F.Cu" "B.Cu") (net 1))
  (via (at 84.9 147.6) (size 0.45) (drill 0.1) (layers "F.Cu" "B.Cu") (net 1))
  (via (at 89.2 104.3) (size 0.45) (drill 0.1) (layers "F.Cu" "B.Cu") (net 1))
  (via (at 160.42 100.47) (size 0.45) (drill 0.1) (layers "F.Cu" "B.Cu") (net 1))
  (via (at 155.940001 132.2195) (size 0.45) (drill 0.1) (layers "F.Cu" "B.Cu") (net 1))
  (via (at 125.1 96.7) (size 0.45) (drill 0.1) (layers "F.Cu" "B.Cu") (net 1))
  (via (at 126.325 130.775) (size 0.45) (drill 0.1) (layers "F.Cu" "B.Cu") (net 1))
  (via (at 153 111.95) (size 0.45) (drill 0.1) (layers "F.Cu" "B.Cu") (net 1))
  (via (at 129.5 89.999999) (size 0.45) (drill 0.1) (layers "F.Cu" "B.Cu") (net 1))
  (via (at 162.992715 147.995238) (size 0.55) (drill 0.2) (layers "F.Cu" "B.Cu") (net 1))
  (via (at 93.71049 123.344) (size 0.45) (drill 0.1) (layers "F.Cu" "B.Cu") (net 1))
  (via (at 92.84 120.795) (size 0.45) (drill 0.1) (layers "F.Cu" "B.Cu") (net 1))
  (via (at 103.9 132.49) (size 0.45) (drill 0.1) (layers "F.Cu" "B.Cu") (net 1))
  (via (at 128.55 149.3) (size 0.45) (drill 0.1) (layers "F.Cu" "B.Cu") (net 1))
  (via (at 158.480001 113.1695) (size 0.45) (drill 0.1) (layers "F.Cu" "B.Cu") (net 1))
  (via (at 87.85 151.407285) (size 0.55) (drill 0.2) (layers "F.Cu" "B.Cu") (net 1))
  (via (at 92.84 134.77) (size 0.45) (drill 0.1) (layers "F.Cu" "B.Cu") (net 1))
  (via (at 128.799994 80.025) (size 0.45) (drill 0.1) (layers "F.Cu" "B.Cu") (net 1))
  (via (at 159.3 70.3) (size 0.55) (drill 0.2) (layers "F.Cu" "B.Cu") (net 1))
  (via (at 155.940001 111.2645) (size 0.45) (drill 0.1) (layers "F.Cu" "B.Cu") (net 1))
  (via (at 155.94 107.455) (size 0.45) (drill 0.1) (layers "F.Cu" "B.Cu") (net 1))
  (via (at 86.1 119.6) (size 0.45) (drill 0.1) (layers "F.Cu" "B.Cu") (net 1))
  (via (at 169.292715 99.695238) (size 0.55) (drill 0.2) (layers "F.Cu" "B.Cu") (free) (net 1))
  (via (at 110.4 71.65) (size 0.45) (drill 0.1) (layers "F.Cu" "B.Cu") (net 1))
  (via (at 166.492715 63.295238) (size 0.55) (drill 0.2) (layers "F.Cu" "B.Cu") (net 1))
  (via (at 160.42 103.01) (size 0.45) (drill 0.1) (layers "F.Cu" "B.Cu") (net 1))
  (via (at 90.7 83.7) (size 0.45) (drill 0.1) (layers "F.Cu" "B.Cu") (net 1))
  (via (at 90.3 134.77) (size 0.45) (drill 0.1) (layers "F.Cu" "B.Cu") (net 1))
  (via (at 157.880001 136.0295) (size 0.45) (drill 0.1) (layers "F.Cu" "B.Cu") (net 1))
  (via (at 78.13 112.73) (size 0.45) (drill 0.1) (layers "F.Cu" "B.Cu") (net 1))
  (via (at 129.75 71.7) (size 0.45) (drill 0.1) (layers "F.Cu" "B.Cu") (net 1))
  (via (at 135.86 72.01) (size 0.45) (drill 0.1) (layers "F.Cu" "B.Cu") (net 1))
  (via (at 92.62 141.94) (size 0.6) (drill 0.25) (layers "F.Cu" "B.Cu") (net 1))
  (via (at 141.925 129.65) (size 0.45) (drill 0.1) (layers "F.Cu" "B.Cu") (net 1))
  (via (at 99.292715 73.795238) (size 0.55) (drill 0.2) (layers "F.Cu" "B.Cu") (net 1))
  (via (at 136.779 82.5246) (size 0.6) (drill 0.25) (layers "F.Cu" "B.Cu") (net 1))
  (via (at 172.092715 109.495238) (size 0.55) (drill 0.2) (layers "F.Cu" "B.Cu") (net 1))
  (via (at 86.75 121.85) (size 0.45) (drill 0.1) (layers "F.Cu" "B.Cu") (net 1))
  (via (at 142.875002 118.45) (size 0.45) (drill 0.1) (layers "F.Cu" "B.Cu") (net 1))
  (via (at 86.1 118.7) (size 0.45) (drill 0.1) (layers "F.Cu" "B.Cu") (net 1))
  (via (at 149.9 108.85) (size 0.45) (drill 0.1) (layers "F.Cu" "B.Cu") (net 1))
  (via (at 141.425 122) (size 0.45) (drill 0.1) (layers "F.Cu" "B.Cu") (net 1))
  (via (at 179.792715 108.795238) (size 0.55) (drill 0.2) (layers "F.Cu" "B.Cu") (net 1))
  (via (at 136.45 149.3) (size 0.45) (drill 0.1) (layers "F.Cu" "B.Cu") (net 1))
  (via (at 156.692715 147.995238) (size 0.55) (drill 0.2) (layers "F.Cu" "B.Cu") (net 1))
  (via (at 91.1715 120.803999) (size 0.45) (drill 0.1) (layers "F.Cu" "B.Cu") (net 1))
  (via (at 147.7 91.1) (size 0.45) (drill 0.1) (layers "F.Cu" "B.Cu") (net 1))
  (via (at 172.8 133.75) (size 0.45) (drill 0.1) (layers "F.Cu" "B.Cu") (net 1))
  (via (at 130.75 83.45) (size 0.45) (drill 0.1) (layers "F.Cu" "B.Cu") (net 1))
  (via (at 135.74 135.55) (size 0.45) (drill 0.1) (layers "F.Cu" "B.Cu") (net 1))
  (via (at 104.900675 132.501006) (size 0.45) (drill 0.1) (layers "F.Cu" "B.Cu") (net 1))
  (via (at 91.9815 117.614) (size 0.45) (drill 0.1) (layers "F.Cu" "B.Cu") (net 1))
  (via (at 92.62 142.57) (size 0.6) (drill 0.25) (layers "F.Cu" "B.Cu") (net 1))
  (via (at 109.42 96.25) (size 0.45) (drill 0.1) (layers "F.Cu" "B.Cu") (net 1))
  (via (at 78.292715 61.895238) (size 0.55) (drill 0.2) (layers "F.Cu" "B.Cu") (net 1))
  (via (at 153.2 71.4) (size 0.45) (drill 0.1) (layers "F.Cu" "B.Cu") (net 1))
  (via (at 174.192715 66.095238) (size 0.55) (drill 0.2) (layers "F.Cu" "B.Cu") (net 1))
  (via (at 148.18 89.39) (size 0.45) (drill 0.1) (layers "F.Cu" "B.Cu") (net 1))
  (via (at 87.02 139.41) (size 0.55) (drill 0.2) (layers "F.Cu" "B.Cu") (net 1))
  (via (at 96.8 66.525) (size 0.45) (drill 0.1) (layers "F.Cu" "B.Cu") (net 1))
  (via (at 92.25 67.2) (size 0.45) (drill 0.1) (layers "F.Cu" "B.Cu") (net 1))
  (via (at 111.1 97.05) (size 0.45) (drill 0.1) (layers "F.Cu" "B.Cu") (net 1))
  (via (at 93.32 142.58) (size 0.6) (drill 0.25) (layers "F.Cu" "B.Cu") (net 1))
  (via (at 156.92 129.68) (size 0.45) (drill 0.1) (layers "F.Cu" "B.Cu") (net 1))
  (via (at 90.3 126.51) (size 0.45) (drill 0.1) (layers "F.Cu" "B.Cu") (net 1))
  (via (at 139.025 129.65) (size 0.45) (drill 0.1) (layers "F.Cu" "B.Cu") (net 1))
  (via (at 123.075 129.225) (size 0.45) (drill 0.1) (layers "F.Cu" "B.Cu") (net 1))
  (via (at 174.2819 141.054343) (size 0.45) (drill 0.1) (layers "F.Cu" "B.Cu") (net 1))
  (via (at 157.88 126.505) (size 0.45) (drill 0.1) (layers "F.Cu" "B.Cu") (net 1))
  (via (at 142.975 124.325) (size 0.45) (drill 0.1) (layers "F.Cu" "B.Cu") (net 1))
  (via (at 128.15 137.25) (size 0.45) (drill 0.1) (layers "F.Cu" "B.Cu") (net 1))
  (via (at 164.392715 91.295238) (size 0.55) (drill 0.2) (layers "F.Cu" "B.Cu") (net 1))
  (via (at 125.50003 73.55) (size 0.45) (drill 0.1) (layers "F.Cu" "B.Cu") (free) (net 1))
  (via (at 142.1 109.575) (size 0.45) (drill 0.1) (layers "F.Cu" "B.Cu") (net 1))
  (via (at 78.66 109.92) (size 0.45) (drill 0.1) (layers "F.Cu" "B.Cu") (net 1))
  (via (at 93.818 100.477) (size 0.45) (drill 0.1) (layers "F.Cu" "B.Cu") (net 1))
  (via (at 100.125 94.1) (size 0.45) (drill 0.1) (layers "F.Cu" "B.Cu") (net 1))
  (via (at 92.84 128.415) (size 0.45) (drill 0.1) (layers "F.Cu" "B.Cu") (net 1))
  (via (at 168.1 75.875) (size 0.55) (drill 0.2) (layers "F.Cu" "B.Cu") (net 1))
  (via (at 123.85 148) (size 0.6) (drill 0.25) (layers "F.Cu" "B.Cu") (net 1))
  (via (at 92.84 134.13) (size 0.45) (drill 0.1) (layers "F.Cu" "B.Cu") (net 1))
  (via (at 135.01 121.02) (size 0.45) (drill 0.1) (layers "F.Cu" "B.Cu") (net 1))
  (via (at 155 71.4) (size 0.45) (drill 0.1) (layers "F.Cu" "B.Cu") (net 1))
  (via (at 86.05 114.15) (size 0.45) (drill 0.1) (layers "F.Cu" "B.Cu") (net 1))
  (via (at 126.4 96.2) (size 0.45) (drill 0.1) (layers "F.Cu" "B.Cu") (net 1))
  (via (at 111 123.325) (size 0.45) (drill 0.1) (layers "F.Cu" "B.Cu") (net 1))
  (segment (start 109.36 145.515) (end 109.35 145.525) (width 0.4) (layer "B.Cu") (net 1))
  (segment (start 116.17 140.25) (end 116.8 140.25) (width 0.182) (layer "B.Cu") (net 1))
  (segment (start 104.36 139.95) (end 104.35 139.94) (width 0.182) (layer "B.Cu") (net 1))
  (segment (start 106.18 141.6) (end 106.18 142.22) (width 0.182) (layer "B.Cu") (net 1))
  (segment (start 106.59 144.9) (end 106.59 145.515) (width 0.4) (layer "B.Cu") (net 1))
  (segment (start 106.18 142.22) (end 106.175 142.225) (width 0.182) (layer "B.Cu") (net 1))
  (segment (start 108.975 141.6) (end 109.45 142.075) (width 0.182) (layer "B.Cu") (net 1))
  (segment (start 116.185 141.95) (end 116.8 141.95) (width 0.182) (layer "B.Cu") (net 1))
  (segment (start 109.36 144.9) (end 109.36 145.515) (width 0.4) (layer "B.Cu") (net 1))
  (segment (start 105 139.95) (end 104.36 139.95) (width 0.182) (layer "B.Cu") (net 1))
  (segment (start 106.59 145.515) (end 106.6 145.525) (width 0.4) (layer "B.Cu") (net 1))
  (segment (start 101.365 134.35) (end 100.515 134.35) (width 0.4) (layer "B.Cu") (net 1))
  (segment (start 97.34 141.06) (end 97.375 141.025) (width 0.182) (layer "B.Cu") (net 1))
  (segment (start 96.45 146.465) (end 96.45 145.85) (width 0.4) (layer "B.Cu") (net 1))
  (segment (start 96.725 141.059999) (end 97.34 141.06) (width 0.182) (layer "B.Cu") (net 1))
  (segment (start 139.85539 113.357609) (end 139.872435 113.374655) (width 0.4) (layer "B.Cu") (net 1))
  (segment (start 148.48 121.175) (end 148.48 120.55) (width 0.4) (layer "B.Cu") (net 1))
  (segment (start 148.25 116.029999) (end 148.250001 116.03) (width 0.4) (layer "B.Cu") (net 1))
  (segment (start 145.365 118.76) (end 145.95 118.76) (width 0.4) (layer "B.Cu") (net 1))
  (segment (start 150.505 121.15) (end 150.505 120.555) (width 0.4) (layer "B.Cu") (net 1))
  (segment (start 152.17 113.2) (end 152.775 113.2) (width 0.4) (layer "B.Cu") (net 1))
  (segment (start 149.479999 116.029999) (end 149.48 116.03) (width 0.4) (layer "B.Cu") (net 1))
  (segment (start 145.365 117.86) (end 145.95 117.86) (width 0.4) (layer "B.Cu") (net 1))
  (segment (start 145.95 117.86) (end 145.97 117.84) (width 0.4) (layer "B.Cu") (net 1))
  (segment (start 151.08 115.06) (end 150.61 115.53) (width 0.4) (layer "B.Cu") (net 1))
  (segment (start 151.095 115.06) (end 151.08 115.06) (width 0.4) (layer "B.Cu") (net 1))
  (segment (start 146.73 115.42) (end 146.73 116.02) (width 0.4) (layer "B.Cu") (net 1))
  (segment (start 145.83 115.42) (end 145.83 116.03) (width 0.4) (layer "B.Cu") (net 1))
  (segment (start 149.479999 115.43) (end 149.479999 116.029999) (width 0.4) (layer "B.Cu") (net 1))
  (segment (start 150.505 120.555) (end 150.5 120.55) (width 0.4) (layer "B.Cu") (net 1))
  (segment (start 147.58 120.832842) (end 147.58 120.55) (width 0.4) (layer "B.Cu") (net 1))
  (segment (start 151.095 117.86) (end 150.5 117.86) (width 0.4) (layer "B.Cu") (net 1))
  (segment (start 148.25 115.43) (end 148.25 116.029999) (width 0.4) (layer "B.Cu") (net 1))
  (segment (start 150.51 119.86) (end 150.5 119.87) (width 0.4) (layer "B.Cu") (net 1))
  (segment (start 151.095 119.86) (end 150.51 119.86) (width 0.4) (layer "B.Cu") (net 1))
  (segment (start 149.605 120.555002) (end 149.6 120.550002) (width 0.4) (layer "B.Cu") (net 1))
  (segment (start 147.580001 121.175) (end 147.58 120.832842) (width 0.4) (layer "B.Cu") (net 1))
  (segment (start 135.102449 74.974573) (end 135.102449 75.748572) (width 0.182) (layer "B.Cu") (net 1))
  (segment (start 115.723449 75.020572) (end 115.723449 75.794571) (width 0.182) (layer "B.Cu") (net 1))
  (segment (start 148.175 75.95) (end 147.675 75.95) (width 0.182) (layer "B.Cu") (net 1))
  (segment (start 148.261 75.864) (end 148.175 75.95) (width 0.182) (layer "B.Cu") (net 1))
  (segment (start 148.261 75.389) (end 148.261 75.561) (width 0.182) (layer "B.Cu") (net 1))
  (segment (start 148.963 74.687) (end 148.261 75.389) (width 0.182) (layer "B.Cu") (net 1))
  (segment (start 148.261 75.561) (end 148.261 75.864) (width 0.182) (layer "B.Cu") (net 1))
  (segment (start 109.5 86.5) (end 110.6 86.5) (width 0.4) (layer "B.Cu") (net 1))
  (segment (start 99.3 88.7) (end 99.95 88.7) (width 0.2) (layer "B.Cu") (net 1))
  (segment (start 129.97 81.425) (end 129.995 81.425) (width 0.182) (layer "B.Cu") (net 1))
  (segment (start 94.65 85.3) (end 94.65 84.65) (width 0.182) (layer "B.Cu") (net 1))
  (segment (start 174.3 141.4825) (end 174.3 141.072443) (width 0.182) (layer "B.Cu") (net 1))
  (segment (start 81.9 108.75) (end 83.09 108.76) (width 0.2) (layer "B.Cu") (net 1))
  (segment (start 119.5 67.5) (end 118.885 67.5) (width 0.4) (layer "B.Cu") (net 1))
  (segment (start 155.114289 92.010711) (end 155.125 92) (width 0.182) (layer "B.Cu") (net 1))
  (segment (start 156.7 85.6) (end 156.7 85.39) (width 0.4) (layer "B.Cu") (net 1))
  (segment (start 124.788559 127.024723) (end 123.875277 127.024723) (width 0.2) (layer "B.Cu") (net 1))
  (segment (start 96.085 87.285) (end 96.1 87.3) (width 0.4) (layer "B.Cu") (net 1))
  (segment (start 118.835 65.55) (end 119.35 65.55) (width 0.4) (layer "B.Cu") (net 1))
  (segment (start 129.75 71.9) (end 129.75 71.7) (width 0.4) (layer "B.Cu") (net 1))
  (segment (start 140.471787 129.921137) (end 141.653863 129.921137) (width 0.182) (layer "B.Cu") (net 1))
  (segment (start 119.35 65.55) (end 119.5 65.7) (width 0.4) (layer "B.Cu") (net 1))
  (segment (start 132.288559 115.774723) (end 133.364723 115.774723) (width 0.182) (layer "B.Cu") (net 1))
  (segment (start 174.3 142.75) (end 174.3 142.3175) (width 0.109) (layer "B.Cu") (net 1))
  (segment (start 109.42 96.25) (end 109.73 96.25) (width 0.182) (layer "B.Cu") (net 1))
  (segment (start 155.114289 92.705025) (end 155.114289 92.010711) (width 0.182) (layer "B.Cu") (net 1))
  (segment (start 133.5 123.6) (end 133.5 123.825) (width 0.182) (layer "B.Cu") (net 1))
  (segment (start 147.729035 91.129035) (end 147.7 91.1) (width 0.2) (layer "B.Cu") (net 1))
  (segment (start 90.19 127.775) (end 90.19 128.305) (width 0.4) (layer "B.Cu") (net 1))
  (segment (start 148.345911 91.129035) (end 147.729035 91.129035) (width 0.2) (layer "B.Cu") (net 1))
  (segment (start 156.3 86.4) (end 156.05 86.65) (width 0.4) (layer "B.Cu") (net 1))
  (segment (start 152.8 111.75) (end 153 111.95) (width 0.4) (layer "B.Cu") (net 1))
  (segment (start 97.25 95) (end 98.15 95) (width 0.4) (layer "B.Cu") (net 1))
  (segment (start 132.288559 131.274723) (end 131.174723 131.274723) (width 0.2) (layer "B.Cu") (net 1))
  (segment (start 94.65 84.65) (end 94.7 84.6) (width 0.182) (layer "B.Cu") (net 1))
  (segment (start 152.7 107.3) (end 152.7 107.15) (width 0.4) (layer "B.Cu") (net 1))
  (segment (start 130.75 82.18) (end 130.75 82.85) (width 0.182) (layer "B.Cu") (net 1))
  (segment (start 109.73 96.25) (end 110.015 95.965) (width 0.182) (layer "B.Cu") (net 1))
  (segment (start 129.3 64.235) (end 128.575 64.235) (width 0.182) (layer "B.Cu") (net 1))
  (segment (start 152.7 110.25) (end 152.7 110.4) (width 0.4) (layer "B.Cu") (net 1))
  (segment (start 129.3 64.235) (end 129.36 64.235) (width 0.182) (layer "B.Cu") (net 1))
  (segment (start 145.6 120.7) (end 145.95 121.05) (width 0.4) (layer "B.Cu") (net 1))
  (segment (start 152.7 110.4) (end 152.4 110.7) (width 0.4) (layer "B.Cu") (net 1))
  (segment (start 129.75 73.6675) (end 129.75 71.9) (width 0.4) (layer "B.Cu") (net 1))
  (segment (start 110.4 70.43) (end 110.4 71.65) (width 0.4) (layer "B.Cu") (net 1))
  (segment (start 97.265 96.785) (end 97.265 96.79) (width 0.4) (layer "B.Cu") (net 1))
  (segment (start 139.025 121.2) (end 139.135 121.09) (width 0.4) (layer "B.Cu") (net 1))
  (segment (start 96.239999 66.529999) (end 96.235 66.525) (width 0.182) (layer "B.Cu") (net 1))
  (segment (start 131.175277 120.274723) (end 131.175 120.275) (width 0.182) (layer "B.Cu") (net 1))
  (segment (start 139.925 121.615) (end 139.925 121.28) (width 0.4) (layer "B.Cu") (net 1))
  (segment (start 95.985 99) (end 96.6 99) (width 0.4) (layer "B.Cu") (net 1))
  (segment (start 91.490002 85.7) (end 91.49 85.700002) (width 0.182) (layer "B.Cu") (net 1))
  (segment (start 139.925 121.28) (end 139.725 121.08) (width 0.4) (layer "B.Cu") (net 1))
  (segment (start 95.5 87.285) (end 96.085 87.285) (width 0.4) (layer "B.Cu") (net 1))
  (segment (start 141.653863 129.921137) (end 141.925 129.65) (width 0.182) (layer "B.Cu") (net 1))
  (segment (start 91.9 86.1) (end 92.755 86.1) (width 0.182) (layer "B.Cu") (net 1))
  (segment (start 152.4 107.6) (end 152.7 107.3) (width 0.4) (layer "B.Cu") (net 1))
  (segment (start 131.174723 131.274723) (end 131.15 131.25) (width 0.2) (layer "B.Cu") (net 1))
  (segment (start 81.9 110.25) (end 83.08 110.26) (width 0.2) (layer "B.Cu") (net 1))
  (segment (start 81.9 99.75) (end 83.03 99.75) (width 0.2) (layer "B.Cu") (net 1))
  (segment (start 152.4 108.635) (end 152.335 108.7) (width 0.4) (layer "B.Cu") (net 1))
  (segment (start 85.785 121.9) (end 86.7 121.9) (width 0.182) (layer "B.Cu") (net 1))
  (segment (start 92.84 136.029) (end 93.411 136.029) (width 0.182) (layer "B.Cu") (net 1))
  (segment (start 132.288559 112.774723) (end 133.374723 112.774723) (width 0.2) (layer "B.Cu") (net 1))
  (segment (start 156.7 85.39) (end 156.7 85.1) (width 0.4) (layer "B.Cu") (net 1))
  (segment (start 102.235 141.9) (end 102.810978 141.9) (width 0.182) (layer "B.Cu") (net 1))
  (segment (start 140.471787 129.921137) (end 139.296137 129.921137) (width 0.182) (layer "B.Cu") (net 1))
  (segment (start 90.19 128.305) (end 90.3 128.415) (width 0.4) (layer "B.Cu") (net 1))
  (segment (start 82.8545 101.25) (end 83.2545 101.65) (width 0.2) (layer "B.Cu") (net 1))
  (segment (start 118.884999 66.6) (end 118.835 66.550001) (width 0.4) (layer "B.Cu") (net 1))
  (segment (start 130.735 147.835) (end 130.75 147.85) (width 0.182) (layer "B.Cu") (net 1))
  (segment (start 129.995 81.425) (end 130.75 82.18) (width 0.182) (layer "B.Cu") (net 1))
  (segment (start 174.3 141.072443) (end 174.2819 141.054343) (width 0.182) (layer "B.Cu") (net 1))
  (segment (start 145.95 121.05) (end 145.95 121.165) (width 0.4) (layer "B.Cu") (net 1))
  (segment (start 152.4 107.9) (end 152.4 108.635) (width 0.4) (layer "B.Cu") (net 1))
  (segment (start 149.245911 91.129035) (end 149.870965 91.129035) (width 0.2) (layer "B.Cu") (net 1))
  (segment (start 94.645 84.655) (end 94.7 84.6) (width 0.182) (layer "B.Cu") (net 1))
  (segment (start 96.239999 67.675) (end 96.239999 66.529999) (width 0.182) (layer "B.Cu") (net 1))
  (segment (start 92.84 129.58) (end 92.935 129.675) (width 0.4) (layer "B.Cu") (net 1))
  (segment (start 133.374723 114.274723) (end 133.4 114.3) (width 0.2) (layer "B.Cu") (net 1))
  (segment (start 97.265 96.79) (end 97.725 97.25) (width 0.4) (layer "B.Cu") (net 1))
  (segment (start 94.2 87.145) (end 94.2 87.8) (width 0.182) (layer "B.Cu") (net 1))
  (segment (start 118.8 93.185) (end 119.425 93.185) (width 0.182) (layer "B.Cu") (net 1))
  (segment (start 148.963 74.187) (end 149.05 74.1) (width 0.182) (layer "B.Cu") (net 1))
  (segment (start 133.365277 117.274723) (end 133.37 117.27) (width 0.182) (layer "B.Cu") (net 1))
  (segment (start 81.9 107.25) (end 83.15 107.25) (width 0.2) (layer "B.Cu") (net 1))
  (segment (start 95.985 98) (end 96.575 98) (width 0.4) (layer "B.Cu") (net 1))
  (segment (start 96.7 88.7) (end 97.35 88.7) (width 0.2) (layer "B.Cu") (net 1))
  (segment (start 107.225 97.925) (end 107.2 97.95) (width 0.182) (layer "B.Cu") (net 1))
  (segment (start 110.4 72.8825) (end 110.4 71.65) (width 0.4) (layer "B.Cu") (net 1))
  (segment (start 156.69 85.4) (end 156.7 85.39) (width 0.4) (layer "B.Cu") (net 1))
  (segment (start 132.288559 117.274723) (end 133.365277 117.274723) (width 0.182) (layer "B.Cu") (net 1))
  (segment (start 132.288559 129.774723) (end 131.225277 129.774723) (width 0.2) (layer "B.Cu") (net 1))
  (segment (start 152.335 111.75) (end 152.8 111.75) (width 0.4) (layer "B.Cu") (net 1))
  (segment (start 149.605 121.15) (end 149.605 120.555002) (width 0.4) (layer "B.Cu") (net 1))
  (segment (start 132.288559 120.274723) (end 131.175277 120.274723) (width 0.182) (layer "B.Cu") (net 1))
  (segment (start 95.585 75.5) (end 96.15 75.5) (width 0.4) (layer "B.Cu") (net 1))
  (segment (start 152.4 110.7) (end 152.4 111) (width 0.4) (layer "B.Cu") (net 1))
  (segment (start 152.4 111.685) (end 152.335 111.75) (width 0.4) (layer "B.Cu") (net 1))
  (segment (start 97.725 97.25) (end 98.25 97.25) (width 0.4) (layer "B.Cu") (net 1))
  (segment (start 152.4 107.9) (end 152.4 107.6) (width 0.4) (layer "B.Cu") (net 1))
  (segment (start 103.974964 138.4) (end 104.424973 137.949991) (width 0.182) (layer "B.Cu") (net 1))
  (segment (start 128.575 64.235) (end 128.57 64.23) (width 0.182) (layer "B.Cu") (net 1))
  (segment (start 92.84 127.87) (end 92.935 127.775) (width 0.4) (layer "B.Cu") (net 1))
  (segment (start 148.963 74.687) (end 148.963 74.187) (width 0.182) (layer "B.Cu") (net 1))
  (segment (start 96.775 67.675) (end 96.8 67.65) (width 0.182) (layer "B.Cu") (net 1))
  (segment (start 100.3 71.585) (end 100.3 72.15) (width 0.4) (layer "B.Cu") (net 1))
  (segment (start 156 85.4) (end 156.69 85.4) (width 0.4) (layer "B.Cu") (net 1))
  (segment (start 99.4 71.585) (end 99.4 72.15) (width 0.4) (layer "B.Cu") (net 1))
  (segment (start 119.5 66.6) (end 118.884999 66.6) (width 0.4) (layer "B.Cu") (net 1))
  (segment (start 110.4 73.7175) (end 110.4 72.8825) (width 0.4) (layer "B.Cu") (net 1))
  (segment (start 149.870965 91.129035) (end 149.9 91.1) (width 0.2) (layer "B.Cu") (net 1))
  (segment (start 83.03 99.75) (end 83.2 99.58) (width 0.2) (layer "B.Cu") (net 1))
  (segment (start 83.2 99.58) (end 83.2 99.175) (width 0.2) (layer "B.Cu") (net 1))
  (segment (start 152.4 111) (end 152.4 111.685) (width 0.4) (layer "B.Cu") (net 1))
  (segment (start 132.288559 121.774723) (end 131.125277 121.774723) (width 0.182) (layer "B.Cu") (net 1))
  (segment (start 103.5 138.4) (end 103.974964 138.4) (width 0.182) (layer "B.Cu") (net 1))
  (segment (start 96.239999 67.675) (end 96.775 67.675) (width 0.182) (layer "B.Cu") (net 1))
  (segment (start 151.385 93.7) (end 151.9 93.7) (width 0.2) (layer "B.Cu") (net 1))
  (segment (start 133.364723 115.774723) (end 133.37 115.78) (width 0.182) (layer "B.Cu") (net 1))
  (segment (start 132.288836 123.274723) (end 132.288559 123.275) (width 0.182) (layer "B.Cu") (net 1))
  (segment (start 129.75 70.43) (end 129.75 71.7) (width 0.4) (layer "B.Cu") (net 1))
  (segment (start 132.288559 118.774723) (end 131.200277 118.774723) (width 0.182) (layer "B.Cu") (net 1))
  (segment (start 96.235 66.525) (end 96.8 66.525) (width 0.182) (layer "B.Cu") (net 1))
  (segment (start 156.05 86.65) (end 155.585 86.65) (width 0.4) (layer "B.Cu") (net 1))
  (segment (start 139.025 121.615) (end 139.025 121.2) (width 0.4) (layer "B.Cu") (net 1))
  (segment (start 92.755 85.7) (end 91.490002 85.7) (width 0.182) (layer "B.Cu") (net 1))
  (segment (start 110.015 95.965) (end 110.425 95.965) (width 0.182) (layer "B.Cu") (net 1))
  (segment (start 131.225277 129.774723) (end 131.2 129.8) (width 0.2) (layer "B.Cu") (net 1))
  (segment (start 131.125277 121.774723) (end 131.125 121.775) (width 0.182) (layer "B.Cu") (net 1))
  (segment (start 93.411 136.029) (end 93.575 135.865) (width 0.182) (layer "B.Cu") (net 1))
  (segment (start 132.288559 114.274723) (end 133.374723 114.274723) (width 0.2) (layer "B.Cu") (net 1))
  (segment (start 123.875277 127.024723) (end 123.6 127.3) (width 0.2) (layer "B.Cu") (net 1))
  (segment (start 148.425 75.225) (end 148.261 75.389) (width 0.182) (layer "B.Cu") (net 1))
  (segment (start 151.9 93.7) (end 152.1 93.5) (width 0.2) (layer "B.Cu") (net 1))
  (segment (start 133.174723 123.274723) (end 132.288836 123.274723) (width 0.182) (layer "B.Cu") (net 1))
  (segment (start 119.425 93.185) (end 119.48 93.24) (width 0.182) (layer "B.Cu") (net 1))
  (segment (start 148.425 74.475) (end 148.425 75.225) (width 0.182) (layer "B.Cu") (net 1))
  (segment (start 94.2 87.8) (end 94.3 87.9) (width 0.182) (layer "B.Cu") (net 1))
  (segment (start 92.84 128.415) (end 92.84 127.87) (width 0.4) (layer "B.Cu") (net 1))
  (segment (start 94.2 84.655) (end 94.645 84.655) (width 0.182) (layer "B.Cu") (net 1))
  (segment (start 98.15 95) (end 98.175 95.025) (width 0.4) (layer "B.Cu") (net 1))
  (segment (start 81.9 101.25) (end 82.8545 101.25) (width 0.2) (layer "B.Cu") (net 1))
  (segment (start 133.374723 112.774723) (end 133.4 112.8) (width 0.2) (layer "B.Cu") (net 1))
  (segment (start 152.335 108.7) (end 152.85 108.7) (width 0.4) (layer "B.Cu") (net 1))
  (segment (start 152.85 108.7) (end 153 108.85) (width 0.4) (layer "B.Cu") (net 1))
  (segment (start 133.174723 123.274723) (end 133.5 123.6) (width 0.182) (layer "B.Cu") (net 1))
  (segment (start 118.885 67.5) (end 118.835 67.55) (width 0.4) (layer "B.Cu") (net 1))
  (segment (start 139.296137 129.921137) (end 139.025 129.65) (width 0.182) (layer "B.Cu") (net 1))
  (segment (start 131.200277 118.774723) (end 131.2 118.775) (width 0.182) (layer "B.Cu") (net 1))
  (segment (start 92.84 129.055) (end 92.84 129.58) (width 0.4) (layer "B.Cu") (net 1))
  (segment (start 81.9 105.75) (end 83.16 105.75) (width 0.2) (layer "B.Cu") (net 1))
  (segment (start 88.179986 119.77) (end 88.5 119.449986) (width 0.182) (layer "F.Cu") (net 2))
  (segment (start 93.3265 119.844) (end 93.7115 119.534) (width 0.182) (layer "F.Cu") (net 2))
  (segment (start 87.775 119.77) (end 88.179986 119.77) (width 0.182) (layer "F.Cu") (net 2))
  (via (at 88.5 119.449986) (size 0.45) (drill 0.1) (layers "F.Cu" "B.Cu") (net 2))
  (via (at 93.7115 119.534) (size 0.45) (drill 0.1) (layers "F.Cu" "B.Cu") (net 2))
  (segment (start 88.5 120.05) (end 88.5 119.449986) (width 0.109) (layer "In6.Cu") (net 2))
  (segment (start 93.7065 120.0685) (end 93.375 120.4) (width 0.109) (layer "In6.Cu") (net 2))
  (segment (start 93.7065 119.534) (end 93.7065 120.0685) (width 0.109) (layer "In6.Cu") (net 2))
  (segment (start 88.85 120.4) (end 88.5 120.05) (width 0.109) (layer "In6.Cu") (net 2))
  (segment (start 93.375 120.4) (end 88.85 120.4) (width 0.109) (layer "In6.Cu") (net 2))
  (segment (start 87.775 118.78) (end 87.855 118.7) (width 0.182) (layer "F.Cu") (net 3))
  (segment (start 93.3265 119.209) (end 93.7115 118.898999) (width 0.182) (layer "F.Cu") (net 3))
  (segment (start 87.855 118.7) (end 88.499994 118.7) (width 0.182) (layer "F.Cu") (net 3))
  (via (at 93.7115 118.908426) (size 0.45) (drill 0.1) (layers "F.Cu" "B.Cu") (net 3))
  (via (at 88.499994 118.7) (size 0.45) (drill 0.1) (layers "F.Cu" "B.Cu") (net 3))
  (segment (start 88.8795 119.5795) (end 88.8795 119.079506) (width 0.109) (layer "In6.Cu") (net 3))
  (segment (start 89.3 120) (end 88.8795 119.5795) (width 0.109) (layer "In6.Cu") (net 3))
  (segment (start 93.697073 118.908426) (end 93.3 119.305499) (width 0.109) (layer "In6.Cu") (net 3))
  (segment (start 93.1 120) (end 89.3 120) (width 0.109) (layer "In6.Cu") (net 3))
  (segment (start 93.3 119.8) (end 93.1 120) (width 0.109) (layer "In6.Cu") (net 3))
  (segment (start 88.8795 119.079506) (end 88.499994 118.7) (width 0.109) (layer "In6.Cu") (net 3))
  (segment (start 93.3 119.305499) (end 93.3 119.8) (width 0.109) (layer "In6.Cu") (net 3))
  (segment (start 88.2 117.8) (end 88.4 117.6) (width 0.182) (layer "F.Cu") (net 4))
  (segment (start 92.84 118.89) (end 93.3265 118.574) (width 0.182) (layer "F.Cu") (net 4))
  (segment (start 88.4 117.6) (end 88.4 117.5) (width 0.182) (layer "F.Cu") (net 4))
  (segment (start 87.785 117.8) (end 88.2 117.8) (width 0.182) (layer "F.Cu") (net 4))
  (via (at 92.84 118.89) (size 0.45) (drill 0.1) (layers "F.Cu" "B.Cu") (net 4))
  (via (at 88.4 117.5) (size 0.45) (drill 0.1) (layers "F.Cu" "B.Cu") (net 4))
  (segment (start 88.4 117.5) (end 88.4 117.9) (width 0.109) (layer "In6.Cu") (net 4))
  (segment (start 88.4 117.9) (end 89 118.5) (width 0.109) (layer "In6.Cu") (net 4))
  (segment (start 92.45 118.5) (end 92.84 118.89) (width 0.109) (layer "In6.Cu") (net 4))
  (segment (start 89 118.5) (end 92.45 118.5) (width 0.109) (layer "In6.Cu") (net 4))
  (segment (start 93.6365 117.629) (end 93.71049 117.629) (width 0.182) (layer "F.Cu") (net 5))
  (segment (start 87.77 116.81) (end 87.86 116.9) (width 0.182) (layer "F.Cu") (net 5))
  (segment (start 93.3265 117.939) (end 93.6365 117.629) (width 0.182) (layer "F.Cu") (net 5))
  (segment (start 87.86 116.9) (end 88.4 116.9) (width 0.182) (layer "F.Cu") (net 5))
  (via (at 93.71049 117.629) (size 0.45) (drill 0.1) (layers "F.Cu" "B.Cu") (net 5))
  (via (at 88.4 116.9) (size 0.45) (drill 0.1) (layers "F.Cu" "B.Cu") (net 5))
  (segment (start 88.7 116.9) (end 88.9 117.1) (width 0.109) (layer "In6.Cu") (net 5))
  (segment (start 88.9 117.8) (end 89.2 118.1) (width 0.109) (layer "In6.Cu") (net 5))
  (segment (start 88.9 117.1) (end 88.9 117.8) (width 0.109) (layer "In6.Cu") (net 5))
  (segment (start 89.2 118.1) (end 93.2355 118.1) (width 0.109) (layer "In6.Cu") (net 5))
  (segment (start 93.2355 118.1) (end 93.7065 117.629) (width 0.109) (layer "In6.Cu") (net 5))
  (segment (start 88.4 116.9) (end 88.7 116.9) (width 0.109) (layer "In6.Cu") (net 5))
  (segment (start 90.7865 121.749) (end 91.1715 121.439) (width 0.182) (layer "F.Cu") (net 6))
  (via (at 96.7 89.7) (size 0.45) (drill 0.1) (layers "F.Cu" "B.Cu") (net 6))
  (via (at 91.1715 121.439) (size 0.45) (drill 0.1) (layers "F.Cu" "B.Cu") (net 6))
  (segment (start 85.6375 121.7875) (end 86.25 122.4) (width 0.109) (layer "In4.Cu") (net 6))
  (segment (start 92.722928 87.1) (end 86.953942 87.1) (width 0.109) (layer "In4.Cu") (net 6))
  (segment (start 90.6055 122) (end 91.1665 121.439) (width 0.109) (layer "In4.Cu") (net 6))
  (segment (start 85.6375 116.5125) (end 85.6375 121.7875) (width 0.109) (layer "In4.Cu") (net 6))
  (segment (start 86.25 122.4) (end 87.25 122.4) (width 0.109) (layer "In4.Cu") (net 6))
  (segment (start 95.322928 89.7) (end 92.722928 87.1) (width 0.109) (layer "In4.Cu") (net 6))
  (segment (start 87.25 122.4) (end 87.65 122) (width 0.109) (layer "In4.Cu") (net 6))
  (segment (start 86.953942 87.1) (end 83.68 90.373942) (width 0.109) (layer "In4.Cu") (net 6))
  (segment (start 83.68 90.373942) (end 83.68 114.555) (width 0.109) (layer "In4.Cu") (net 6))
  (segment (start 96.7 89.7) (end 95.322928 89.7) (width 0.109) (layer "In4.Cu") (net 6))
  (segment (start 83.68 114.555) (end 85.6375 116.5125) (width 0.109) (layer "In4.Cu") (net 6))
  (segment (start 87.65 122) (end 90.6055 122) (width 0.109) (layer "In4.Cu") (net 6))
  (segment (start 97.315 89.735) (end 97.35 89.7) (width 0.182) (layer "B.Cu") (net 6))
  (segment (start 96.7 89.7) (end 97.35 89.7) (width 0.109) (layer "B.Cu") (net 6))
  (segment (start 97.315 91) (end 97.315 89.735) (width 0.182) (layer "B.Cu") (net 6))
  (segment (start 184.71 78.05) (end 184.23 78.05) (width 0.2) (layer "F.Cu") (net 7))
  (segment (start 184.23 78.05) (end 184.11 78.17) (width 0.2) (layer "F.Cu") (net 7))
  (segment (start 184.91 77.85) (end 184.71 78.05) (width 0.2) (layer "F.Cu") (net 7))
  (via (at 184.91 77.85) (size 0.45) (drill 0.1) (layers "F.Cu" "B.Cu") (net 7))
  (segment (start 184.91 76.94) (end 185.3 76.55) (width 0.4) (layer "B.Cu") (net 7))
  (segment (start 184.91 77.85) (end 184.91 76.94) (width 0.4) (layer "B.Cu") (net 7))
  (segment (start 121.515 95.4) (end 121.515 95.685) (width 0.182) (layer "F.Cu") (net 8))
  (segment (start 92.608 98.728) (end 92.8 98.6) (width 0.2) (layer "F.Cu") (net 8))
  (segment (start 93.3265 99.524) (end 93.75 99.225) (width 0.2) (layer "F.Cu") (net 8))
  (segment (start 90.7865 98.889) (end 90.7865 98.4765) (width 0.2) (layer "F.Cu") (net 8))
  (segment (start 80.325 89.6) (end 79.91 89.6) (width 0.4) (layer "F.Cu") (net 8))
  (segment (start 92.625 98.425) (end 92.8 98.6) (width 0.2) (layer "F.Cu") (net 8))
  (segment (start 92.3665 98.889) (end 92.608 98.728) (width 0.2) (layer "F.Cu") (net 8))
  (segment (start 89.5575 98.62) (end 87.93 98.62) (width 0.2) (layer "F.Cu") (net 8))
  (segment (start 80.55 89.6) (end 80.8 89.85) (width 0.4) (layer "F.Cu") (net 8))
  (segment (start 90.7865 98.4765) (end 90.65 98.34) (width 0.2) (layer "F.Cu") (net 8))
  (segment (start 79.9 88.385) (end 79.9 89.59) (width 0.4) (layer "F.Cu") (net 8))
  (segment (start 91.176 99.524) (end 91.321 99.379) (width 0.2) (layer "F.Cu") (net 8))
  (segment (start 121.515 95.685) (end 121.4 95.8) (width 0.182) (layer "F.Cu") (net 8))
  (segment (start 121.403 96.003) (end 121.4 96) (width 0.182) (layer "F.Cu") (net 8))
  (segment (start 92.49 98.29) (end 92.625 98.425) (width 0.2) (layer "F.Cu") (net 8))
  (segment (start 91.321 99.379) (end 91.321 98.889) (width 0.2) (layer "F.Cu") (net 8))
  (segment (start 91.92 98.29) (end 92.49 98.29) (width 0.2) (layer "F.Cu") (net 8))
  (segment (start 79.815 88.3) (end 79.9 88.385) (width 0.4) (layer "F.Cu") (net 8))
  (segment (start 87.93 98.62) (end 87.25 99.3) (width 0.2) (layer "F.Cu") (net 8))
  (segment (start 90.7865 99.524) (end 91.176 99.524) (width 0.2) (layer "F.Cu") (net 8))
  (segment (start 90.65 98.34) (end 89.8375 98.34) (width 0.2) (layer "F.Cu") (net 8))
  (segment (start 89.8265 98.889) (end 89.5575 98.62) (width 0.2) (layer "F.Cu") (net 8))
  (segment (start 80.55 89.6) (end 80.325 89.6) (width 0.4) (layer "F.Cu") (net 8))
  (segment (start 121.4 95.8) (end 121.4 96) (width 0.182) (layer "F.Cu") (net 8))
  (segment (start 92.608 98.442) (end 92.625 98.425) (width 0.2) (layer "F.Cu") (net 8))
  (segment (start 92.608 98.728) (end 92.608 98.442) (width 0.2) (layer "F.Cu") (net 8))
  (segment (start 91.6 98.61) (end 91.92 98.29) (width 0.2) (layer "F.Cu") (net 8))
  (segment (start 91.321 98.889) (end 91.6 98.61) (width 0.2) (layer "F.Cu") (net 8))
  (segment (start 79.9 89.59) (end 79.91 89.6) (width 0.4) (layer "F.Cu") (net 8))
  (segment (start 93.3265 98.889) (end 93.75 98.6) (width 0.2) (layer "F.Cu") (net 8))
  (segment (start 80.8 89.85) (end 80.8 90.225) (width 0.4) (layer "F.Cu") (net 8))
  (segment (start 89.8375 98.34) (end 89.5575 98.62) (width 0.2) (layer "F.Cu") (net 8))
  (segment (start 121.403 96.7629) (end 121.403 96.003) (width 0.182) (layer "F.Cu") (net 8))
  (via (at 93.75 98) (size 0.45) (drill 0.1) (layers "F.Cu" "B.Cu") (net 8))
  (via (at 151.95 101.1) (size 0.6) (drill 0.25) (layers "F.Cu" "B.Cu") (net 8))
  (via (at 152.75 101.1) (size 0.6) (drill 0.25) (layers "F.Cu" "B.Cu") (net 8))
  (via (at 153.55 101.1) (size 0.6) (drill 0.25) (layers "F.Cu" "B.Cu") (net 8))
  (via (at 154.35 101.1) (size 0.6) (drill 0.25) (layers "F.Cu" "B.Cu") (net 8))
  (via (at 151.15 101.9) (size 0.6) (drill 0.25) (layers "F.Cu" "B.Cu") (net 8))
  (via (at 151.95 101.9) (size 0.6) (drill 0.25) (layers "F.Cu" "B.Cu") (net 8))
  (via (at 152.75 101.9) (size 0.6) (drill 0.25) (layers "F.Cu" "B.Cu") (net 8))
  (via (at 153.55 101.9) (size 0.6) (drill 0.25) (layers "F.Cu" "B.Cu") (net 8))
  (via (at 154.35 101.9) (size 0.6) (drill 0.25) (layers "F.Cu" "B.Cu") (net 8))
  (via (at 152.75 102.7) (size 0.6) (drill 0.25) (layers "F.Cu" "B.Cu") (net 8))
  (via (at 153.55 102.7) (size 0.6) (drill 0.25) (layers "F.Cu" "B.Cu") (net 8))
  (via (at 154.35 102.7) (size 0.6) (drill 0.25) (layers "F.Cu" "B.Cu") (net 8))
  (via (at 151.95 102.7) (size 0.6) (drill 0.25) (layers "F.Cu" "B.Cu") (net 8))
  (via (at 94.11 97.5) (size 0.45) (drill 0.1) (layers "F.Cu" "B.Cu") (net 8))
  (via (at 94.11 96.9) (size 0.45) (drill 0.1) (layers "F.Cu" "B.Cu") (net 8))
  (via (at 93.75 97.19) (size 0.45) (drill 0.1) (layers "F.Cu" "B.Cu") (net 8))
  (via (at 93.27 98.36) (size 0.45) (drill 0.1) (layers "F.Cu" "B.Cu") (net 8))
  (via (at 163.624999 126.025) (size 0.6) (drill 0.25) (layers "F.Cu" "B.Cu") (net 8))
  (via (at 164.825 125.925) (size 0.6) (drill 0.25) (layers "F.Cu" "B.Cu") (net 8))
  (via (at 163.625 126.725) (size 0.6) (drill 0.25) (layers "F.Cu" "B.Cu") (net 8))
  (via (at 164.825 126.625) (size 0.6) (drill 0.25) (layers "F.Cu" "B.Cu") (net 8))
  (via (at 164.225 126.325001) (size 0.6) (drill 0.25) (layers "F.Cu" "B.Cu") (net 8))
  (via (at 164.225 125.675) (size 0.6) (drill 0.25) (layers "F.Cu" "B.Cu") (net 8))
  (via (at 164.825 123.875) (size 0.6) (drill 0.25) (layers "F.Cu" "B.Cu") (net 8))
  (via (at 164.825 124.575) (size 0.6) (drill 0.25) (layers "F.Cu" "B.Cu") (net 8))
  (via (at 164.825 125.274999) (size 0.6) (drill 0.25) (layers "F.Cu" "B.Cu") (net 8))
  (via (at 164.225 124.275) (size 0.6) (drill 0.25) (layers "F.Cu" "B.Cu") (net 8))
  (via (at 164.224999 124.975) (size 0.6) (drill 0.25) (layers "F.Cu" "B.Cu") (net 8))
  (via (at 163.625 123.975) (size 0.6) (drill 0.25) (layers "F.Cu" "B.Cu") (net 8))
  (via (at 163.624999 124.675) (size 0.6) (drill 0.25) (layers "F.Cu" "B.Cu") (net 8))
  (via (at 163.625 125.375) (size 0.6) (drill 0.25) (layers "F.Cu" "B.Cu") (net 8))
  (via (at 151.15 101.1) (size 0.6) (drill 0.25) (layers "F.Cu" "B.Cu") (net 8))
  (via (at 113.965557 104.226723) (size 0.5) (drill 0.15) (layers "F.Cu" "B.Cu") (net 8))
  (via (at 80.55 89.6) (size 0.45) (drill 0.1) (layers "F.Cu" "B.Cu") (net 8))
  (via (at 138.65 97.625) (size 0.45) (drill 0.1) (layers "F.Cu" "B.Cu") (net 8))
  (via (at 173.2 129.5) (size 0.45) (drill 0.1) (layers "F.Cu" "B.Cu") (net 8))
  (via (at 93.75 98.6) (size 0.45) (drill 0.1) (layers "F.Cu" "B.Cu") (net 8))
  (via (at 114.390557 104.701723) (size 0.5) (drill 0.15) (layers "F.Cu" "B.Cu") (net 8))
  (via (at 114.515557 104.151723) (size 0.5) (drill 0.15) (layers "F.Cu" "B.Cu") (net 8))
  (via (at 113.840557 104.776723) (size 0.5) (drill 0.15) (layers "F.Cu" "B.Cu") (net 8))
  (via (at 92.8 98.6) (size 0.45) (drill 0.1) (layers "F.Cu" "B.Cu") (net 8))
  (via (at 80.8 90.225) (size 0.45) (drill 0.1) (layers "F.Cu" "B.Cu") (net 8))
  (via (at 93.75 99.225) (size 0.45) (drill 0.1) (layers "F.Cu" "B.Cu") (net 8))
  (via (at 121.4 96) (size 0.5) (drill 0.15) (layers "F.Cu" "B.Cu") (net 8))
  (segment (start 129.6 100.775) (end 126.15 100.775) (width 0.109) (layer "In2.Cu") (net 8))
  (segment (start 94.263834 99.225) (end 93.75 99.225) (width 0.109) (layer "In2.Cu") (net 8))
  (segment (start 96.090557 101.051723) (end 94.263834 99.225) (width 0.109) (layer "In2.Cu") (net 8))
  (segment (start 112.875 105.925) (end 112.378277 106.421723) (width 0.109) (layer "In2.Cu") (net 8))
  (segment (start 101.590777 106.421723) (end 99.953277 106.421723) (width 0.109) (layer "In2.Cu") (net 8))
  (segment (start 99.456554 105.925) (end 96.873834 105.925) (width 0.109) (layer "In2.Cu") (net 8))
  (segment (start 126.15 100.775) (end 121 105.925) (width 0.109) (layer "In2.Cu") (net 8))
  (segment (start 110.528277 106.421723) (end 110.031554 105.925) (width 0.109) (layer "In2.Cu") (net 8))
  (segment (start 96.090557 105.141723) (end 96.090557 101.051723) (width 0.109) (layer "In2.Cu") (net 8))
  (segment (start 132.75 97.625) (end 129.6 100.775) (width 0.109) (layer "In2.Cu") (net 8))
  (segment (start 112.378277 106.421723) (end 110.528277 106.421723) (width 0.109) (layer "In2.Cu") (net 8))
  (segment (start 121 105.925) (end 112.875 105.925) (width 0.109) (layer "In2.Cu") (net 8))
  (segment (start 102.0875 105.925) (end 101.590777 106.421723) (width 0.109) (layer "In2.Cu") (net 8))
  (segment (start 110.031554 105.925) (end 102.0875 105.925) (width 0.109) (layer "In2.Cu") (net 8))
  (segment (start 99.953277 106.421723) (end 99.456554 105.925) (width 0.109) (layer "In2.Cu") (net 8))
  (segment (start 138.65 97.625) (end 132.75 97.625) (width 0.109) (layer "In2.Cu") (net 8))
  (segment (start 96.873834 105.925) (end 96.090557 105.141723) (width 0.109) (layer "In2.Cu") (net 8))
  (segment (start 173.2 129.5) (end 172.325 130.375) (width 0.109) (layer "In6.Cu") (net 8))
  (segment (start 156.12 130.32) (end 155.25 129.45) (width 0.109) (layer "In6.Cu") (net 8))
  (segment (start 155.25 129.45) (end 155.25 107) (width 0.109) (layer "In6.Cu") (net 8))
  (segment (start 154.35 106.1) (end 151.3 106.1) (width 0.109) (layer "In6.Cu") (net 8))
  (segment (start 172.325 130.6) (end 171.605 131.32) (width 0.109) (layer "In6.Cu") (net 8))
  (segment (start 155.25 107) (end 154.35 106.1) (width 0.109) (layer "In6.Cu") (net 8))
  (segment (start 150.829417 103.970583) (end 144.483834 97.625) (width 0.109) (layer "In6.Cu") (net 8))
  (segment (start 151.3 106.1) (end 150.829417 105.629417) (width 0.109) (layer "In6.Cu") (net 8))
  (segment (start 160.5 130.32) (end 156.12 130.32) (width 0.109) (layer "In6.Cu") (net 8))
  (segment (start 150.829417 105.629417) (end 150.829417 103.970583) (width 0.109) (layer "In6.Cu") (net 8))
  (segment (start 144.483834 97.625) (end 138.65 97.625) (width 0.109) (layer "In6.Cu") (net 8))
  (segment (start 171.605 131.32) (end 161.5 131.32) (width 0.109) (layer "In6.Cu") (net 8))
  (segment (start 172.325 130.375) (end 172.325 130.6) (width 0.109) (layer "In6.Cu") (net 8))
  (segment (start 161.5 131.32) (end 160.5 130.32) (width 0.109) (layer "In6.Cu") (net 8))
  (segment (start 121.599 96.210166) (end 121.599 96.669) (width 0.4) (layer "B.Cu") (net 8))
  (segment (start 173.2 129.5) (end 173.21 129.51) (width 0.182) (layer "B.Cu") (net 8))
  (segment (start 80.775 89.6) (end 80.925 89.75) (width 0.182) (layer "B.Cu") (net 8))
  (segment (start 121.4 96) (end 121.4 96.011166) (width 0.4) (layer "B.Cu") (net 8))
  (segment (start 81.9 90.25) (end 80.825 90.25) (width 0.182) (layer "B.Cu") (net 8))
  (segment (start 80.825 90.25) (end 80.8 90.225) (width 0.182) (layer "B.Cu") (net 8))
  (segment (start 121.4 96.011166) (end 121.599 96.210166) (width 0.4) (layer "B.Cu") (net 8))
  (segment (start 80.925 89.75) (end 81.9 89.75) (width 0.182) (layer "B.Cu") (net 8))
  (segment (start 173.21 129.51) (end 173.925 129.51) (width 0.182) (layer "B.Cu") (net 8))
  (segment (start 80.55 89.6) (end 80.775 89.6) (width 0.182) (layer "B.Cu") (net 8))
  (segment (start 95.15 95) (end 95.15 95.1722) (width 0.109) (layer "B.Cu") (net 8))
  (segment (start 179.3 76.95) (end 179.3 76.55) (width 0.4) (layer "F.Cu") (net 9))
  (segment (start 190.505 78.378) (end 190.505 77.505) (width 0.4) (layer "F.Cu") (net 9))
  (segment (start 184.125 71.9) (end 187.131373 71.9) (width 0.4) (layer "F.Cu") (net 9))
  (segment (start 189.6 71.3) (end 189.5 71.2) (width 0.4) (layer "F.Cu") (net 9))
  (segment (start 189.6 71.95) (end 189.6 71.3) (width 0.4) (layer "F.Cu") (net 9))
  (segment (start 179.3 76.55) (end 179.3 76.2) (width 0.4) (layer "F.Cu") (net 9))
  (segment (start 190.235 77.235) (end 190.235 76.75) (width 0.4) (layer "F.Cu") (net 9))
  (segment (start 189.6 73.4) (end 191.2 73.4) (width 0.4) (layer "F.Cu") (net 9))
  (segment (start 189.6 71.95) (end 191.2 71.95) (width 0.4) (layer "F.Cu") (net 9))
  (segment (start 178.6 76.2) (end 179.3 76.2) (width 0.4) (layer "F.Cu") (net 9))
  (segment (start 189.5 71.2) (end 190.399999 71.2) (width 0.4) (layer "F.Cu") (net 9))
  (segment (start 180.64 71.435) (end 183.66 71.435) (width 0.4) (layer "F.Cu") (net 9))
  (segment (start 180.265 76.55) (end 180.64 76.925) (width 0.4) (layer "F.Cu") (net 9))
  (segment (start 188.799999 71.2) (end 189.5 71.2) (width 0.4) (layer "F.Cu") (net 9))
  (segment (start 190.505 77.505) (end 190.235 77.235) (width 0.4) (layer "F.Cu") (net 9))
  (segment (start 190.235 75.235) (end 190.235 76.75) (width 0.2) (layer "F.Cu") (net 9))
  (segment (start 188.8 72.650001) (end 190.4 72.650001) (width 0.4) (layer "F.Cu") (net 9))
  (segment (start 179.3 76.55) (end 180.265 76.55) (width 0.4) (layer "F.Cu") (net 9))
  (segment (start 187.131373 71.9) (end 187.1766 71.854773) (width 0.4) (layer "F.Cu") (net 9))
  (segment (start 189.6 74.6) (end 190.235 75.235) (width 0.2) (layer "F.Cu") (net 9))
  (segment (start 183.66 71.435) (end 184.125 71.9) (width 0.4) (layer "F.Cu") (net 9))
  (segment (start 187.1766 71.854773) (end 188.145226 71.854773) (width 0.4) (layer "F.Cu") (net 9))
  (segment (start 178.55 76.95) (end 179.3 76.95) (width 0.4) (layer "F.Cu") (net 9))
  (segment (start 189.6 73.4) (end 189.6 74.6) (width 0.2) (layer "F.Cu") (net 9))
  (segment (start 188.145226 71.854773) (end 188.799999 71.2) (width 0.4) (layer "F.Cu") (net 9))
  (via (at 163.575 87.15) (size 0.8) (drill 0.4) (layers "F.Cu" "B.Cu") (net 9))
  (via (at 165.575 87.15) (size 0.8) (drill 0.4) (layers "F.Cu" "B.Cu") (net 9))
  (via (at 167.575 87.15) (size 0.8) (drill 0.4) (layers "F.Cu" "B.Cu") (net 9))
  (via (at 169.575 87.15) (size 0.8) (drill 0.4) (layers "F.Cu" "B.Cu") (net 9))
  (via (at 171.575 87.15) (size 0.8) (drill 0.4) (layers "F.Cu" "B.Cu") (net 9))
  (via (at 173.575 87.15) (size 0.8) (drill 0.4) (layers "F.Cu" "B.Cu") (net 9))
  (via (at 175.575 87.15) (size 0.8) (drill 0.4) (layers "F.Cu" "B.Cu") (net 9))
  (via (at 177.575 87.15) (size 0.8) (drill 0.4) (layers "F.Cu" "B.Cu") (net 9))
  (via (at 179.575 87.15) (size 0.8) (drill 0.4) (layers "F.Cu" "B.Cu") (net 9))
  (via (at 181.575 87.15) (size 0.8) (drill 0.4) (layers "F.Cu" "B.Cu") (net 9))
  (via (at 183.575 87.15) (size 0.8) (drill 0.4) (layers "F.Cu" "B.Cu") (net 9))
  (via (at 164.575 88.15) (size 0.8) (drill 0.4) (layers "F.Cu" "B.Cu") (net 9))
  (via (at 166.575 88.15) (size 0.8) (drill 0.4) (layers "F.Cu" "B.Cu") (net 9))
  (via (at 168.575 88.15) (size 0.8) (drill 0.4) (layers "F.Cu" "B.Cu") (net 9))
  (via (at 170.575 88.15) (size 0.8) (drill 0.4) (layers "F.Cu" "B.Cu") (net 9))
  (via (at 172.575 88.15) (size 0.8) (drill 0.4) (layers "F.Cu" "B.Cu") (net 9))
  (via (at 174.575 88.15) (size 0.8) (drill 0.4) (layers "F.Cu" "B.Cu") (net 9))
  (via (at 176.575 88.15) (size 0.8) (drill 0.4) (layers "F.Cu" "B.Cu") (net 9))
  (via (at 178.575 88.15) (size 0.8) (drill 0.4) (layers "F.Cu" "B.Cu") (net 9))
  (via (at 180.575 88.15) (size 0.8) (drill 0.4) (layers "F.Cu" "B.Cu") (net 9))
  (via (at 182.575 88.15) (size 0.8) (drill 0.4) (layers "F.Cu" "B.Cu") (net 9))
  (via (at 191.2 73.4) (size 0.8) (drill 0.4) (layers "F.Cu" "B.Cu") (net 9))
  (via (at 190.4 72.650001) (size 0.8) (drill 0.4) (layers "F.Cu" "B.Cu") (net 9))
  (via (at 190.399999 71.2) (size 0.8) (drill 0.4) (layers "F.Cu" "B.Cu") (net 9))
  (via (at 191.2 71.95) (size 0.8) (drill 0.4) (layers "F.Cu" "B.Cu") (net 9))
  (via (at 189.6 71.95) (size 0.8) (drill 0.4) (layers "F.Cu" "B.Cu") (net 9))
  (via (at 188.8 72.650001) (size 0.8) (drill 0.4) (layers "F.Cu" "B.Cu") (net 9))
  (via (at 189.6 73.4) (size 0.8) (drill 0.4) (layers "F.Cu" "B.Cu") (net 9))
  (via (at 188.799999 71.2) (size 0.8) (drill 0.4) (layers "F.Cu" "B.Cu") (net 9))
  (via (at 178.55 76.95) (size 0.6) (drill 0.25) (layers "F.Cu" "B.Cu") (net 9))
  (via (at 179.3 76.95) (size 0.6) (drill 0.25) (layers "F.Cu" "B.Cu") (net 9))
  (via (at 179.3 76.2) (size 0.6) (drill 0.25) (layers "F.Cu" "B.Cu") (net 9))
  (via (at 178.6 76.2) (size 0.6) (drill 0.25) (layers "F.Cu" "B.Cu") (net 9))
  (segment (start 180.64 74.475) (end 182.075 74.475) (width 0.4) (layer "F.Cu") (net 10))
  (segment (start 184.575 75.45) (end 184.125 75.9) (width 0.4) (layer "F.Cu") (net 10))
  (segment (start 186.55 76.55) (end 186.55 78.233) (width 0.4) (layer "F.Cu") (net 10))
  (segment (start 186.695 80.06) (end 186.925 80.29) (width 0.4) (layer "F.Cu") (net 10))
  (segment (start 187.8 80.29) (end 188.6 81.09) (width 0.4) (layer "F.Cu") (net 10))
  (segment (start 179.05 69.15) (end 179.05 73.75) (width 0.4) (layer "F.Cu") (net 10))
  (segment (start 179.215 68.985) (end 179.05 69.15) (width 0.4) (layer "F.Cu") (net 10))
  (segment (start 182.075 74.475) (end 182.7 75.1) (width 0.4) (layer "F.Cu") (net 10))
  (segment (start 186.925 80.29) (end 187.8 80.29) (width 0.4) (layer "F.Cu") (net 10))
  (segment (start 186.55 78.233) (end 186.695 78.378) (width 0.4) (layer "F.Cu") (net 10))
  (segment (start 180.64 68.985) (end 179.215 68.985) (width 0.4) (layer "F.Cu") (net 10))
  (segment (start 183.9 75.1) (end 184.125 75.325) (width 0.4) (layer "F.Cu") (net 10))
  (segment (start 186.55 75.45) (end 184.575 75.45) (width 0.4) (layer "F.Cu") (net 10))
  (segment (start 187.1766 73.954773) (end 187.1766 74.8234) (width 0.4) (layer "F.Cu") (net 10))
  (segment (start 186.695 78.378) (end 186.695 80.06) (width 0.4) (layer "F.Cu") (net 10))
  (segment (start 179.775 74.475) (end 180.64 74.475) (width 0.4) (layer "F.Cu") (net 10))
  (segment (start 186.55 75.45) (end 186.55 76.55) (width 0.4) (layer "F.Cu") (net 10))
  (segment (start 182.7 75.1) (end 183.9 75.1) (width 0.4) (layer "F.Cu") (net 10))
  (segment (start 184.125 75.325) (end 184.125 75.9) (width 0.4) (layer "F.Cu") (net 10))
  (segment (start 179.05 73.75) (end 179.775 74.475) (width 0.4) (layer "F.Cu") (net 10))
  (segment (start 187.1766 74.8234) (end 186.55 75.45) (width 0.4) (layer "F.Cu") (net 10))
  (segment (start 187.1 86.8) (end 186.695 86.395) (width 0.4) (layer "F.Cu") (net 11))
  (segment (start 187.1 86.8) (end 183.26 90.64) (width 0.4) (layer "F.Cu") (net 11))
  (segment (start 190.505 83.802) (end 190.505 85.895) (width 0.4) (layer "F.Cu") (net 11))
  (segment (start 186.695 83.802) (end 186.695 82.695) (width 0.4) (layer "F.Cu") (net 11))
  (segment (start 184.4 80.4) (end 182.87 80.4) (width 0.4) (layer "F.Cu") (net 11))
  (segment (start 190.505 85.895) (end 189.6 86.8) (width 0.4) (layer "F.Cu") (net 11))
  (segment (start 186.695 82.695) (end 184.4 80.4) (width 0.4) (layer "F.Cu") (net 11))
  (segment (start 183.26 90.64) (end 180.04 90.64) (width 0.4) (layer "F.Cu") (net 11))
  (segment (start 186.695 86.395) (end 186.695 83.802) (width 0.4) (layer "F.Cu") (net 11))
  (segment (start 189.6 86.8) (end 187.1 86.8) (width 0.4) (layer "F.Cu") (net 11))
  (via (at 164.175 78.15) (size 0.8) (drill 0.4) (layers "F.Cu" "B.Cu") (net 11))
  (via (at 166.175 78.15) (size 0.8) (drill 0.4) (layers "F.Cu" "B.Cu") (free) (net 11))
  (via (at 168.175 78.15) (size 0.8) (drill 0.4) (layers "F.Cu" "B.Cu") (free) (net 11))
  (via (at 170.175 78.15) (size 0.8) (drill 0.4) (layers "F.Cu" "B.Cu") (net 11))
  (via (at 165.175 78.65) (size 0.8) (drill 0.4) (layers "F.Cu" "B.Cu") (net 11))
  (via (at 167.175 78.65) (size 0.8) (drill 0.4) (layers "F.Cu" "B.Cu") (free) (net 11))
  (via (at 169.175 78.65) (size 0.8) (drill 0.4) (layers "F.Cu" "B.Cu") (free) (net 11))
  (via (at 171.175 78.65) (size 0.8) (drill 0.4) (layers "F.Cu" "B.Cu") (net 11))
  (via (at 173.175 78.65) (size 0.8) (drill 0.4) (layers "F.Cu" "B.Cu") (net 11))
  (segment (start 187.8 83.852) (end 187.85 83.802) (width 0.182) (layer "F.Cu") (net 12))
  (segment (start 187.85 83.802) (end 187.965 83.802) (width 0.182) (layer "F.Cu") (net 12))
  (segment (start 187.8 85.2) (end 187.8 83.852) (width 0.4) (layer "F.Cu") (net 12))
  (via (at 187.8 85.2) (size 0.6) (drill 0.25) (layers "F.Cu" "B.Cu") (net 12))
  (segment (start 187.8 90.5) (end 187.66 90.64) (width 0.4) (layer "B.Cu") (net 12))
  (segment (start 187.8 85.2) (end 187.8 90.5) (width 0.4) (layer "B.Cu") (net 12))
  (segment (start 147.925 72.7) (end 148.725 71.9) (width 0.182) (layer "F.Cu") (net 14))
  (segment (start 147.925 73.415) (end 147.925 72.7) (width 0.182) (layer "F.Cu") (net 14))
  (segment (start 188.615 67.62) (end 187.915 67.62) (width 0.4) (layer "F.Cu") (net 14))
  (segment (start 187.215 67.62) (end 187.915 67.62) (width 0.4) (layer "F.Cu") (net 14))
  (segment (start 188.615 67.62) (end 188.655 67.62) (width 0.4) (layer "F.Cu") (net 14))
  (segment (start 187.965 67.57) (end 187.915 67.62) (width 0.4) (layer "F.Cu") (net 14))
  (segment (start 187.975 64.75) (end 187.975 65.375) (width 0.2) (layer "F.Cu") (net 14))
  (segment (start 187.600001 121.449999) (end 187.600001 120.3546) (width 0.109) (layer "F.Cu") (net 14))
  (segment (start 186.6 121.8) (end 187.25 121.8) (width 0.109) (layer "F.Cu") (net 14))
  (segment (start 190.7 63.58) (end 190.7 62.774978) (width 0.182) (layer "F.Cu") (net 14))
  (segment (start 188.350001 65.750001) (end 189.4204 65.750001) (width 0.2) (layer "F.Cu") (net 14))
  (segment (start 190.7 62.774978) (end 190.675 62.749978) (width 0.182) (layer "F.Cu") (net 14))
  (segment (start 187.975 65.375) (end 188.350001 65.750001) (width 0.2) (layer "F.Cu") (net 14))
  (segment (start 188.625 66.9) (end 188.665 66.9) (width 0.4) (layer "F.Cu") (net 14))
  (segment (start 188.625 66.9) (end 187.925 66.9) (width 0.4) (layer "F.Cu") (net 14))
  (segment (start 188.665 66.9) (end 189.365 67.6) (width 0.4) (layer "F.Cu") (net 14))
  (segment (start 187.25 121.8) (end 187.600001 121.449999) (width 0.109) (layer "F.Cu") (net 14))
  (segment (start 187.975 64.75) (end 187.975 66.85) (width 0.4) (layer "F.Cu") (net 14))
  (segment (start 187.225 66.9) (end 187.925 66.9) (width 0.4) (layer "F.Cu") (net 14))
  (segment (start 187.975 66.85) (end 187.925 66.9) (width 0.4) (layer "F.Cu") (net 14))
  (via (at 135.599999 89.25) (size 0.5) (drill 0.15) (layers "F.Cu" "B.Cu") (net 14))
  (via (at 137.100001 89.25) (size 0.5) (drill 0.15) (layers "F.Cu" "B.Cu") (net 14))
  (via (at 136.6 89.25) (size 0.5) (drill 0.15) (layers "F.Cu" "B.Cu") (net 14))
  (via (at 136.1 89.25) (size 0.5) (drill 0.15) (layers "F.Cu" "B.Cu") (net 14))
  (via (at 149.85 69.05) (size 0.6) (drill 0.25) (layers "F.Cu" "B.Cu") (net 14))
  (via (at 187.225 66.9) (size 0.6) (drill 0.25) (layers "F.Cu" "B.Cu") (net 14))
  (via (at 188.625 66.9) (size 0.6) (drill 0.25) (layers "F.Cu" "B.Cu") (net 14))
  (via (at 187.925 66.9) (size 0.6) (drill 0.25) (layers "F.Cu" "B.Cu") (net 14))
  (via (at 190.8 120.3) (size 0.6) (drill 0.25) (layers "F.Cu" "B.Cu") (net 14))
  (via (at 190.8 121.699999) (size 0.6) (drill 0.25) (layers "F.Cu" "B.Cu") (net 14))
  (via (at 190.8 121.000001) (size 0.6) (drill 0.25) (layers "F.Cu" "B.Cu") (net 14))
  (via (at 190.15 120.65) (size 0.6) (drill 0.25) (layers "F.Cu" "B.Cu") (net 14))
  (via (at 190.15 121.349999) (size 0.6) (drill 0.25) (layers "F.Cu" "B.Cu") (net 14))
  (via (at 189.499999 121.699999) (size 0.6) (drill 0.25) (layers "F.Cu" "B.Cu") (net 14))
  (via (at 189.5 120.3) (size 0.6) (drill 0.25) (layers "F.Cu" "B.Cu") (net 14))
  (via (at 189.5 121.000001) (size 0.6) (drill 0.25) (layers "F.Cu" "B.Cu") (net 14))
  (via (at 149.45 68.4) (size 0.6) (drill 0.25) (layers "F.Cu" "B.Cu") (net 14))
  (via (at 147.65 69.05) (size 0.6) (drill 0.25) (layers "F.Cu" "B.Cu") (net 14))
  (via (at 150.1 68.42) (size 0.6) (drill 0.25) (layers "F.Cu" "B.Cu") (net 14))
  (via (at 148.05 68.4) (size 0.6) (drill 0.25) (layers "F.Cu" "B.Cu") (net 14))
  (via (at 149.1 69.05) (size 0.6) (drill 0.25) (layers "F.Cu" "B.Cu") (net 14))
  (via (at 148.75 68.4) (size 0.6) (drill 0.25) (layers "F.Cu" "B.Cu") (net 14))
  (via (at 148.725 71.9) (size 0.45) (drill 0.1) (layers "F.Cu" "B.Cu") (net 14))
  (via (at 187.215 67.62) (size 0.6) (drill 0.25) (layers "F.Cu" "B.Cu") (net 14))
  (via (at 187.915 67.62) (size 0.6) (drill 0.25) (layers "F.Cu" "B.Cu") (net 14))
  (via (at 188.615 67.62) (size 0.6) (drill 0.25) (layers "F.Cu" "B.Cu") (net 14))
  (via (at 139.165 79.035) (size 0.6) (drill 0.25) (layers "F.Cu" "B.Cu") (net 14))
  (via (at 139.915 79.035) (size 0.6) (drill 0.25) (layers "F.Cu" "B.Cu") (net 14))
  (via (at 140.665 79.035) (size 0.6) (drill 0.25) (layers "F.Cu" "B.Cu") (net 14))
  (via (at 140.665 79.785) (size 0.6) (drill 0.25) (layers "F.Cu" "B.Cu") (net 14))
  (via (at 172.9 123.35) (size 0.45) (drill 0.1) (layers "F.Cu" "B.Cu") (net 14))
  (via (at 148.375 69.025) (size 0.6) (drill 0.25) (layers "F.Cu" "B.Cu") (net 14))
  (via (at 190.675 62.749978) (size 0.6) (drill 0.25) (layers "F.Cu" "B.Cu") (net 14))
  (via (at 138.415 79.035) (size 0.6) (drill 0.25) (layers "F.Cu" "B.Cu") (net 14))
  (segment (start 148.075 71.6) (end 148.075 71.4) (width 0.182) (layer "B.Cu") (net 14))
  (segment (start 148.375 71.9) (end 148.075 71.6) (width 0.182) (layer "B.Cu") (net 14))
  (segment (start 148.725 71.9) (end 148.375 71.9) (width 0.182) (layer "B.Cu") (net 14))
  (segment (start 188.625 66.9) (end 188.625 64.4) (width 0.4) (layer "B.Cu") (net 14))
  (segment (start 190.275022 62.749978) (end 190.675 62.749978) (width 0.4) (layer "B.Cu") (net 14))
  (segment (start 188.625 64.4) (end 190.275022 62.749978) (width 0.4) (layer "B.Cu") (net 14))
  (segment (start 173.225 123.675) (end 173.225 124.865) (width 0.2) (layer "B.Cu") (net 14))
  (segment (start 172.9 123.35) (end 173.225 123.675) (width 0.2) (layer "B.Cu") (net 14))
  (segment (start 108.175 144.82) (end 108.175 145.35) (width 0.182) (layer "F.Cu") (net 15))
  (segment (start 112.1 143.535) (end 112.085 143.55) (width 0.182) (layer "F.Cu") (net 15))
  (segment (start 108.175 145.35) (end 108.375 145.55) (width 0.182) (layer "F.Cu") (net 15))
  (segment (start 105 140.925) (end 104.175 140.925) (width 0.182) (layer "F.Cu") (net 15))
  (segment (start 112.085 143.55) (end 112.085 144.165) (width 0.4) (layer "F.Cu") (net 15))
  (segment (start 112.1 142.56) (end 112.1 143.535) (width 0.25) (layer "F.Cu") (net 15))
  (segment (start 105.672282 136.762282) (end 105.985 137.075) (width 0.182) (layer "F.Cu") (net 15))
  (segment (start 105.985 137.95) (end 105.985 137.075) (width 0.182) (layer "F.Cu") (net 15))
  (segment (start 105.400001 136.661273) (end 105.50101 136.762282) (width 0.182) (layer "F.Cu") (net 15))
  (segment (start 105.50101 136.762282) (end 105.672282 136.762282) (width 0.182) (layer "F.Cu") (net 15))
  (segment (start 105.400001 136.0954) (end 105.400001 136.661273) (width 0.182) (layer "F.Cu") (net 15))
  (segment (start 112.025 122.565) (end 112.01 122.55) (width 0.4) (layer "F.Cu") (net 15))
  (segment (start 112.61 122.565) (end 112.025 122.565) (width 0.4) (layer "F.Cu") (net 15))
  (segment (start 116.415 124.135) (end 116.4 124.15) (width 0.4) (layer "F.Cu") (net 15))
  (segment (start 116.415 123.55) (end 116.415 124.135) (width 0.4) (layer "F.Cu") (net 15))
  (segment (start 129.325 83.935) (end 129.975 83.935) (width 0.4) (layer "F.Cu") (net 15))
  (segment (start 123.7 113.08) (end 123.515 113.265) (width 0.2) (layer "F.Cu") (net 15))
  (segment (start 107.95 141.445) (end 107.95 142.158906) (width 0.182) (layer "F.Cu") (net 15))
  (segment (start 123.05 113.265) (end 123.415 113.265) (width 0.2) (layer "F.Cu") (net 15))
  (segment (start 123.7 113.45) (end 123.515 113.265) (width 0.2) (layer "F.Cu") (net 15))
  (segment (start 115.86 93.035) (end 115.85 93.025) (width 0.182) (layer "F.Cu") (net 15))
  (segment (start 115.765139 80.534861) (end 115.615137 80.534861) (width 0.2) (layer "F.Cu") (net 15))
  (segment (start 118.518942 91.187) (end 118.756942 91.425) (width 0.2) (layer "F.Cu") (net 15))
  (segment (start 119.285 118.8) (end 119.285 118.31) (width 0.4) (layer "F.Cu") (net 15))
  (segment (start 112.12 97.465) (end 112.79 97.465) (width 0.4) (layer "F.Cu") (net 15))
  (segment (start 128.31818 78.881816) (end 128.768184 78.881816) (width 0.182) (layer "F.Cu") (net 15))
  (segment (start 128.768184 78.881816) (end 128.85 78.8) (width 0.182) (layer "F.Cu") (net 15))
  (segment (start 110.85 95.49) (end 110.85 94.775) (width 0.4) (layer "F.Cu") (net 15))
  (segment (start 112.61 122.415) (end 112.974811 122.050189) (width 0.2) (layer "F.Cu") (net 15))
  (segment (start 110.725 95.49) (end 109.865 95.49) (width 0.4) (layer "F.Cu") (net 15))
  (segment (start 110.1 117.7) (end 110.1 118.335) (width 0.4) (layer "F.Cu") (net 15))
  (segment (start 104.284999 96.684999) (end 104.3 96.7) (width 0.4) (layer "F.Cu") (net 15))
  (segment (start 110.1 118.335) (end 110.085 118.35) (width 0.4) (layer "F.Cu") (net 15))
  (segment (start 110.085 119.365) (end 110.085 118.35) (width 0.4) (layer "F.Cu") (net 15))
  (segment (start 128.85 78.8) (end 129.465 78.8) (width 0.182) (layer "F.Cu") (net 15))
  (segment (start 126.815 94.9) (end 126.15 94.9) (width 0.4) (layer "F.Cu") (net 15))
  (segment (start 123.415 113.265) (end 123.415 113.315) (width 0.2) (layer "F.Cu") (net 15))
  (segment (start 134.05 135.89) (end 134.46 136.3) (width 0.4) (layer "F.Cu") (net 15))
  (segment (start 102.634999 96.684999) (end 102.525 96.575) (width 0.4) (layer "F.Cu") (net 15))
  (segment (start 107.983938 142.23371) (end 108.004371 142.213277) (width 0.182) (layer "F.Cu") (net 15))
  (segment (start 116.415 118.315) (end 116.4 118.3) (width 0.4) (layer "F.Cu") (net 15))
  (segment (start 116.330142 86.13486) (end 115.47486 86.13486) (width 0.2) (layer "F.Cu") (net 15))
  (segment (start 116.45 93.035) (end 115.86 93.035) (width 0.182) (layer "F.Cu") (net 15))
  (segment (start 136.232999 137.867001) (end 136.232999 137.114001) (width 0.2) (layer "F.Cu") (net 15))
  (segment (start 118.518942 90.323661) (end 118.518942 91.187) (width 0.2) (layer "F.Cu") (net 15))
  (segment (start 110.085 118.35) (end 110.725 118.35) (width 0.4) (layer "F.Cu") (net 15))
  (segment (start 123.085 130.775) (end 123.075 130.785) (width 0.4) (layer "F.Cu") (net 15))
  (segment (start 135.5 137.9) (end 136.5 137.9) (width 0.4) (layer "F.Cu") (net 15))
  (segment (start 123.65 113.4) (end 123.65 113.55) (width 0.4) (layer "F.Cu") (net 15))
  (segment (start 107.948874 142.23371) (end 107.983938 142.23371) (width 0.182) (layer "F.Cu") (net 15))
  (segment (start 113.815 89.875) (end 113.815 90.615) (width 0.182) (layer "F.Cu") (net 15))
  (segment (start 106.35 104.685) (end 106.909998 104.685) (width 0.4) (layer "F.Cu") (net 15))
  (segment (start 126.918943 78.746061) (end 126.918943 79.188943) (width 0.182) (layer "F.Cu") (net 15))
  (segment (start 123.7 113.55) (end 123.7 113.45) (width 0.2) (layer "F.Cu") (net 15))
  (segment (start 112.105 97.48) (end 112.12 97.465) (width 0.4) (layer "F.Cu") (net 15))
  (segment (start 112.6 136.485) (end 112.6 137.1) (width 0.182) (layer "F.Cu") (net 15))
  (segment (start 123.415 113.265) (end 123.415 113.235) (width 0.2) (layer "F.Cu") (net 15))
  (segment (start 116.330142 84.134862) (end 115.714858 84.134862) (width 0.2) (layer "F.Cu") (net 15))
  (segment (start 122.118942 90.323661) (end 122.118942 90.828942) (width 0.2) (layer "F.Cu") (net 15))
  (segment (start 106.35 104.685) (end 105.325 104.685) (width 0.4) (layer "F.Cu") (net 15))
  (segment (start 115.650189 122.6946) (end 115.650189 122.950189) (width 0.182) (layer "F.Cu") (net 15))
  (segment (start 123.85 113.2) (end 123.65 113.4) (width 0.4) (layer "F.Cu") (net 15))
  (segment (start 121.95 130.95) (end 121.55 131.35) (width 0.4) (layer "F.Cu") (net 15))
  (segment (start 115.650189 119.9054) (end 115.650189 119.499811) (width 0.2) (layer "F.Cu") (net 15))
  (segment (start 123.415 113.265) (end 123.585 113.265) (width 0.2) (layer "F.Cu") (net 15))
  (segment (start 115.969001 119.286) (end 116.415 118.840001) (width 0.2) (layer "F.Cu") (net 15))
  (segment (start 120.118943 77.981057) (end 120.118943 78.746061) (width 0.2) (layer "F.Cu") (net 15))
  (segment (start 115.615137 80.534861) (end 115.501266 80.648732) (width 0.2) (layer "F.Cu") (net 15))
  (segment (start 135.2 137.6) (end 135.5 137.9) (width 0.4) (layer "F.Cu") (net 15))
  (segment (start 107.95 142.158906) (end 108.004371 142.213277) (width 0.182) (layer "F.Cu") (net 15))
  (segment (start 115.7875 123.25) (end 116.115 123.25) (width 0.2) (layer "F.Cu") (net 15))
  (segment (start 115.650189 119.499811) (end 115.864 119.286) (width 0.2) (layer "F.Cu") (net 15))
  (segment (start 116.115 123.25) (end 116.415 123.55) (width 0.2) (layer "F.Cu") (net 15))
  (segment (start 134.46 136.3) (end 134.46 136.61) (width 0.4) (layer "F.Cu") (net 15))
  (segment (start 115.47486 86.13486) (end 115.375 86.035) (width 0.2) (layer "F.Cu") (net 15))
  (segment (start 123.515 113.265) (end 123.585 113.265) (width 0.2) (layer "F.Cu") (net 15))
  (segment (start 115.650189 122.6946) (end 115.650189 123.112689) (width 0.2) (layer "F.Cu") (net 15))
  (segment (start 120.518943 78.746061) (end 120.518943 78.018943) (width 0.2) (layer "F.Cu") (net 15))
  (segment (start 115.650189 123.112689) (end 115.7875 123.25) (width 0.2) (layer "F.Cu") (net 15))
  (segment (start 94.068 73.232) (end 94.05 73.25) (width 0.4) (layer "F.Cu") (net 15))
  (segment (start 103.650001 96.684999) (end 104.284999 96.684999) (width 0.4) (layer "F.Cu") (net 15))
  (segment (start 112.974811 122.050189) (end 113.5054 122.050189) (width 0.2) (layer "F.Cu") (net 15))
  (segment (start 127.834996 79.365) (end 128.31818 78.881816) (width 0.182) (layer "F.Cu") (net 15))
  (segment (start 93.69 71.417) (end 94.20349 71.417) (width 0.4) (layer "F.Cu") (net 15))
  (segment (start 126.518941 90.323661) (end 126.518941 91.348941) (width 0.2) (layer "F.Cu") (net 15))
  (segment (start 105.525 132.4) (end 105.525 132.8) (width 0.182) (layer "F.Cu") (net 15))
  (segment (start 124 134.65) (end 133.55 134.65) (width 0.4) (layer "F.Cu") (net 15))
  (segment (start 119.285 118.31) (end 119.225 118.25) (width 0.4) (layer "F.Cu") (net 15))
  (segment (start 123.725277 113.524723) (end 123.7 113.55) (width 0.2) (layer "F.Cu") (net 15))
  (segment (start 109.8 119.5) (end 109.95 119.5) (width 0.4) (layer "F.Cu") (net 15))
  (segment (start 123.415 113.315) (end 123.65 113.55) (width 0.2) (layer "F.Cu") (net 15))
  (segment (start 112.105 99.225) (end 112.105 97.48) (width 0.4) (layer "F.Cu") (net 15))
  (segment (start 124.35 113.2) (end 123.85 113.2) (width 0.4) (layer "F.Cu") (net 15))
  (segment (start 115.714858 84.134862) (end 115.445 83.865004) (width 0.2) (layer "F.Cu") (net 15))
  (segment (start 120.518943 78.018943) (end 120.718943 78.018943) (width 0.2) (layer "F.Cu") (net 15))
  (segment (start 126.8125 94.8975) (end 126.815 94.9) (width 0.4) (layer "F.Cu") (net 15))
  (segment (start 123.075 130.785) (end 122.115 130.785) (width 0.4) (layer "F.Cu") (net 15))
  (segment (start 122.118942 90.828942) (end 122.495 91.205) (width 0.2) (layer "F.Cu") (net 15))
  (segment (start 110.725 118.35) (end 110.75 118.325) (width 0.4) (layer "F.Cu") (net 15))
  (segment (start 126.518941 91.348941) (end 126.565 91.395) (width 0.2) (layer "F.Cu") (net 15))
  (segment (start 105.400001 133.2046) (end 105.400001 132.924999) (width 0.182) (layer "F.Cu") (net 15))
  (segment (start 123.515 113.265) (end 123.415 113.265) (width 0.2) (layer "F.Cu") (net 15))
  (segment (start 124.3 130.775) (end 123.085 130.775) (width 0.4) (layer "F.Cu") (net 15))
  (segment (start 123.7 113.265) (end 123.7 113.55) (width 0.2) (layer "F.Cu") (net 15))
  (segment (start 105.325 104.685) (end 104.69 104.05) (width 0.2) (layer "F.Cu") (net 15))
  (segment (start 120.718943 78.018943) (end 120.918942 78.218942) (width 0.2) (layer "F.Cu") (net 15))
  (segment (start 122.115 130.785) (end 121.95 130.95) (width 0.4) (layer "F.Cu") (net 15))
  (segment (start 115.501266 80.648732) (end 115.501266 80.698696) (width 0.2) (layer "F.Cu") (net 15))
  (segment (start 120.918942 78.218942) (end 120.918942 78.746061) (width 0.2) (layer "F.Cu") (net 15))
  (segment (start 121.55 131.35) (end 121.55 133.35) (width 0.4) (layer "F.Cu") (net 15))
  (segment (start 127.095 79.365) (end 127.834996 79.365) (width 0.182) (layer "F.Cu") (net 15))
  (segment (start 123.415 113.235) (end 123.65 113) (width 0.2) (layer "F.Cu") (net 15))
  (segment (start 115.864 119.286) (end 115.969001 119.286) (width 0.2) (layer "F.Cu") (net 15))
  (segment (start 123.7 113) (end 123.7 113.08) (width 0.2) (layer "F.Cu") (net 15))
  (segment (start 116.415 118.8) (end 116.415 118.315) (width 0.4) (layer "F.Cu") (net 15))
  (segment (start 120.518943 78.018943) (end 120.3 77.8) (width 0.2) (layer "F.Cu") (net 15))
  (segment (start 121.75 133.55) (end 122.9 133.55) (width 0.4) (layer "F.Cu") (net 15))
  (segment (start 103.650001 96.684999) (end 102.634999 96.684999) (width 0.4) (layer "F.Cu") (net 15))
  (segment (start 134.735 136.885) (end 135.2 136.885) (width 0.4) (layer "F.Cu") (net 15))
  (segment (start 95.85 70.04) (end 95.55 70.34) (width 0.4) (layer "F.Cu") (net 15))
  (segment (start 136.733 137.114001) (end 136.733 137.667) (width 0.2) (layer "F.Cu") (net 15))
  (segment (start 122.9 133.55) (end 124 134.65) (width 0.4) (layer "F.Cu") (net 15))
  (segment (start 123.585 113.265) (end 123.7 113.265) (width 0.2) (layer "F.Cu") (net 15))
  (segment (start 134.46 136.61) (end 134.735 136.885) (width 0.4) (layer "F.Cu") (net 15))
  (segment (start 95.55 70.34) (end 95.55 71) (width 0.4) (layer "F.Cu") (net 15))
  (segment (start 121.55 133.35) (end 121.75 133.55) (width 0.4) (layer "F.Cu") (net 15))
  (segment (start 109.95 119.5) (end 110.085 119.365) (width 0.4) (layer "F.Cu") (net 15))
  (segment (start 133.55 134.65) (end 134.05 135.15) (width 0.4) (layer "F.Cu") (net 15))
  (segment (start 116.330142 80.534861) (end 115.615137 80.534861) (width 0.2) (layer "F.Cu") (net 15))
  (segment (start 112.79 97.465) (end 112.9 97.575) (width 0.4) (layer "F.Cu") (net 15))
  (segment (start 120.3 77.8) (end 120.118943 77.981057) (width 0.2) (layer "F.Cu") (net 15))
  (segment (start 123.724723 113.024723) (end 123.7 113) (width 0.2) (layer "F.Cu") (net 15))
  (segment (start 126.8125 93.937499) (end 126.8125 94.8975) (width 0.4) (layer "F.Cu") (net 15))
  (segment (start 112.61 122.565) (end 112.61 122.415) (width 0.2) (layer "F.Cu") (net 15))
  (segment (start 94.20349 71.417) (end 94.22049 71.4) (width 0.4) (layer "F.Cu") (net 15))
  (segment (start 136.733 137.667) (end 136.5 137.9) (width 0.2) (layer "F.Cu") (net 15))
  (segment (start 94.605 73.232) (end 94.068 73.232) (width 0.4) (layer "F.Cu") (net 15))
  (segment (start 127.685 118.5) (end 128.3 118.5) (width 0.182) (layer "F.Cu") (net 15))
  (segment (start 116.415 118.840001) (end 116.415 118.8) (width 0.2) (layer "F.Cu") (net 15))
  (segment (start 105.400001 132.924999) (end 105.525 132.8) (width 0.182) (layer "F.Cu") (net 15))
  (segment (start 123.7 113) (end 123.7 113.265) (width 0.2) (layer "F.Cu") (net 15))
  (segment (start 123.7 130.5) (end 123.7 131.05) (width 0.4) (layer "F.Cu") (net 15))
  (segment (start 135.2 136.885) (end 135.2 137.6) (width 0.4) (layer "F.Cu") (net 15))
  (segment (start 126.918943 79.188943) (end 127.095 79.365) (width 0.182) (layer "F.Cu") (net 15))
  (segment (start 134.05 135.15) (end 134.05 135.89) (width 0.4) (layer "F.Cu") (net 15))
  (segment (start 123.85 113.2) (end 123.65 113) (width 0.4) (layer "F.Cu") (net 15))
  (segment (start 105.985 137.95) (end 106.650018 137.95) (width 0.4) (layer "F.Cu") (net 15))
  (segment (start 126.15 94.9) (end 126.1 94.95) (width 0.4) (layer "F.Cu") (net 15))
  (segment (start 109.865 95.49) (end 109.75 95.375) (width 0.4) (layer "F.Cu") (net 15))
  (segment (start 113.815 90.615) (end 113.8 90.63) (width 0.182) (layer "F.Cu") (net 15))
  (via (at 108.375 145.55) (size 0.45) (drill 0.1) (layers "F.Cu" "B.Cu") (net 15))
  (via (at 112.085 144.165) (size 0.45) (drill 0.1) (layers "F.Cu" "B.Cu") (net 15))
  (via (at 116.8 142.8) (size 0.45) (drill 0.1) (layers "F.Cu" "B.Cu") (net 15))
  (via (at 116.8 139.4) (size 0.45) (drill 0.1) (layers "F.Cu" "B.Cu") (net 15))
  (via (at 105 140.925) (size 0.45) (drill 0.1) (layers "F.Cu" "B.Cu") (net 15))
  (via (at 126.1 94.95) (size 0.5) (drill 0.15) (layers "F.Cu" "B.Cu") (net 15))
  (via (at 106.475 133.375) (size 0.45) (drill 0.1) (layers "F.Cu" "B.Cu") (net 15))
  (via (at 100.49 135.2) (size 0.45) (drill 0.1) (layers "F.Cu" "B.Cu") (net 15))
  (via (at 123.7 130.5) (size 0.45) (drill 0.1) (layers "F.Cu" "B.Cu") (net 15))
  (via (at 123.7 131.05) (size 0.45) (drill 0.1) (layers "F.Cu" "B.Cu") (net 15))
  (via (at 116.4 118.3) (size 0.5) (drill 0.15) (layers "F.Cu" "B.Cu") (net 15))
  (via (at 112.01 122.55) (size 0.5) (drill 0.15) (layers "F.Cu" "B.Cu") (net 15))
  (via (at 116.4 124.15) (size 0.5) (drill 0.15) (layers "F.Cu" "B.Cu") (net 15))
  (via (at 118.756942 91.425) (size 0.5) (drill 0.15) (layers "F.Cu" "B.Cu") (net 15))
  (via (at 120.075 121.95) (size 0.5) (drill 0.15) (layers "F.Cu" "B.Cu") (net 15))
  (via (at 120.075 122.65) (size 0.5) (drill 0.15) (layers "F.Cu" "B.Cu") (net 15))
  (via (at 120.075 123.3) (size 0.5) (drill 0.15) (layers "F.Cu" "B.Cu") (net 15))
  (via (at 120.075 123.9) (size 0.5) (drill 0.15) (layers "F.Cu" "B.Cu") (net 15))
  (via (at 163.975 136.124999) (size 0.5) (drill 0.15) (layers "F.Cu" "B.Cu") (net 15))
  (via (at 163.975 135.475) (size 0.5) (drill 0.15) (layers "F.Cu" "B.Cu") (net 15))
  (via (at 164.7 137.35) (size 0.5) (drill 0.15) (layers "F.Cu" "B.Cu") (net 15))
  (via (at 165.35 137.35) (size 0.5) (drill 0.15) (layers "F.Cu" "B.Cu") (net 15))
  (via (at 166 137.35) (size 0.5) (drill 0.15) (layers "F.Cu" "B.Cu") (net 15))
  (via (at 166.65 137.35) (size 0.5) (drill 0.15) (layers "F.Cu" "B.Cu") (net 15))
  (via (at 164.7 138) (size 0.5) (drill 0.15) (layers "F.Cu" "B.Cu") (net 15))
  (via (at 165.35 138) (size 0.5) (drill 0.15) (layers "F.Cu" "B.Cu") (net 15))
  (via (at 166 138) (size 0.5) (drill 0.15) (layers "F.Cu" "B.Cu") (net 15))
  (via (at 166.65 138) (size 0.5) (drill 0.15) (layers "F.Cu" "B.Cu") (net 15))
  (via (at 152.3 104.5) (size 0.6) (drill 0.25) (layers "F.Cu" "B.Cu") (net 15))
  (via (at 153.1 104.5) (size 0.6) (drill 0.25) (layers "F.Cu" "B.Cu") (net 15))
  (via (at 153.9 104.5) (size 0.6) (drill 0.25) (layers "F.Cu" "B.Cu") (net 15))
  (via (at 154.7 104.5) (size 0.6) (drill 0.25) (layers "F.Cu" "B.Cu") (net 15))
  (via (at 152.3 105.3) (size 0.6) (drill 0.25) (layers "F.Cu" "B.Cu") (net 15))
  (via (at 153.1 105.3) (size 0.6) (drill 0.25) (layers "F.Cu" "B.Cu") (net 15))
  (via (at 153.9 105.3) (size 0.6) (drill 0.25) (layers "F.Cu" "B.Cu") (net 15))
  (via (at 154.7 105.3) (size 0.6) (drill 0.25) (layers "F.Cu" "B.Cu") (net 15))
  (via (at 153.05 99.65) (size 0.6) (drill 0.25) (layers "F.Cu" "B.Cu") (net 15))
  (via (at 153.75 98.85) (size 0.6) (drill 0.25) (layers "F.Cu" "B.Cu") (net 15))
  (via (at 153.75 99.65) (size 0.6) (drill 0.25) (layers "F.Cu" "B.Cu") (net 15))
  (via (at 121.1 142.85) (size 0.6) (drill 0.25) (layers "F.Cu" "B.Cu") (net 15))
  (via (at 121.9 142.85) (size 0.6) (drill 0.25) (layers "F.Cu" "B.Cu") (net 15))
  (via (at 120.3 143.65) (size 0.6) (drill 0.25) (layers "F.Cu" "B.Cu") (net 15))
  (via (at 121.1 143.65) (size 0.6) (drill 0.25) (layers "F.Cu" "B.Cu") (net 15))
  (via (at 121.9 143.65) (size 0.6) (drill 0.25) (layers "F.Cu" "B.Cu") (net 15))
  (via (at 120.3 142.85) (size 0.6) (drill 0.25) (layers "F.Cu" "B.Cu") (net 15))
  (via (at 114.240557 102.676723) (size 0.6) (drill 0.25) (layers "F.Cu" "B.Cu") (net 15))
  (via (at 110.75 118.325) (size 0.45) (drill 0.1) (layers "F.Cu" "B.Cu") (net 15))
  (via (at 94.22049 71.4) (size 0.5) (drill 0.15) (layers "F.Cu" "B.Cu") (net 15))
  (via (at 154.45 99.65) (size 0.6) (drill 0.25) (layers "F.Cu" "B.Cu") (net 15))
  (via (at 100.420313 136.029992) (size 0.45) (drill 0.1) (layers "F.Cu" "B.Cu") (net 15))
  (via (at 96.05 85.5) (size 0.5) (drill 0.15) (layers "F.Cu" "B.Cu") (net 15))
  (via (at 94.229434 74.924797) (size 0.45) (drill 0.1) (layers "F.Cu" "B.Cu") (net 15))
  (via (at 115.85 93.025) (size 0.45) (drill 0.1) (layers "F.Cu" "B.Cu") (net 15))
  (via (at 110.1 117.7) (size 0.45) (drill 0.1) (layers "F.Cu" "B.Cu") (net 15))
  (via (at 125.3 144.4) (size 0.6) (drill 0.25) (layers "F.Cu" "B.Cu") (net 15))
  (via (at 128.31818 78.881816) (size 0.5) (drill 0.15) (layers "F.Cu" "B.Cu") (net 15))
  (via (at 153.05 98.85) (size 0.6) (drill 0.25) (layers "F.Cu" "B.Cu") (net 15))
  (via (at 115.445 83.865004) (size 0.5) (drill 0.15) (layers "F.Cu" "B.Cu") (net 15))
  (via (at 129.325 83.935) (size 0.5) (drill 0.15) (layers "F.Cu" "B.Cu") (net 15))
  (via (at 123.15 145.4) (size 0.45) (drill 0.1) (layers "F.Cu" "B.Cu") (net 15))
  (via (at 115.501266 80.698696) (size 0.5) (drill 0.15) (layers "F.Cu" "B.Cu") (net 15))
  (via (at 120.3 77.8) (size 0.5) (drill 0.15) (layers "F.Cu" "B.Cu") (net 15))
  (via (at 100.515 133.5) (size 0.45) (drill 0.1) (layers "F.Cu" "B.Cu") (net 15))
  (via (at 112.9 97.575) (size 0.5) (drill 0.15) (layers "F.Cu" "B.Cu") (net 15))
  (via (at 95.55 71) (size 0.6) (drill 0.25) (layers "F.Cu" "B.Cu") (net 15))
  (via (at 123.65 113) (size 0.5) (drill 0.15) (layers "F.Cu" "B.Cu") (net 15))
  (via (at 151.5 105.3) (size 0.6) (drill 0.25) (layers "F.Cu" "B.Cu") (net 15))
  (via (at 110.375 138.95) (size 0.45) (drill 0.1) (layers "F.Cu" "B.Cu") (net 15))
  (via (at 151.5 104.5) (size 0.6) (drill 0.25) (layers "F.Cu" "B.Cu") (net 15))
  (via (at 123.65 113.55) (size 0.5) (drill 0.15) (layers "F.Cu" "B.Cu") (net 15))
  (via (at 154.45 98.85) (size 0.6) (drill 0.25) (layers "F.Cu" "B.Cu") (net 15))
  (via (at 105.525 132.4) (size 0.45) (drill 0.1) (layers "F.Cu" "B.Cu") (net 15))
  (via (at 122.495 91.205) (size 0.5) (drill 0.15) (layers "F.Cu" "B.Cu") (net 15))
  (via (at 106.650018 137.95) (size 0.45) (drill 0.1) (layers "F.Cu" "B.Cu") (net 15))
  (via (at 94.05 73.25) (size 0.45) (drill 0.1) (layers "F.Cu" "B.Cu") (net 15))
  (via (at 114.240557 102.001723) (size 0.6) (drill 0.25) (layers "F.Cu" "B.Cu") (net 15))
  (via (at 117.3 93.2) (size 0.5) (drill 0.15) (layers "F.Cu" "B.Cu") (net 15))
  (via (at 113.8 90.63) (size 0.45) (drill 0.1) (layers "F.Cu" "B.Cu") (net 15))
  (via (at 163.975 136.775) (size 0.5) (drill 0.15) (layers "F.Cu" "B.Cu") (net 15))
  (via (at 112.6 137.1) (size 0.45) (drill 0.1) (layers "F.Cu" "B.Cu") (net 15))
  (via (at 104.3 96.7) (size 0.5) (drill 0.15) (layers "F.Cu" "B.Cu") (net 15))
  (via (at 124.1 145.4) (size 0.45) (drill 0.1) (layers "F.Cu" "B.Cu") (net 15))
  (via (at 106.909998 104.685) (size 0.5) (drill 0.15) (layers "F.Cu" "B.Cu") (net 15))
  (via (at 108.004371 142.213277) (size 0.5) (drill 0.15) (layers "F.Cu" "B.Cu") (net 15))
  (via (at 124.6 144.4) (size 0.6) (drill 0.25) (layers "F.Cu" "B.Cu") (net 15))
  (via (at 119.225 118.25) (size 0.5) (drill 0.15) (layers "F.Cu" "B.Cu") (net 15))
  (via (at 115.375 86.035) (size 0.5) (drill 0.15) (layers "F.Cu" "B.Cu") (net 15))
  (via (at 125.3 145.1) (size 0.6) (drill 0.25) (layers "F.Cu" "B.Cu") (net 15))
  (via (at 110.85 94.775) (size 0.5) (drill 0.15) (layers "F.Cu" "B.Cu") (net 15))
  (via (at 114.240557 103.401723) (size 0.6) (drill 0.25) (layers "F.Cu" "B.Cu") (net 15))
  (via (at 126.565 91.395) (size 0.5) (drill 0.15) (layers "F.Cu" "B.Cu") (net 15))
  (segment (start 107.965 141.6) (end 107.965 142.217584) (width 0.182) (layer "B.Cu") (net 15))
  (segment (start 108.375 145.55) (end 108.375 144.915) (width 0.4) (layer "B.Cu") (net 15))
  (segment (start 104.35 140.91) (end 104.985 140.91) (width 0.182) (layer "B.Cu") (net 15))
  (segment (start 104.985 140.91) (end 105 140.925) (width 0.182) (layer "B.Cu") (net 15))
  (segment (start 108.375 144.915) (end 108.39 144.9) (width 0.182) (layer "B.Cu") (net 15))
  (segment (start 105.825 133.39) (end 105.79 133.39) (width 0.182) (layer "B.Cu") (net 15))
  (segment (start 105.825 133.39) (end 106.46 133.39) (width 0.4) (layer "B.Cu") (net 15))
  (segment (start 106.46 133.39) (end 106.475 133.375) (width 0.182) (layer "B.Cu") (net 15))
  (segment (start 101.365 135.2) (end 100.49 135.2) (width 0.4) (layer "B.Cu") (net 15))
  (segment (start 124.788559 131.024723) (end 123.725277 131.024723) (width 0.2) (layer "B.Cu") (net 15))
  (segment (start 123.725277 131.024723) (end 123.7 131.05) (width 0.2) (layer "B.Cu") (net 15))
  (segment (start 123.724723 130.524723) (end 123.7 130.5) (width 0.2) (layer "B.Cu") (net 15))
  (segment (start 124.788559 130.524723) (end 123.724723 130.524723) (width 0.2) (layer "B.Cu") (net 15))
  (segment (start 117.9 93.185) (end 117.315 93.185) (width 0.182) (layer "B.Cu") (net 15))
  (segment (start 105.75 132.625) (end 105.525 132.4) (width 0.4) (layer "B.Cu") (net 15))
  (segment (start 124.788559 113.524723) (end 123.725277 113.524723) (width 0.2) (layer "B.Cu") (net 15))
  (segment (start 117.091942 84.37) (end 116.121942 83.4) (width 0.182) (layer "B.Cu") (net 15))
  (segment (start 123.15 146.065) (end 123.15 145.4) (width 0.182) (layer "B.Cu") (net 15))
  (segment (start 94.445 85.7) (end 95.285 85.7) (width 0.182) (layer "B.Cu") (net 15))
  (segment (start 94.615 75.5) (end 94.229434 75.114434) (width 0.4) (layer "B.Cu") (net 15))
  (segment (start 111.2 139.18) (end 110.605 139.18) (width 0.182) (layer "B.Cu") (net 15))
  (segment (start 101.355 133.31) (end 101.165 133.5) (width 0.4) (layer "B.Cu") (net 15))
  (segment (start 100.440321 136.05) (end 100.420313 136.029992) (width 0.4) (layer "B.Cu") (net 15))
  (segment (start 115.615102 80.58486) (end 115.501266 80.698696) (width 0.4) (layer "B.Cu") (net 15))
  (segment (start 126.4 90.485) (end 126.4 91.23) (width 0.4) (layer "B.Cu") (net 15))
  (segment (start 94.5 76.7875) (end 94.55 76.8375) (width 0.182) (layer "B.Cu") (net 15))
  (segment (start 123.7 130.5) (end 123.7 130.75) (width 0.4) (layer "B.Cu") (net 15))
  (segment (start 126.4 91.23) (end 126.565 91.395) (width 0.4) (layer "B.Cu") (net 15))
  (segment (start 101.365 136.05) (end 100.440321 136.05) (width 0.4) (layer "B.Cu") (net 15))
  (segment (start 116.071942 86.4) (end 115.74 86.4) (width 0.4) (layer "B.Cu") (net 15))
  (segment (start 94.615 75.5) (end 94.615 75.885) (width 0.182) (layer "B.Cu") (net 15))
  (segment (start 121.7 90.911166) (end 121.988834 91.2) (width 0.4) (layer "B.Cu") (net 15))
  (segment (start 121.7 90.485) (end 121.7 90.911166) (width 0.4) (layer "B.Cu") (net 15))
  (segment (start 116.8 139.4) (end 116.8 139.3) (width 0.182) (layer "B.Cu") (net 15))
  (segment (start 96.035 85.485) (end 96.05 85.5) (width 0.4) (layer "B.Cu") (net 15))
  (segment (start 94.229434 75.114434) (end 94.229434 74.924797) (width 0.4) (layer "B.Cu") (net 15))
  (segment (start 94.5 76) (end 94.5 76.7875) (width 0.182) (layer "B.Cu") (net 15))
  (segment (start 120.2 78.44) (end 120.26 78.5) (width 0.4) (layer "B.Cu") (net 15))
  (segment (start 121.988834 91.2) (end 122.4 91.2) (width 0.4) (layer "B.Cu") (net 15))
  (segment (start 116.171942 80.58486) (end 115.615102 80.58486) (width 0.4) (layer "B.Cu") (net 15))
  (segment (start 95.285 85.7) (end 95.5 85.485) (width 0.182) (layer "B.Cu") (net 15))
  (segment (start 118.9 90.835) (end 118.9 91.281942) (width 0.4) (layer "B.Cu") (net 15))
  (segment (start 126.4 145.1) (end 125.3 145.1) (width 0.2) (layer "B.Cu") (net 15))
  (segment (start 123.7 130.75) (end 123.7 131.05) (width 0.4) (layer "B.Cu") (net 15))
  (segment (start 115.74 86.4) (end 115.375 86.035) (width 0.4) (layer "B.Cu") (net 15))
  (segment (start 115.7 83.4) (end 115.445 83.655) (width 0.4) (layer "B.Cu") (net 15))
  (segment (start 116.8 139.3) (end 116.6 139.1) (width 0.182) (layer "B.Cu") (net 15))
  (segment (start 120.26 78.5) (end 120.3 78.5) (width 0.4) (layer "B.Cu") (net 15))
  (segment (start 117.091942 84.4) (end 117.091942 84.37) (width 0.182) (layer "B.Cu") (net 15))
  (segment (start 120.3 78.5) (end 120.3 77.8) (width 0.4) (layer "B.Cu") (net 15))
  (segment (start 115.445 83.655) (end 115.445 83.865004) (width 0.4) (layer "B.Cu") (net 15))
  (segment (start 101.165 133.5) (end 100.515 133.5) (width 0.4) (layer "B.Cu") (net 15))
  (segment (start 105.75 133.415) (end 105.75 132.625) (width 0.4) (layer "B.Cu") (net 15))
  (segment (start 94.615 75.885) (end 94.5 76) (width 0.182) (layer "B.Cu") (net 15))
  (segment (start 116.121942 83.4) (end 115.7 83.4) (width 0.4) (layer "B.Cu") (net 15))
  (segment (start 118.9 91.281942) (end 118.756942 91.425) (width 0.4) (layer "B.Cu") (net 15))
  (segment (start 116.5 142.8) (end 116.2 143.1) (width 0.182) (layer "B.Cu") (net 15))
  (segment (start 117.315 93.185) (end 117.3 93.2) (width 0.182) (layer "B.Cu") (net 15))
  (segment (start 124.788559 113.024723) (end 123.724723 113.024723) (width 0.2) (layer "B.Cu") (net 15))
  (segment (start 116.6 139.1) (end 116.185 139.1) (width 0.182) (layer "B.Cu") (net 15))
  (segment (start 116.8 142.8) (end 116.5 142.8) (width 0.182) (layer "B.Cu") (net 15))
  (segment (start 95.5 85.485) (end 96.035 85.485) (width 0.4) (layer "B.Cu") (net 15))
  (segment (start 110.605 139.18) (end 110.375 138.95) (width 0.182) (layer "B.Cu") (net 15))
  (segment (start 116.2 143.1) (end 116.185 143.1) (width 0.182) (layer "B.Cu") (net 15))
  (segment (start 124.1 146.05) (end 124.1 145.4) (width 0.182) (layer "B.Cu") (net 15))
  (segment (start 147.597 84.533002) (end 147.6 84.530002) (width 0.182) (layer "F.Cu") (net 16))
  (segment (start 150.596 85.238) (end 150.590633 85.232633) (width 0.182) (layer "F.Cu") (net 16))
  (segment (start 147.597 85.238) (end 147.597 84.533002) (width 0.182) (layer "F.Cu") (net 16))
  (segment (start 153.3 68.085) (end 153.3 68.7) (width 0.182) (layer "F.Cu") (net 16))
  (segment (start 150.590633 85.232633) (end 150.590633 84.524948) (width 0.182) (layer "F.Cu") (net 16))
  (segment (start 153.27 68.055) (end 153.3 68.085) (width 0.182) (layer "F.Cu") (net 16))
  (segment (start 154.5 68.205) (end 154.5 68.7) (width 0.182) (layer "F.Cu") (net 16))
  (segment (start 154.33 68.035) (end 154.5 68.205) (width 0.182) (layer "F.Cu") (net 16))
  (via (at 150.590633 84.524948) (size 0.5) (drill 0.15) (layers "F.Cu" "B.Cu") (net 16))
  (via (at 137.25 86.7) (size 0.6) (drill 0.25) (layers "F.Cu" "B.Cu") (net 16))
  (via (at 138 86.7) (size 0.6) (drill 0.25) (layers "F.Cu" "B.Cu") (net 16))
  (via (at 136.5 86.7) (size 0.6) (drill 0.25) (layers "F.Cu" "B.Cu") (net 16))
  (via (at 145.6 81.825) (size 0.5) (drill 0.15) (layers "F.Cu" "B.Cu") (net 16))
  (via (at 146.8 81.8) (size 0.5) (drill 0.15) (layers "F.Cu" "B.Cu") (net 16))
  (via (at 138 85.95) (size 0.6) (drill 0.25) (layers "F.Cu" "B.Cu") (net 16))
  (via (at 147 81.1) (size 0.5) (drill 0.15) (layers "F.Cu" "B.Cu") (net 16))
  (via (at 144.95 81.825) (size 0.5) (drill 0.15) (layers "F.Cu" "B.Cu") (net 16))
  (via (at 153.3 68.7) (size 0.45) (drill 0.1) (layers "F.Cu" "B.Cu") (net 16))
  (via (at 154.5 68.7) (size 0.45) (drill 0.1) (layers "F.Cu" "B.Cu") (net 16))
  (via (at 147.6 84.530002) (size 0.5) (drill 0.15) (layers "F.Cu" "B.Cu") (net 16))
  (via (at 146.2 81.8) (size 0.5) (drill 0.15) (layers "F.Cu" "B.Cu") (net 16))
  (segment (start 153.8 68.7) (end 153.3 68.7) (width 0.2) (layer "In2.Cu") (net 16))
  (segment (start 151.7 81.1) (end 153.89 78.91) (width 0.2) (layer "In2.Cu") (net 16))
  (segment (start 153.89 68.81) (end 153.9 68.8) (width 0.2) (layer "In2.Cu") (net 16))
  (segment (start 153.9 68.8) (end 153.8 68.7) (width 0.2) (layer "In2.Cu") (net 16))
  (segment (start 147 81.1) (end 151.7 81.1) (width 0.2) (layer "In2.Cu") (net 16))
  (segment (start 154 68.7) (end 154.5 68.7) (width 0.2) (layer "In2.Cu") (net 16))
  (segment (start 153.9 68.8) (end 154 68.7) (width 0.2) (layer "In2.Cu") (net 16))
  (segment (start 153.89 78.91) (end 153.89 68.81) (width 0.2) (layer "In2.Cu") (net 16))
  (segment (start 153.8 68.7) (end 154 68.7) (width 0.2) (layer "In2.Cu") (net 16))
  (segment (start 151.45 85.277385) (end 150.45 85.277385) (width 0.4) (layer "B.Cu") (net 16))
  (segment (start 146.465 85.28) (end 146.45 85.265) (width 0.4) (layer "B.Cu") (net 16))
  (segment (start 147.5 85.23) (end 147.45 85.28) (width 0.4) (layer "B.Cu") (net 16))
  (segment (start 147.5 84.630002) (end 147.5 85.23) (width 0.4) (layer "B.Cu") (net 16))
  (segment (start 147.6 84.530002) (end 147.5 84.630002) (width 0.4) (layer "B.Cu") (net 16))
  (segment (start 150.590633 84.524948) (end 150.590633 84.609367) (width 0.4) (layer "B.Cu") (net 16))
  (segment (start 150.45 84.75) (end 150.45 85.277385) (width 0.4) (layer "B.Cu") (net 16))
  (segment (start 150.590633 84.609367) (end 150.45 84.75) (width 0.4) (layer "B.Cu") (net 16))
  (segment (start 147.267231 85.242029) (end 147.267231 85.232769) (width 0.2) (layer "B.Cu") (net 16))
  (segment (start 147.45 85.28) (end 146.465 85.28) (width 0.4) (layer "B.Cu") (net 16))
  (segment (start 107.775 145.35) (end 107.575 145.55) (width 0.182) (layer "F.Cu") (net 17))
  (segment (start 107.775 144.82) (end 107.775 145.35) (width 0.182) (layer "F.Cu") (net 17))
  (segment (start 95.2 133.135) (end 95.585 133.135) (width 0.4) (layer "F.Cu") (net 17))
  (segment (start 95.765 133.315) (end 96.95 133.315) (width 0.4) (layer "F.Cu") (net 17))
  (segment (start 95.585 133.135) (end 95.765 133.315) (width 0.4) (layer "F.Cu") (net 17))
  (segment (start 144.195597 126.212994) (end 144.841707 126.212994) (width 0.182) (layer "F.Cu") (net 17))
  (segment (start 144.841707 126.212994) (end 145.032626 126.403913) (width 0.182) (layer "F.Cu") (net 17))
  (segment (start 144.194916 126.212313) (end 144.195597 126.212994) (width 0.182) (layer "F.Cu") (net 17))
  (segment (start 139.225 123) (end 139.025 123.2) (width 0.2) (layer "F.Cu") (net 17))
  (segment (start 139.025 117.77) (end 139.025 118.725) (width 0.182) (layer "F.Cu") (net 17))
  (segment (start 139.025 118.725) (end 138.775 118.975) (width 0.182) (layer "F.Cu") (net 17))
  (segment (start 139.225 122.045) (end 139.225 123) (width 0.2) (layer "F.Cu") (net 17))
  (segment (start 155.269848 87.530152) (end 155.275 87.525) (width 0.2) (layer "F.Cu") (net 17))
  (segment (start 148.545911 92.825911) (end 148.595911 92.775911) (width 0.2) (layer "F.Cu") (net 17))
  (segment (start 94.435 133.135) (end 94.4 133.1) (width 0.4) (layer "F.Cu") (net 17))
  (segment (start 140.235 136.235) (end 139.5 135.5) (width 0.2) (layer "F.Cu") (net 17))
  (segment (start 138.18 120.6) (end 137.865 120.6) (width 0.182) (layer "F.Cu") (net 17))
  (segment (start 141.119953 85.873222) (end 142.079955 85.873222) (width 0.4) (layer "F.Cu") (net 17))
  (segment (start 127.285 98.33) (end 127.68 97.935) (width 0.2) (layer "F.Cu") (net 17))
  (segment (start 131.8 136.6) (end 132.43 136.6) (width 0.2) (layer "F.Cu") (net 17))
  (segment (start 137.71 119.995) (end 137.965 119.74) (width 0.182) (layer "F.Cu") (net 17))
  (segment (start 132.43 136.6) (end 132.53 136.5) (width 0.2) (layer "F.Cu") (net 17))
  (segment (start 131.1 136.775) (end 131.625 136.775) (width 0.182) (layer "F.Cu") (net 17))
  (segment (start 127.8 99) (end 127.9 99) (width 0.2) (layer "F.Cu") (net 17))
  (segment (start 137.71 120.445) (end 137.71 119.995) (width 0.182) (layer "F.Cu") (net 17))
  (segment (start 153.100223 89.59619) (end 153.621621 90.117588) (width 0.182) (layer "F.Cu") (net 17))
  (segment (start 109.4 136.545) (end 109.4 137.1) (width 0.182) (layer "F.Cu") (net 17))
  (segment (start 136.733 135.167) (end 136.9 135) (width 0.2) (layer "F.Cu") (net 17))
  (segment (start 120.895 101.19728) (end 120.717266 101.375014) (width 0.2) (layer "F.Cu") (net 17))
  (segment (start 120.387 101.187014) (end 120.575 101.375014) (width 0.2) (layer "F.Cu") (net 17))
  (segment (start 148.545911 93.054035) (end 148.345911 93.254035) (width 0.2) (layer "F.Cu") (net 17))
  (segment (start 137.965 119.74) (end 138.265 119.74) (width 0.182) (layer "F.Cu") (net 17))
  (segment (start 120.717266 101.375014) (end 120.575 101.375014) (width 0.2) (layer "F.Cu") (net 17))
  (segment (start 95.2 133.135) (end 94.435 133.135) (width 0.4) (layer "F.Cu") (net 17))
  (segment (start 136.733 135.633999) (end 136.733 135.167) (width 0.2) (layer "F.Cu") (net 17))
  (segment (start 123.1151 98.983) (end 123.90928 98.983) (width 0.182) (layer "F.Cu") (net 17))
  (segment (start 141.296875 90.05) (end 141.310911 90.064036) (width 0.2) (layer "F.Cu") (net 17))
  (segment (start 120.387 100.6951) (end 120.387 101.187014) (width 0.2) (layer "F.Cu") (net 17))
  (segment (start 127.285 99) (end 127.8 99) (width 0.2) (layer "F.Cu") (net 17))
  (segment (start 139.485 135.515) (end 139.5 135.5) (width 0.4) (layer "F.Cu") (net 17))
  (segment (start 107.55 141.445) (end 107.55 141.85) (width 0.182) (layer "F.Cu") (net 17))
  (segment (start 136.9 135) (end 138.285 135) (width 0.2) (layer "F.Cu") (net 17))
  (segment (start 148.545911 92.825911) (end 148.545911 93.054035) (width 0.2) (layer "F.Cu") (net 17))
  (segment (start 123.90928 98.983) (end 123.940557 98.951723) (width 0.182) (layer "F.Cu") (net 17))
  (segment (start 138.285 135) (end 138.8 135.515) (width 0.2) (layer "F.Cu") (net 17))
  (segment (start 127.285 99) (end 127.285 98.33) (width 0.2) (layer "F.Cu") (net 17))
  (segment (start 126.175 137.6) (end 126.68 137.6) (width 0.182) (layer "F.Cu") (net 17))
  (segment (start 138.8 135.515) (end 139.485 135.515) (width 0.4) (layer "F.Cu") (net 17))
  (segment (start 132.53 135.93) (end 132.5 135.9) (width 0.2) (layer "F.Cu") (net 17))
  (segment (start 140.65 88.3) (end 141.294185 88.3) (width 0.2) (layer "F.Cu") (net 17))
  (segment (start 140.675 89.175) (end 141.299945 89.175) (width 0.2) (layer "F.Cu") (net 17))
  (segment (start 132.53 136.5) (end 132.53 135.93) (width 0.2) (layer "F.Cu") (net 17))
  (segment (start 142.079955 85.873222) (end 142.082455 85.870722) (width 0.182) (layer "F.Cu") (net 17))
  (segment (start 140.675 90.05) (end 141.296875 90.05) (width 0.2) (layer "F.Cu") (net 17))
  (segment (start 148.595911 92.775911) (end 148.595911 92.114036) (width 0.2) (layer "F.Cu") (net 17))
  (segment (start 154.646522 87.530152) (end 155.269848 87.530152) (width 0.2) (layer "F.Cu") (net 17))
  (segment (start 140.235 138) (end 140.235 136.235) (width 0.2) (layer "F.Cu") (net 17))
  (segment (start 120.895 100.6951) (end 120.895 101.19728) (width 0.2) (layer "F.Cu") (net 17))
  (segment (start 109.35 136.495) (end 109.4 136.545) (width 0.182) (layer "F.Cu") (net 17))
  (segment (start 153.012911 89.59619) (end 152.880757 89.464036) (width 0.182) (layer "F.Cu") (net 17))
  (segment (start 107.45 141.95) (end 107.45 142.2) (width 0.182) (layer "F.Cu") (net 17))
  (segment (start 131.625 136.775) (end 131.8 136.6) (width 0.182) (layer "F.Cu") (net 17))
  (segment (start 153.012911 89.59619) (end 153.100223 89.59619) (width 0.182) (layer "F.Cu") (net 17))
  (segment (start 145.317924 89.015076) (end 144.757002 89.015076) (width 0.182) (layer "F.Cu") (net 17))
  (segment (start 152.880757 89.464036) (end 152.245912 89.464036) (width 0.182) (layer "F.Cu") (net 17))
  (segment (start 107.404696 142.2) (end 107.40451 142.199814) (width 0.2) (layer "F.Cu") (net 17))
  (segment (start 140.25 85.875) (end 140.918175 85.875) (width 0.4) (layer "F.Cu") (net 17))
  (segment (start 107.45 142.2) (end 107.404696 142.2) (width 0.2) (layer "F.Cu") (net 17))
  (segment (start 137.865 120.6) (end 137.71 120.445) (width 0.182) (layer "F.Cu") (net 17))
  (segment (start 145.371 88.962) (end 145.317924 89.015076) (width 0.182) (layer "F.Cu") (net 17))
  (segment (start 107.55 141.85) (end 107.45 141.95) (width 0.182) (layer "F.Cu") (net 17))
  (segment (start 140.918175 85.875) (end 140.919953 85.873222) (width 0.182) (layer "F.Cu") (net 17))
  (segment (start 140.675 90.975) (end 141.299946 90.975) (width 0.2) (layer "F.Cu") (net 17))
  (via (at 107.575 145.55) (size 0.45) (drill 0.1) (layers "F.Cu" "B.Cu") (net 17))
  (via (at 116.8 141.1) (size 0.45) (drill 0.1) (layers "F.Cu" "B.Cu") (net 17))
  (via (at 145.032626 126.403913) (size 0.45) (drill 0.1) (layers "F.Cu" "B.Cu") (net 17))
  (via (at 138.775 118.975) (size 0.45) (drill 0.1) (layers "F.Cu" "B.Cu") (net 17))
  (via (at 139.025 123.2) (size 0.45) (drill 0.1) (layers "F.Cu" "B.Cu") (net 17))
  (via (at 144.757002 89.015076) (size 0.45) (drill 0.1) (layers "F.Cu" "B.Cu") (net 17))
  (via (at 96.5 138.15) (size 0.6) (drill 0.25) (layers "F.Cu" "B.Cu") (net 17))
  (via (at 174.9 116.7) (size 0.6) (drill 0.25) (layers "F.Cu" "B.Cu") (net 17))
  (via (at 128.825 96.225) (size 0.5) (drill 0.15) (layers "F.Cu" "B.Cu") (net 17))
  (via (at 128.825 97.025) (size 0.5) (drill 0.15) (layers "F.Cu" "B.Cu") (net 17))
  (via (at 128.825 97.825) (size 0.5) (drill 0.15) (layers "F.Cu" "B.Cu") (net 17))
  (via (at 137.95 134.5) (size 0.5) (drill 0.15) (layers "F.Cu" "B.Cu") (net 17))
  (via (at 137.25 134.5) (size 0.5) (drill 0.15) (layers "F.Cu" "B.Cu") (net 17))
  (via (at 138.65 134.5) (size 0.5) (drill 0.15) (layers "F.Cu" "B.Cu") (net 17))
  (via (at 139.4 134.5) (size 0.5) (drill 0.15) (layers "F.Cu" "B.Cu") (net 17))
  (via (at 140.1 134.5) (size 0.5) (drill 0.15) (layers "F.Cu" "B.Cu") (net 17))
  (via (at 140.1 135.2) (size 0.5) (drill 0.15) (layers "F.Cu" "B.Cu") (net 17))
  (via (at 140.575 89.175) (size 0.5) (drill 0.15) (layers "F.Cu" "B.Cu") (net 17))
  (via (at 153.9 85.6) (size 0.5) (drill 0.15) (layers "F.Cu" "B.Cu") (net 17))
  (via (at 126.68 137.6) (size 0.45) (drill 0.1) (layers "F.Cu" "B.Cu") (net 17))
  (via (at 95.7 138.15) (size 0.6) (drill 0.25) (layers "F.Cu" "B.Cu") (net 17))
  (via (at 153.9 86.5) (size 0.5) (drill 0.15) (layers "F.Cu" "B.Cu") (net 17))
  (via (at 109.4 137.1) (size 0.45) (drill 0.1) (layers "F.Cu" "B.Cu") (net 17))
  (via (at 127.9 99) (size 0.5) (drill 0.15) (layers "F.Cu" "B.Cu") (net 17))
  (via (at 96.1 86.3) (size 0.5) (drill 0.15) (layers "F.Cu" "B.Cu") (net 17))
  (via (at 138.265 119.74) (size 0.45) (drill 0.1) (layers "F.Cu" "B.Cu") (net 17))
  (via (at 174.7 115.4) (size 0.6) (drill 0.25) (layers "F.Cu" "B.Cu") (net 17))
  (via (at 107.40451 142.199814) (size 0.5) (drill 0.15) (layers "F.Cu" "B.Cu") (net 17))
  (via (at 110.425 138.100006) (size 0.45) (drill 0.1) (layers "F.Cu" "B.Cu") (net 17))
  (via (at 174.25 114.8) (size 0.6) (drill 0.25) (layers "F.Cu" "B.Cu") (net 17))
  (via (at 140.25 85.875) (size 0.5) (drill 0.15) (layers "F.Cu" "B.Cu") (net 17))
  (via (at 148.545911 92.825911) (size 0.45) (drill 0.1) (layers "F.Cu" "B.Cu") (net 17))
  (via (at 155.275 87.525) (size 0.5) (drill 0.15) (layers "F.Cu" "B.Cu") (net 17))
  (via (at 94.4 133.1) (size 0.45) (drill 0.1) (layers "F.Cu" "B.Cu") (net 17))
  (via (at 132.5 135.9) (size 0.5) (drill 0.15) (layers "F.Cu" "B.Cu") (net 17))
  (via (at 120.575 101.375014) (size 0.45) (drill 0.1) (layers "F.Cu" "B.Cu") (net 17))
  (via (at 172.85 114.8) (size 0.6) (drill 0.25) (layers "F.Cu" "B.Cu") (net 17))
  (via (at 153.9 85.1) (size 0.5) (drill 0.15) (layers "F.Cu" "B.Cu") (net 17))
  (via (at 155.7 93.6) (size 0.5) (drill 0.15) (layers "F.Cu" "B.Cu") (net 17))
  (via (at 153.012911 89.59619) (size 0.5) (drill 0.15) (layers "F.Cu" "B.Cu") (net 17))
  (via (at 140.575 90.975) (size 0.5) (drill 0.15) (layers "F.Cu" "B.Cu") (net 17))
  (via (at 173.55 114.8) (size 0.6) (drill 0.25) (layers "F.Cu" "B.Cu") (net 17))
  (via (at 139.5 135.5) (size 0.5) (drill 0.15) (layers "F.Cu" "B.Cu") (net 17))
  (via (at 140.575 90.05) (size 0.5) (drill 0.15) (layers "F.Cu" "B.Cu") (net 17))
  (via (at 123.940557 98.951723) (size 0.5) (drill 0.15) (layers "F.Cu" "B.Cu") (net 17))
  (via (at 174.75 116.05) (size 0.6) (drill 0.25) (layers "F.Cu" "B.Cu") (net 17))
  (via (at 140.55 88.3) (size 0.5) (drill 0.15) (layers "F.Cu" "B.Cu") (net 17))
  (via (at 152.1 92.8) (size 0.45) (drill 0.1) (layers "F.Cu" "B.Cu") (net 17))
  (via (at 135.9 136.4) (size 0.5) (drill 0.15) (layers "F.Cu" "B.Cu") (net 17))
  (segment (start 95.7 138.15) (end 96.15 138.15) (width 0.4) (layer "In2.Cu") (net 17))
  (segment (start 94.65 137.1) (end 94.65 133.35) (width 0.4) (layer "In2.Cu") (net 17))
  (segment (start 94.65 133.35) (end 94.4 133.1) (width 0.4) (layer "In2.Cu") (net 17))
  (segment (start 95.7 138.15) (end 94.65 137.1) (width 0.4) (layer "In2.Cu") (net 17))
  (segment (start 99.5 140.3) (end 99.5 144.3) (width 0.4) (layer "In2.Cu") (net 17))
  (segment (start 101.25 146.05) (end 107.55 146.05) (width 0.4) (layer "In2.Cu") (net 17))
  (segment (start 97.35 138.15) (end 99.5 140.3) (width 0.4) (layer "In2.Cu") (net 17))
  (segment (start 99.5 144.3) (end 101.25 146.05) (width 0.4) (layer "In2.Cu") (net 17))
  (segment (start 96.15 138.15) (end 97.35 138.15) (width 0.4) (layer "In2.Cu") (net 17))
  (segment (start 107.575 146.025) (end 107.575 145.55) (width 0.4) (layer "In2.Cu") (net 17))
  (segment (start 107.55 146.05) (end 107.575 146.025) (width 0.4) (layer "In2.Cu") (net 17))
  (segment (start 80.045 130.975) (end 87.78 138.71) (width 0.4) (layer "In4.Cu") (net 17))
  (segment (start 78.8 130.975) (end 80.045 130.975) (width 0.4) (layer "In4.Cu") (net 17))
  (segment (start 87.78 138.71) (end 95.14 138.71) (width 0.4) (layer "In4.Cu") (net 17))
  (segment (start 95.14 138.71) (end 95.7 138.15) (width 0.4) (layer "In4.Cu") (net 17))
  (segment (start 95.7 138.15) (end 96.5 138.15) (width 0.4) (layer "In4.Cu") (net 17))
  (segment (start 107.575 145.55) (end 107.575 144.915) (width 0.4) (layer "B.Cu") (net 17))
  (segment (start 116.185 141.1) (end 116.8 141.1) (width 0.182) (layer "B.Cu") (net 17))
  (segment (start 107.45 142) (end 107.45 142.2) (width 0.182) (layer "B.Cu") (net 17))
  (segment (start 107.15 141.7) (end 107.45 142) (width 0.182) (layer "B.Cu") (net 17))
  (segment (start 107.575 144.915) (end 107.56 144.9) (width 0.182) (layer "B.Cu") (net 17))
  (segment (start 107.15 141.6) (end 107.15 141.7) (width 0.182) (layer "B.Cu") (net 17))
  (segment (start 144.329687 126.403913) (end 145.032626 126.403913) (width 0.4) (layer "B.Cu") (net 17))
  (segment (start 139.025 123.2) (end 139.025 122.585) (width 0.4) (layer "B.Cu") (net 17))
  (segment (start 138.775 118.26) (end 138.775 118.975) (width 0.4) (layer "B.Cu") (net 17))
  (segment (start 145.41091 88.964035) (end 145.35987 89.015076) (width 0.182) (layer "B.Cu") (net 17))
  (segment (start 145.35987 89.015076) (end 144.757002 89.015076) (width 0.4) (layer "B.Cu") (net 17))
  (segment (start 145.403373 89.863604) (end 145.41091 89.856066) (width 0.182) (layer "B.Cu") (net 17))
  (segment (start 145.41091 89.856066) (end 145.41091 88.964035) (width 0.4) (layer "B.Cu") (net 17))
  (segment (start 94.445 86.1) (end 95.285 86.1) (width 0.182) (layer "B.Cu") (net 17))
  (segment (start 120.6 100.773999) (end 120.6 101.350014) (width 0.4) (layer "B.Cu") (net 17))
  (segment (start 154.615 86.65) (end 154.05 86.65) (width 0.4) (layer "B.Cu") (net 17))
  (segment (start 78.185 130.36) (end 78.8 130.975) (width 0.4) (layer "B.Cu") (net 17))
  (segment (start 148.545911 92.825911) (end 148.4 92.68) (width 0.4) (layer "B.Cu") (net 17))
  (segment (start 94.445 86.5) (end 95.315 86.5) (width 0.182) (layer "B.Cu") (net 17))
  (segment (start 148.4 92.68) (end 148.4 92.2) (width 0.4) (layer "B.Cu") (net 17))
  (segment (start 153.9 85.1) (end 153.9 85.27) (width 0.4) (layer "B.Cu") (net 17))
  (segment (start 123.88828 99.004) (end 123.940557 98.951723) (width 0.4) (layer "B.Cu") (net 17))
  (segment (start 148.3 92.1) (end 148.3 92.099035) (width 0.4) (layer "B.Cu") (net 17))
  (segment (start 96.085 86.315) (end 96.1 86.3) (width 0.4) (layer "B.Cu") (net 17))
  (segment (start 154.03 85.4) (end 153.9 85.27) (width 0.4) (layer "B.Cu") (net 17))
  (segment (start 152.984101 89.625) (end 153.012911 89.59619) (width 0.4) (layer "B.Cu") (net 17))
  (segment (start 151.37 92.8) (end 152.1 92.8) (width 0.2) (layer "B.Cu") (net 17))
  (segment (start 120.6 101.350014) (end 120.575 101.375014) (width 0.2) (layer "B.Cu") (net 17))
  (segment (start 155.659113 93.559113) (end 155.7 93.6) (width 0.4) (layer "B.Cu") (net 17))
  (segment (start 148.4 92.2) (end 148.3 92.1) (width 0.4) (layer "B.Cu") (net 17))
  (segment (start 95.315 86.5) (end 95.5 86.315) (width 0.182) (layer "B.Cu") (net 17))
  (segment (start 152.330911 89.764035) (end 152.335965 89.764035) (width 0.2) (layer "B.Cu") (net 17))
  (segment (start 155.100255 93.559113) (end 155.659113 93.559113) (width 0.4) (layer "B.Cu") (net 17))
  (segment (start 123.234 99.004) (end 123.88828 99.004) (width 0.4) (layer "B.Cu") (net 17))
  (segment (start 95.285 86.1) (end 95.5 86.315) (width 0.182) (layer "B.Cu") (net 17))
  (segment (start 152.475 89.625) (end 152.984101 89.625) (width 0.4) (layer "B.Cu") (net 17))
  (segment (start 152.3 89.8) (end 152.475 89.625) (width 0.4) (layer "B.Cu") (net 17))
  (segment (start 153.9 85.27) (end 153.9 85.6) (width 0.4) (layer "B.Cu") (net 17))
  (segment (start 95.5 86.315) (end 96.085 86.315) (width 0.4) (layer "B.Cu") (net 17))
  (segment (start 110.574994 138.25) (end 110.425 138.100006) (width 0.182) (layer "B.Cu") (net 17))
  (segment (start 152.335965 89.764035) (end 152.475 89.625) (width 0.2) (layer "B.Cu") (net 17))
  (segment (start 154.05 86.65) (end 153.9 86.5) (width 0.4) (layer "B.Cu") (net 17))
  (segment (start 78.185 129.4) (end 78.185 130.36) (width 0.4) (layer "B.Cu") (net 17))
  (segment (start 111.165 138.25) (end 110.574994 138.25) (width 0.182) (layer "B.Cu") (net 17))
  (segment (start 154.6 85.4) (end 154.03 85.4) (width 0.4) (layer "B.Cu") (net 17))
  (segment (start 129.425 79.75) (end 129.126153 79.451153) (width 0.2) (layer "F.Cu") (net 18))
  (segment (start 122.118942 78.746061) (end 122.118942 79.593942) (width 0.2) (layer "F.Cu") (net 18))
  (segment (start 130.5 90.715) (end 130.485 90.7) (width 0.4) (layer "F.Cu") (net 18))
  (segment (start 127.907742 79.73486) (end 128.46514 79.73486) (width 0.182) (layer "F.Cu") (net 18))
  (segment (start 128.746943 86.13486) (end 127.907743 86.13486) (width 0.182) (layer "F.Cu") (net 18))
  (segment (start 120.93 91.27) (end 120.925 91.265) (width 0.182) (layer "F.Cu") (net 18))
  (segment (start 120.93 91.28) (end 120.918942 91.162862) (width 0.182) (layer "F.Cu") (net 18))
  (segment (start 128.746943 86.13486) (end 128.82514 86.13486) (width 0.182) (layer "F.Cu") (net 18))
  (segment (start 124.918941 78.746061) (end 124.918941 79.581059) (width 0.2) (layer "F.Cu") (net 18))
  (segment (start 116.330142 81.334862) (end 115.522384 81.334862) (width 0.2) (layer "F.Cu") (net 18))
  (segment (start 122.118942 79.593942) (end 122.125 79.6) (width 0.2) (layer "F.Cu") (net 18))
  (segment (start 129.126153 79.451153) (end 128.836592 79.451153) (width 0.2) (layer "F.Cu") (net 18))
  (segment (start 130.5 91.4) (end 130.5 90.715) (width 0.4) (layer "F.Cu") (net 18))
  (segment (start 118.118942 90.323661) (end 118.118942 91.212859) (width 0.2) (layer "F.Cu") (net 18))
  (segment (start 115.522384 81.334862) (end 115.503067 81.315545) (width 0.2) (layer "F.Cu") (net 18))
  (segment (start 120.93 91.28) (end 120.93 91.27) (width 0.182) (layer "F.Cu") (net 18))
  (segment (start 130.485 90.7) (end 131.15 90.7) (width 0.4) (layer "F.Cu") (net 18))
  (segment (start 118.118942 91.212859) (end 117.906942 91.424859) (width 0.2) (layer "F.Cu") (net 18))
  (segment (start 124.118943 91.591057) (end 124.11 91.6) (width 0.182) (layer "F.Cu") (net 18))
  (segment (start 124.918941 79.581059) (end 124.9 79.6) (width 0.2) (layer "F.Cu") (net 18))
  (segment (start 128.748847 79.451153) (end 128.836592 79.451153) (width 0.182) (layer "F.Cu") (net 18))
  (segment (start 128.46514 79.73486) (end 128.748847 79.451153) (width 0.182) (layer "F.Cu") (net 18))
  (segment (start 124.118943 90.323662) (end 124.118943 91.591057) (width 0.182) (layer "F.Cu") (net 18))
  (segment (start 130.5 90.685) (end 130.485 90.7) (width 0.4) (layer "F.Cu") (net 18))
  (segment (start 128.82514 86.13486) (end 128.835 86.125) (width 0.182) (layer "F.Cu") (net 18))
  (segment (start 130.5 90) (end 130.5 90.685) (width 0.4) (layer "F.Cu") (net 18))
  (segment (start 127.907742 82.534862) (end 128.8 82.534862) (width 0.2) (layer "F.Cu") (net 18))
  (segment (start 120.918942 91.162862) (end 120.918942 90.323662) (width 0.182) (layer "F.Cu") (net 18))
  (via (at 122.125 79.6) (size 0.5) (drill 0.15) (layers "F.Cu" "B.Cu") (net 18))
  (via (at 124.9 79.6) (size 0.5) (drill 0.15) (layers "F.Cu" "B.Cu") (net 18))
  (via (at 117.906942 91.424859) (size 0.5) (drill 0.15) (layers "F.Cu" "B.Cu") (net 18))
  (via (at 128.8 82.534862) (size 0.5) (drill 0.15) (layers "F.Cu" "B.Cu") (net 18))
  (via (at 131.2 95.4) (size 0.5) (drill 0.15) (layers "F.Cu" "B.Cu") (net 18))
  (via (at 130.4 96.2) (size 0.5) (drill 0.15) (layers "F.Cu" "B.Cu") (net 18))
  (via (at 131.2 96.2) (size 0.5) (drill 0.15) (layers "F.Cu" "B.Cu") (net 18))
  (via (at 130.4 97) (size 0.5) (drill 0.15) (layers "F.Cu" "B.Cu") (net 18))
  (via (at 131.2 97) (size 0.5) (drill 0.15) (layers "F.Cu" "B.Cu") (net 18))
  (via (at 130.5 91.4) (size 0.5) (drill 0.15) (layers "F.Cu" "B.Cu") (free) (net 18))
  (via (at 131.15 90.7) (size 0.5) (drill 0.15) (layers "F.Cu" "B.Cu") (net 18))
  (via (at 128.836592 79.451153) (size 0.5) (drill 0.15) (layers "F.Cu" "B.Cu") (net 18))
  (via (at 130.5 90) (size 0.5) (drill 0.15) (layers "F.Cu" "B.Cu") (net 18))
  (via (at 115.503067 81.315545) (size 0.5) (drill 0.15) (layers "F.Cu" "B.Cu") (net 18))
  (via (at 124.11 91.6) (size 0.5) (drill 0.15) (layers "F.Cu" "B.Cu") (net 18))
  (via (at 130.4 95.4) (size 0.5) (drill 0.15) (layers "F.Cu" "B.Cu") (net 18))
  (via (at 120.925 91.265) (size 0.5) (drill 0.15) (layers "F.Cu" "B.Cu") (net 18))
  (via (at 128.835 86.125) (size 0.45) (drill 0.1) (layers "F.Cu" "B.Cu") (net 18))
  (segment (start 120.93 91.28) (end 120.928942 91.080108) (width 0.4) (layer "B.Cu") (net 18))
  (segment (start 128.151942 82.524862) (end 128.79 82.524862) (width 0.4) (layer "B.Cu") (net 18))
  (segment (start 116.171942 81.434861) (end 115.622383 81.434861) (width 0.4) (layer "B.Cu") (net 18))
  (segment (start 124.1 90.485) (end 124.1 91.59) (width 0.4) (layer "B.Cu") (net 18))
  (segment (start 115.622383 81.434861) (end 115.503067 81.315545) (width 0.4) (layer "B.Cu") (net 18))
  (segment (start 120.928942 91.080108) (end 120.8 90.951166) (width 0.4) (layer "B.Cu") (net 18))
  (segment (start 128.79 82.524862) (end 128.8 82.534862) (width 0.4) (layer "B.Cu") (net 18))
  (segment (start 124.906941 80.315) (end 124.906941 79.606941) (width 0.4) (layer "B.Cu") (net 18))
  (segment (start 117.9 90.835) (end 117.9 91.417917) (width 0.4) (layer "B.Cu") (net 18))
  (segment (start 124.906941 79.606941) (end 124.9 79.6) (width 0.2) (layer "B.Cu") (net 18))
  (segment (start 120.8 90.951166) (end 120.8 90.485) (width 0.4) (layer "B.Cu") (net 18))
  (segment (start 128.86 86.12) (end 128.752082 86.12) (width 0.4) (layer "B.Cu") (net 18))
  (segment (start 117.9 91.417917) (end 117.906942 91.424859) (width 0.4) (layer "B.Cu") (net 18))
  (segment (start 122.125 80.315) (end 122.125 79.6) (width 0.4) (layer "B.Cu") (net 18))
  (segment (start 128.752082 86.12) (end 128.145 86.12) (width 0.4) (layer "B.Cu") (net 18))
  (segment (start 124.1 91.59) (end 124.11 91.6) (width 0.4) (layer "B.Cu") (net 18))
  (segment (start 149.105709 84.524948) (end 149.105709 85.228291) (width 0.182) (layer "F.Cu") (net 19))
  (segment (start 149.105709 85.228291) (end 149.095911 85.238089) (width 0.182) (layer "F.Cu") (net 19))
  (segment (start 153.464034 89) (end 153.631622 89.167588) (width 0.182) (layer "F.Cu") (net 19))
  (segment (start 152.95 89) (end 153.464034 89) (width 0.182) (layer "F.Cu") (net 19))
  (segment (start 149.095911 92.114036) (end 149.095911 92.695911) (width 0.2) (layer "F.Cu") (net 19))
  (segment (start 144.785 91.575) (end 145.259 91.575) (width 0.182) (layer "F.Cu") (net 19))
  (segment (start 149.095911 92.695911) (end 149.125 92.725) (width 0.2) (layer "F.Cu") (net 19))
  (segment (start 149.245911 93.279034) (end 149.245911 92.845911) (width 0.182) (layer "F.Cu") (net 19))
  (segment (start 144.724035 91.514035) (end 144.785 91.575) (width 0.182) (layer "F.Cu") (net 19))
  (segment (start 149.245911 92.845911) (end 149.125 92.725) (width 0.182) (layer "F.Cu") (net 19))
  (segment (start 152.95 89) (end 152.36 89) (width 0.182) (layer "F.Cu") (net 19))
  (segment (start 144.185 91.514035) (end 144.724035 91.514035) (width 0.182) (layer "F.Cu") (net 19))
  (segment (start 152.36 89) (end 152.322 88.962) (width 0.182) (layer "F.Cu") (net 19))
  (segment (start 145.259 91.575) (end 145.371 91.463) (width 0.182) (layer "F.Cu") (net 19))
  (via (at 143.6 93.9) (size 0.5) (drill 0.15) (layers "F.Cu" "B.Cu") (free) (net 19))
  (via (at 141.65 93.3) (size 0.5) (drill 0.15) (layers "F.Cu" "B.Cu") (net 19))
  (via (at 142.900001 93.3) (size 0.5) (drill 0.15) (layers "F.Cu" "B.Cu") (net 19))
  (via (at 149.105709 84.524948) (size 0.5) (drill 0.15) (layers "F.Cu" "B.Cu") (net 19))
  (via (at 136.434 97.037) (size 0.5) (drill 0.15) (layers "F.Cu" "B.Cu") (net 19))
  (via (at 137.55 97.05) (size 0.5) (drill 0.15) (layers "F.Cu" "B.Cu") (net 19))
  (via (at 137.019 97.042) (size 0.5) (drill 0.15) (layers "F.Cu" "B.Cu") (net 19))
  (via (at 135.903 97.029) (size 0.5) (drill 0.15) (layers "F.Cu" "B.Cu") (net 19))
  (via (at 144.785 91.575) (size 0.5) (drill 0.15) (layers "F.Cu" "B.Cu") (net 19))
  (via (at 149.125 92.725) (size 0.45) (drill 0.1) (layers "F.Cu" "B.Cu") (net 19))
  (via (at 152.95 89) (size 0.5) (drill 0.15) (layers "F.Cu" "B.Cu") (net 19))
  (via (at 140.85 93.9) (size 0.5) (drill 0.15) (layers "F.Cu" "B.Cu") (net 19))
  (segment (start 142.900001 93.3) (end 142.900001 93.908123) (width 0.4) (layer "B.Cu") (net 19))
  (segment (start 148.872615 85.277385) (end 148.45 85.277385) (width 0.4) (layer "B.Cu") (net 19))
  (segment (start 152.330911 88.830911) (end 152.5 89) (width 0.2) (layer "B.Cu") (net 19))
  (segment (start 145.46091 91.514035) (end 144.845965 91.514035) (width 0.4) (layer "B.Cu") (net 19))
  (segment (start 149.105709 85.044291) (end 148.872615 85.277385) (width 0.4) (layer "B.Cu") (net 19))
  (segment (start 149.125 92.219947) (end 149.125 92.725) (width 0.4) (layer "B.Cu") (net 19))
  (segment (start 140.85 93.9) (end 141.584946 93.9) (width 0.4) (layer "B.Cu") (net 19))
  (segment (start 141.65 93.3) (end 141.65 93.965054) (width 0.4) (layer "B.Cu") (net 19))
  (segment (start 142.889035 93.919089) (end 143.580911 93.919089) (width 0.4) (layer "B.Cu") (net 19))
  (segment (start 149.105709 84.933094) (end 149.105709 85.044291) (width 0.4) (layer "B.Cu") (net 19))
  (segment (start 144.845965 91.514035) (end 144.785 91.575) (width 0.182) (layer "B.Cu") (net 19))
  (segment (start 149.105709 84.933094) (end 149.45 85.277385) (width 0.4) (layer "B.Cu") (net 19))
  (segment (start 149.105709 84.524948) (end 149.105709 84.933094) (width 0.4) (layer "B.Cu") (net 19))
  (segment (start 143.580911 93.919089) (end 143.6 93.9) (width 0.4) (layer "B.Cu") (net 19))
  (segment (start 141.584946 93.9) (end 141.654035 93.969089) (width 0.4) (layer "B.Cu") (net 19))
  (segment (start 149.45 85.277385) (end 149.172615 85.277385) (width 0.4) (layer "B.Cu") (net 19))
  (segment (start 141.65 93.965054) (end 141.654035 93.969089) (width 0.4) (layer "B.Cu") (net 19))
  (segment (start 152.5 89) (end 152.95 89) (width 0.4) (layer "B.Cu") (net 19))
  (segment (start 149.245911 92.099036) (end 149.125 92.219947) (width 0.182) (layer "B.Cu") (net 19))
  (segment (start 142.900001 93.908123) (end 142.889035 93.919089) (width 0.4) (layer "B.Cu") (net 19))
  (segment (start 152.3 88.8) (end 152.5 89) (width 0.4) (layer "B.Cu") (net 19))
  (segment (start 152.330911 88.814035) (end 152.330911 88.830911) (width 0.2) (layer "B.Cu") (net 19))
  (segment (start 96.45 147.239999) (end 96.464999 147.225) (width 0.182) (layer "F.Cu") (net 20))
  (segment (start 96.45 148.15) (end 96.45 147.239999) (width 0.4) (layer "F.Cu") (net 20))
  (segment (start 83.175 121.9) (end 83.05 122.025) (width 0.4) (layer "F.Cu") (net 20))
  (segment (start 84.4 121.7) (end 85.634822 121.7) (width 0.182) (layer "F.Cu") (net 20))
  (segment (start 79.91 92.175) (end 80.535 92.175) (width 0.4) (layer "F.Cu") (net 20))
  (segment (start 91.9815 129.044) (end 92.3665 128.734) (width 0.182) (layer "F.Cu") (net 20))
  (segment (start 83.35 124.5) (end 86.15 124.5) (width 0.4) (layer "F.Cu") (net 20))
  (segment (start 97.675 143.025001) (end 97.675 144.145) (width 0.182) (layer "F.Cu") (net 20))
  (segment (start 83.375 120.35) (end 83.975 120.35) (width 0.4) (layer "F.Cu") (net 20))
  (segment (start 97.675 144.145) (end 97.83 144.3) (width 0.182) (layer "F.Cu") (net 20))
  (segment (start 84.359999 119.965001) (end 84.359999 119.35) (width 0.4) (layer "F.Cu") (net 20))
  (segment (start 83.05 120.675) (end 83.375 120.35) (width 0.4) (layer "F.Cu") (net 20))
  (segment (start 83.05 122.45) (end 83.05 120.675) (width 0.4) (layer "F.Cu") (net 20))
  (segment (start 80.7 92.01) (end 80.7 90.95) (width 0.4) (layer "F.Cu") (net 20))
  (segment (start 84.2 121.9) (end 83.175 121.9) (width 0.4) (layer "F.Cu") (net 20))
  (segment (start 84.2 121.9) (end 84.4 121.7) (width 0.182) (layer "F.Cu") (net 20))
  (segment (start 83.975 120.35) (end 84.359999 119.965001) (width 0.4) (layer "F.Cu") (net 20))
  (segment (start 97.83 144.3) (end 97.83 145.05) (width 0.4) (layer "F.Cu") (net 20))
  (segment (start 83.05 124.2) (end 83.35 124.5) (width 0.4) (layer "F.Cu") (net 20))
  (segment (start 91.9815 128.409) (end 92.3665 128.099) (width 0.182) (layer "F.Cu") (net 20))
  (segment (start 97.83 145.05) (end 97.69 145.19) (width 0.4) (layer "F.Cu") (net 20))
  (segment (start 83.05 122.45) (end 83.05 124.2) (width 0.4) (layer "F.Cu") (net 20))
  (segment (start 79.815 90.9) (end 80.65 90.9) (width 0.4) (layer "F.Cu") (net 20))
  (segment (start 86.5 124.15) (end 86.5 123.7) (width 0.4) (layer "F.Cu") (net 20))
  (segment (start 84.325 118.375001) (end 84.449999 118.375001) (width 0.109) (layer "F.Cu") (net 20))
  (segment (start 80.65 90.9) (end 80.7 90.95) (width 0.4) (layer "F.Cu") (net 20))
  (segment (start 80.7 92.01) (end 80.7 91.55) (width 0.4) (layer "F.Cu") (net 20))
  (segment (start 80.535 92.175) (end 80.7 92.01) (width 0.4) (layer "F.Cu") (net 20))
  (segment (start 83.05 122.025) (end 83.05 122.45) (width 0.4) (layer "F.Cu") (net 20))
  (segment (start 86.15 124.5) (end 86.5 124.15) (width 0.4) (layer "F.Cu") (net 20))
  (via (at 97.69 145.19) (size 0.45) (drill 0.1) (layers "F.Cu" "B.Cu") (net 20))
  (via (at 96.45 148.15) (size 0.45) (drill 0.1) (layers "F.Cu" "B.Cu") (net 20))
  (via (at 182.2 138.8) (size 0.6) (drill 0.25) (layers "F.Cu" "B.Cu") (net 20))
  (via (at 183 139.5) (size 0.6) (drill 0.25) (layers "F.Cu" "B.Cu") (net 20))
  (via (at 182.2 139.5) (size 0.6) (drill 0.25) (layers "F.Cu" "B.Cu") (net 20))
  (via (at 84.5 138.2) (size 0.6) (drill 0.25) (layers "F.Cu" "B.Cu") (net 20))
  (via (at 85.3 138.2) (size 0.6) (drill 0.25) (layers "F.Cu" "B.Cu") (net 20))
  (via (at 83.7 139) (size 0.6) (drill 0.25) (layers "F.Cu" "B.Cu") (net 20))
  (via (at 84.5 139) (size 0.6) (drill 0.25) (layers "F.Cu" "B.Cu") (net 20))
  (via (at 85.3 139) (size 0.6) (drill 0.25) (layers "F.Cu" "B.Cu") (net 20))
  (via (at 169 142.4) (size 0.5) (drill 0.15) (layers "F.Cu" "B.Cu") (net 20))
  (via (at 168.5 142.4) (size 0.5) (drill 0.15) (layers "F.Cu" "B.Cu") (net 20))
  (via (at 168 142.4) (size 0.5) (drill 0.15) (layers "F.Cu" "B.Cu") (net 20))
  (via (at 169.5 142.4) (size 0.5) (drill 0.15) (layers "F.Cu" "B.Cu") (net 20))
  (via (at 183.8 138.3) (size 0.6) (drill 0.25) (layers "F.Cu" "B.Cu") (net 20))
  (via (at 80.7 91.55) (size 0.5) (drill 0.15) (layers "F.Cu" "B.Cu") (net 20))
  (via (at 84.2 121.9) (size 0.45) (drill 0.1) (layers "F.Cu" "B.Cu") (net 20))
  (via (at 87.9 129.05) (size 0.6) (drill 0.25) (layers "F.Cu" "B.Cu") (net 20))
  (via (at 183 138.6) (size 0.6) (drill 0.25) (layers "F.Cu" "B.Cu") (net 20))
  (via (at 86.5 123.7) (size 0.45) (drill 0.1) (layers "F.Cu" "B.Cu") (net 20))
  (via (at 91.9815 129.044) (size 0.45) (drill 0.1) (layers "F.Cu" "B.Cu") (net 20))
  (via (at 87.9 128.25) (size 0.6) (drill 0.25) (layers "F.Cu" "B.Cu") (net 20))
  (via (at 183 137.6) (size 0.6) (drill 0.25) (layers "F.Cu" "B.Cu") (net 20))
  (via (at 80.7 90.95) (size 0.5) (drill 0.15) (layers "F.Cu" "B.Cu") (net 20))
  (via (at 91.9815 128.409) (size 0.45) (drill 0.1) (layers "F.Cu" "B.Cu") (net 20))
  (via (at 83.7 138.2) (size 0.6) (drill 0.25) (layers "F.Cu" "B.Cu") (net 20))
  (segment (start 96.45 147.435) (end 96.45 148.15) (width 0.4) (layer "B.Cu") (net 20))
  (segment (start 86.5 123.7) (end 85.785 123.7) (width 0.182) (layer "B.Cu") (net 20))
  (segment (start 91.9865 128.409) (end 91.9865 127.7965) (width 0.4) (layer "B.Cu") (net 20))
  (segment (start 81 91.25) (end 80.7 91.55) (width 0.2) (layer "B.Cu") (net 20))
  (segment (start 84.2 121.9) (end 84.815 121.9) (width 0.4) (layer "B.Cu") (net 20))
  (segment (start 91.9865 129.6535) (end 91.965 129.675) (width 0.4) (layer "B.Cu") (net 20))
  (segment (start 81.9 91.25) (end 81 91.25) (width 0.2) (layer "B.Cu") (net 20))
  (segment (start 91.9865 129.044) (end 91.9865 129.6535) (width 0.4) (layer "B.Cu") (net 20))
  (segment (start 80.9 90.75) (end 80.7 90.95) (width 0.2) (layer "B.Cu") (net 20))
  (segment (start 91.9865 127.7965) (end 91.965 127.775) (width 0.4) (layer "B.Cu") (net 20))
  (segment (start 81.9 90.75) (end 80.9 90.75) (width 0.2) (layer "B.Cu") (net 20))
  (segment (start 85.785 122.8) (end 85.785 123.7) (width 0.182) (layer "B.Cu") (net 20))
  (segment (start 91.16 127.775) (end 91.965 127.775) (width 0.4) (layer "B.Cu") (net 20))
  (segment (start 91.9865 128.409) (end 91.9865 129.044) (width 0.4) (layer "B.Cu") (net 20))
  (segment (start 91.535 140.195) (end 92.435 140.195) (width 0.4) (layer "F.Cu") (net 21))
  (segment (start 89.2 135.725) (end 89.8205 135.725) (width 0.2) (layer "F.Cu") (net 21))
  (segment (start 89.8205 135.725) (end 89.8265 135.719) (width 0.182) (layer "F.Cu") (net 21))
  (segment (start 89.8265 136.354) (end 89.271 136.354) (width 0.2) (layer "F.Cu") (net 21))
  (segment (start 92.435 140.195) (end 93.335 140.195) (width 0.4) (layer "F.Cu") (net 21))
  (via (at 190.275001 139.450001) (size 0.6) (drill 0.25) (layers "F.Cu" "B.Cu") (net 21))
  (via (at 189.5 138.750001) (size 0.6) (drill 0.25) (layers "F.Cu" "B.Cu") (net 21))
  (via (at 189.5 139.45) (size 0.6) (drill 0.25) (layers "F.Cu" "B.Cu") (net 21))
  (via (at 190.275001 138.750001) (size 0.6) (drill 0.25) (layers "F.Cu" "B.Cu") (net 21))
  (via (at 188.8 139.75) (size 0.6) (drill 0.25) (layers "F.Cu" "B.Cu") (net 21))
  (via (at 92.43 139.405) (size 0.6) (drill 0.25) (layers "F.Cu" "B.Cu") (net 21))
  (via (at 91.505 139.405) (size 0.6) (drill 0.25) (layers "F.Cu" "B.Cu") (net 21))
  (via (at 188.1 139.75) (size 0.6) (drill 0.25) (layers "F.Cu" "B.Cu") (net 21))
  (segment (start 186.5296 64.75) (end 185.75 64.75) (width 0.2) (layer "F.Cu") (net 22))
  (segment (start 185.05 62.6) (end 185.1 62.65) (width 0.2) (layer "F.Cu") (net 22))
  (segment (start 185.75 64.75) (end 185.75 64.25) (width 0.2) (layer "F.Cu") (net 22))
  (segment (start 183.8 65.7) (end 183.9 65.7) (width 0.4) (layer "F.Cu") (net 22))
  (segment (start 183.8 65.7) (end 180 65.7) (width 0.4) (layer "F.Cu") (net 22))
  (segment (start 189.4204 64.75) (end 189.95 64.75) (width 0.2) (layer "F.Cu") (net 22))
  (segment (start 185.800001 63.749999) (end 186.5296 63.749999) (width 0.2) (layer "F.Cu") (net 22))
  (segment (start 185.05 61.75) (end 185.05 62.6) (width 0.2) (layer "F.Cu") (net 22))
  (segment (start 185.55 67.25) (end 184 65.7) (width 0.4) (layer "F.Cu") (net 22))
  (segment (start 185.75 62.7) (end 185.7 62.65) (width 0.2) (layer "F.Cu") (net 22))
  (segment (start 185.925601 64.250001) (end 186.5296 64.250001) (width 0.2) (layer "F.Cu") (net 22))
  (segment (start 186.29 60.71) (end 186.29 61.75) (width 0.4) (layer "F.Cu") (net 22))
  (segment (start 186.72 59.95) (end 186.72 60.28) (width 0.4) (layer "F.Cu") (net 22))
  (segment (start 185.75 64.25) (end 185.925601 64.250001) (width 0.2) (layer "F.Cu") (net 22))
  (segment (start 186.72 60.28) (end 186.29 60.71) (width 0.4) (layer "F.Cu") (net 22))
  (segment (start 184 65.7) (end 183.8 65.7) (width 0.4) (layer "F.Cu") (net 22))
  (segment (start 189.95 63.85) (end 189.95 63.25) (width 0.2) (layer "F.Cu") (net 22))
  (segment (start 185.55 69.15) (end 185.55 67.25) (width 0.4) (layer "F.Cu") (net 22))
  (segment (start 189.9 62.65) (end 185.7 62.65) (width 0.2) (layer "F.Cu") (net 22))
  (segment (start 185.75 63.25) (end 186.5296 63.25) (width 0.2) (layer "F.Cu") (net 22))
  (segment (start 186.29 61.75) (end 185.05 61.75) (width 0.2) (layer "F.Cu") (net 22))
  (segment (start 189.95 62.7) (end 189.9 62.65) (width 0.2) (layer "F.Cu") (net 22))
  (segment (start 189.949998 64.249998) (end 189.95 64.25) (width 0.2) (layer "F.Cu") (net 22))
  (segment (start 185.75 63.8) (end 185.800001 63.749999) (width 0.2) (layer "F.Cu") (net 22))
  (segment (start 185.75 63.8) (end 185.75 63.25) (width 0.2) (layer "F.Cu") (net 22))
  (segment (start 189.95 64.25) (end 189.95 63.85) (width 0.2) (layer "F.Cu") (net 22))
  (segment (start 185.75 64.75) (end 184.95 64.75) (width 0.2) (layer "F.Cu") (net 22))
  (segment (start 185.75 63.25) (end 185.75 62.7) (width 0.2) (layer "F.Cu") (net 22))
  (segment (start 185.7 62.65) (end 185.1 62.65) (width 0.2) (layer "F.Cu") (net 22))
  (segment (start 189.4204 63.749999) (end 189.949999 63.749999) (width 0.2) (layer "F.Cu") (net 22))
  (segment (start 189.949999 63.749999) (end 189.95 63.75) (width 0.2) (layer "F.Cu") (net 22))
  (segment (start 184.95 64.75) (end 184 65.7) (width 0.2) (layer "F.Cu") (net 22))
  (segment (start 189.95 63.25) (end 189.95 62.7) (width 0.2) (layer "F.Cu") (net 22))
  (segment (start 189.4204 64.249998) (end 189.949998 64.249998) (width 0.2) (layer "F.Cu") (net 22))
  (segment (start 189.4204 63.25) (end 189.95 63.25) (width 0.2) (layer "F.Cu") (net 22))
  (segment (start 185.75 64.25) (end 185.75 63.8) (width 0.2) (layer "F.Cu") (net 22))
  (segment (start 189.95 64.75) (end 189.95 64.25) (width 0.2) (layer "F.Cu") (net 22))
  (segment (start 180.999999 119.975) (end 181.95 119.975) (width 0.182) (layer "F.Cu") (net 23))
  (segment (start 145.7 134) (end 124.20951 134) (width 0.182) (layer "F.Cu") (net 23))
  (segment (start 171.855 120) (end 172.755 119.1) (width 0.182) (layer "F.Cu") (net 23))
  (segment (start 170.408991 132.620189) (end 170.408991 132.790189) (width 0.182) (layer "F.Cu") (net 23))
  (segment (start 152.1 140.4) (end 145.7 134) (width 0.182) (layer "F.Cu") (net 23))
  (segment (start 115.72 128.17) (end 116.05 128.5) (width 0.182) (layer "F.Cu") (net 23))
  (segment (start 94.16 124.72) (end 97.61 128.17) (width 0.182) (layer "F.Cu") (net 23))
  (segment (start 170.875 133.256198) (end 170.875 133.6) (width 0.182) (layer "F.Cu") (net 23))
  (segment (start 171.325 140.4) (end 152.1 140.4) (width 0.182) (layer "F.Cu") (net 23))
  (segment (start 94.16 124.72) (end 93.5305 124.72) (width 0.182) (layer "F.Cu") (net 23))
  (segment (start 93.5305 124.72) (end 93.3265 124.924) (width 0.182) (layer "F.Cu") (net 23))
  (segment (start 170.408991 132.790189) (end 170.875 133.256198) (width 0.182) (layer "F.Cu") (net 23))
  (segment (start 171.5 120) (end 171.855 120) (width 0.182) (layer "F.Cu") (net 23))
  (segment (start 172.65 139.075) (end 171.325 140.4) (width 0.182) (layer "F.Cu") (net 23))
  (segment (start 170.408991 132.620189) (end 170.269804 132.481002) (width 0.182) (layer "F.Cu") (net 23))
  (segment (start 124.20951 134) (end 122.75 132.54049) (width 0.182) (layer "F.Cu") (net 23))
  (segment (start 169.836052 132.481002) (end 169.615296 132.260246) (width 0.182) (layer "F.Cu") (net 23))
  (segment (start 170.269804 132.481002) (end 169.836052 132.481002) (width 0.182) (layer "F.Cu") (net 23))
  (segment (start 97.61 128.17) (end 115.72 128.17) (width 0.182) (layer "F.Cu") (net 23))
  (segment (start 169.615296 132.260246) (end 169.615296 131.942048) (width 0.182) (layer "F.Cu") (net 23))
  (segment (start 172.755 119.1) (end 172.950002 119.1) (width 0.182) (layer "F.Cu") (net 23))
  (segment (start 172.65 138.7) (end 172.65 139.075) (width 0.182) (layer "F.Cu") (net 23))
  (via (at 172.950002 119.1) (size 0.45) (drill 0.1) (layers "F.Cu" "B.Cu") (net 23))
  (via (at 181.95 119.975) (size 0.45) (drill 0.1) (layers "F.Cu" "B.Cu") (net 23))
  (via (at 169.615296 131.942048) (size 0.45) (drill 0.1) (layers "F.Cu" "B.Cu") (net 23))
  (via (at 116.05 128.5) (size 0.45) (drill 0.1) (layers "F.Cu" "B.Cu") (net 23))
  (via (at 172.65 138.7) (size 0.45) (drill 0.1) (layers "F.Cu" "B.Cu") (net 23))
  (via (at 122.75 132.54049) (size 0.45) (drill 0.1) (layers "F.Cu" "B.Cu") (net 23))
  (segment (start 175.8 120.975) (end 175.85 120.925) (width 0.109) (layer "In2.Cu") (net 23))
  (segment (start 175.85 120.925) (end 175.9 120.925) (width 0.109) (layer "In2.Cu") (net 23))
  (segment (start 175.8 120.925) (end 175.9 120.925) (width 0.109) (layer "In2.Cu") (net 23))
  (segment (start 175.9 120.925) (end 181 120.925) (width 0.109) (layer "In2.Cu") (net 23))
  (segment (start 175.8 120.925) (end 175.8 121.025) (width 0.109) (layer "In2.Cu") (net 23))
  (segment (start 175.5 120.925) (end 175.75 120.925) (width 0.109) (layer "In2.Cu") (net 23))
  (segment (start 175.75 120.925) (end 175.8 120.925) (width 0.109) (layer "In2.Cu") (net 23))
  (segment (start 175.8 121.025) (end 175.8 120.975) (width 0.109) (layer "In2.Cu") (net 23))
  (segment (start 175.8 120.975) (end 175.75 120.925) (width 0.109) (layer "In2.Cu") (net 23))
  (segment (start 175.15 120.575) (end 175.5 120.925) (width 0.109) (layer "In2.Cu") (net 23))
  (segment (start 181 120.925) (end 181.95 119.975) (width 0.109) (layer "In2.Cu") (net 23))
  (segment (start 175.8 122.375) (end 175.8 121.025) (width 0.109) (layer "In2.Cu") (net 23))
  (segment (start 172.950002 119.1) (end 174.1 119.1) (width 0.109) (layer "In2.Cu") (net 23))
  (segment (start 174.925 128.775) (end 174.925 123.25) (width 0.109) (layer "In2.Cu") (net 23))
  (segment (start 172.65 138.7) (end 172.65 136.715) (width 0.109) (layer "In2.Cu") (net 23))
  (segment (start 174.1 119.1) (end 175.15 120.15) (width 0.109) (layer "In2.Cu") (net 23))
  (segment (start 171.13317 130.105976) (end 173.594024 130.105976) (width 0.109) (layer "In2.Cu") (net 23))
  (segment (start 175.15 120.15) (end 175.15 120.575) (width 0.109) (layer "In2.Cu") (net 23))
  (segment (start 172.65 136.715) (end 169.615296 133.680296) (width 0.109) (layer "In2.Cu") (net 23))
  (segment (start 169.615296 133.680296) (end 169.615296 131.942048) (width 0.109) (layer "In2.Cu") (net 23))
  (segment (start 169.615296 131.942048) (end 169.615296 131.62385) (width 0.109) (layer "In2.Cu") (net 23))
  (segment (start 173.594024 130.105976) (end 174.925 128.775) (width 0.109) (layer "In2.Cu") (net 23))
  (segment (start 174.925 123.25) (end 175.8 122.375) (width 0.109) (layer "In2.Cu") (net 23))
  (segment (start 169.615296 131.62385) (end 171.13317 130.105976) (width 0.109) (layer "In2.Cu") (net 23))
  (segment (start 116.05 128.5) (end 120.09049 132.54049) (width 0.109) (layer "In4.Cu") (net 23))
  (segment (start 120.09049 132.54049) (end 122.75 132.54049) (width 0.109) (layer "In4.Cu") (net 23))
  (segment (start 184.800006 133.481802) (end 184.800006 133.8) (width 0.182) (layer "F.Cu") (net 24))
  (segment (start 176.3 133) (end 175.7 133.6) (width 0.182) (layer "F.Cu") (net 24))
  (segment (start 153.16 139.66) (end 147.06 133.56) (width 0.182) (layer "F.Cu") (net 24))
  (segment (start 123.85 132.88) (end 123.85 132.54049) (width 0.182) (layer "F.Cu") (net 24))
  (segment (start 185.381808 132.9) (end 184.800006 133.481802) (width 0.182) (layer "F.Cu") (net 24))
  (segment (start 173.01 138.28) (end 172.27 138.28) (width 0.182) (layer "F.Cu") (net 24))
  (segment (start 176.7 133) (end 176.3 133) (width 0.182) (layer "F.Cu") (net 24))
  (segment (start 147.06 133.56) (end 124.53 133.56) (width 0.182) (layer "F.Cu") (net 24))
  (segment (start 185.8 132.9) (end 185.381808 132.9) (width 0.182) (layer "F.Cu") (net 24))
  (segment (start 116.81649 127.5) (end 117.06081 127.74432) (width 0.182) (layer "F.Cu") (net 24))
  (segment (start 172.27 138.28) (end 171.95 138.6) (width 0.182) (layer "F.Cu") (net 24))
  (segment (start 171.95 138.6) (end 171.95 139.075) (width 0.182) (layer "F.Cu") (net 24))
  (segment (start 171.95 139.075) (end 171.365 139.66) (width 0.182) (layer "F.Cu") (net 24))
  (segment (start 97.83 127.5) (end 116.81649 127.5) (width 0.182) (layer "F.Cu") (net 24))
  (segment (start 94.619 124.289) (end 93.3265 124.289) (width 0.182) (layer "F.Cu") (net 24))
  (segment (start 94.619 124.289) (end 97.83 127.5) (width 0.182) (layer "F.Cu") (net 24))
  (segment (start 173.4 138.67) (end 173.01 138.28) (width 0.182) (layer "F.Cu") (net 24))
  (segment (start 124.53 133.56) (end 123.85 132.88) (width 0.182) (layer "F.Cu") (net 24))
  (segment (start 171.365 139.66) (end 153.16 139.66) (width 0.182) (layer "F.Cu") (net 24))
  (via (at 184.800006 133.8) (size 0.45) (drill 0.1) (layers "F.Cu" "B.Cu") (net 24))
  (via (at 175.7 133.6) (size 0.45) (drill 0.1) (layers "F.Cu" "B.Cu") (net 24))
  (via (at 117.06081 127.74432) (size 0.45) (drill 0.1) (layers "F.Cu" "B.Cu") (net 24))
  (via (at 173.4 138.67) (size 0.45) (drill 0.1) (layers "F.Cu" "B.Cu") (net 24))
  (via (at 123.85 132.54049) (size 0.45) (drill 0.1) (layers "F.Cu" "B.Cu") (net 24))
  (segment (start 175.7 133.6) (end 180.3 133.6) (width 0.109) (layer "In2.Cu") (net 24))
  (segment (start 183.36 132.8) (end 184.36 133.8) (width 0.109) (layer "In2.Cu") (net 24))
  (segment (start 180.3 133.6) (end 181.1 132.8) (width 0.109) (layer "In2.Cu") (net 24))
  (segment (start 175.45 133.85) (end 175.45 136.85) (width 0.109) (layer "In2.Cu") (net 24))
  (segment (start 175.7 133.6) (end 175.45 133.85) (width 0.109) (layer "In2.Cu") (net 24))
  (segment (start 181.1 132.8) (end 183.36 132.8) (width 0.109) (layer "In2.Cu") (net 24))
  (segment (start 175.45 136.85) (end 174.59 137.71) (width 0.109) (layer "In2.Cu") (net 24))
  (segment (start 184.36 133.8) (end 184.800006 133.8) (width 0.109) (layer "In2.Cu") (net 24))
  (segment (start 173.4 138.2) (end 173.4 138.67) (width 0.109) (layer "In2.Cu") (net 24))
  (segment (start 173.89 137.71) (end 173.4 138.2) (width 0.109) (layer "In2.Cu") (net 24))
  (segment (start 174.59 137.71) (end 173.89 137.71) (width 0.109) (layer "In2.Cu") (net 24))
  (segment (start 117.06081 128.71081) (end 120.2 131.85) (width 0.109) (layer "In4.Cu") (net 24))
  (segment (start 117.06081 127.74432) (end 117.06081 128.71081) (width 0.109) (layer "In4.Cu") (net 24))
  (segment (start 120.2 131.85) (end 123.15951 131.85) (width 0.109) (layer "In4.Cu") (net 24))
  (segment (start 123.15951 131.85) (end 123.85 132.54049) (width 0.109) (layer "In4.Cu") (net 24))
  (segment (start 147.601857 94.549436) (end 147.762206 94.389087) (width 0.182) (layer "F.Cu") (net 25))
  (segment (start 147.762206 92.867794) (end 148.09591 92.53409) (width 0.182) (layer "F.Cu") (net 25))
  (segment (start 89.4415 111.899) (end 89.8265 111.589) (width 0.182) (layer "F.Cu") (net 25))
  (segment (start 147.762206 94.389087) (end 147.762206 92.867794) (width 0.182) (layer "F.Cu") (net 25))
  (segment (start 148.09591 92.53409) (end 148.09591 92.114036) (width 0.182) (layer "F.Cu") (net 25))
  (segment (start 147.6 94.91) (end 147.601857 94.549436) (width 0.182) (layer "F.Cu") (net 25))
  (via (at 147.6 94.91) (size 0.45) (drill 0.1) (layers "F.Cu" "B.Cu") (net 25))
  (via (at 89.4415 111.899) (size 0.45) (drill 0.1) (layers "F.Cu" "B.Cu") (net 25))
  (segment (start 129.15529 108.090351) (end 129.177478 108.15376) (width 0.109) (layer "In4.Cu") (net 25))
  (segment (start 128.285 109.529484) (end 128.351756 109.521962) (width 0.109) (layer "In4.Cu") (net 25))
  (segment (start 129.485 109.529484) (end 129.551756 109.521962) (width 0.109) (layer "In4.Cu") (net 25))
  (segment (start 128.351756 109.521962) (end 128.415165 109.499774) (width 0.109) (layer "In4.Cu") (net 25))
  (segment (start 127.919549 108.837953) (end 127.95529 108.894834) (width 0.109) (layer "In4.Cu") (net 25))
  (segment (start 129.785 109.229484) (end 129.785 109.025) (width 0.109) (layer "In4.Cu") (net 25))
  (segment (start 129.354834 109.499774) (end 129.418243 109.521962) (width 0.109) (layer "In4.Cu") (net 25))
  (segment (start 129.192521 109.29624) (end 129.214709 109.359649) (width 0.109) (layer "In4.Cu") (net 25))
  (segment (start 128.472046 109.464033) (end 128.519549 109.41653) (width 0.109) (layer "In4.Cu") (net 25))
  (segment (start 128.818243 107.928038) (end 128.885 107.920516) (width 0.109) (layer "In4.Cu") (net 25))
  (segment (start 148.05 95.362328) (end 147.6 94.91) (width 0.109) (layer "In4.Cu") (net 25))
  (segment (start 129.015165 107.950226) (end 129.072046 107.985967) (width 0.109) (layer "In4.Cu") (net 25))
  (segment (start 129.814709 108.894834) (end 129.85045 108.837953) (width 0.109) (layer "In4.Cu") (net 25))
  (segment (start 129.785 109.025) (end 129.792521 108.958243) (width 0.109) (layer "In4.Cu") (net 25))
  (segment (start 129.75529 109.359649) (end 129.777478 109.29624) (width 0.109) (layer "In4.Cu") (net 25))
  (segment (start 129.072046 107.985967) (end 129.119549 108.03347) (width 0.109) (layer "In4.Cu") (net 25))
  (segment (start 128.951756 107.928038) (end 129.015165 107.950226) (width 0.109) (layer "In4.Cu") (net 25))
  (segment (start 129.297953 109.464033) (end 129.354834 109.499774) (width 0.109) (layer "In4.Cu") (net 25))
  (segment (start 127.985 109.229484) (end 127.992521 109.29624) (width 0.109) (layer "In4.Cu") (net 25))
  (segment (start 128.65045 108.03347) (end 128.697953 107.985967) (width 0.109) (layer "In4.Cu") (net 25))
  (segment (start 129.214709 109.359649) (end 129.25045 109.41653) (width 0.109) (layer "In4.Cu") (net 25))
  (segment (start 130.018243 108.732521) (end 130.085 108.725) (width 0.109) (layer "In4.Cu") (net 25))
  (segment (start 89.4415 112.3165) (end 89.7 112.575) (width 0.109) (layer "In4.Cu") (net 25))
  (segment (start 128.697953 107.985967) (end 128.754834 107.950226) (width 0.109) (layer "In4.Cu") (net 25))
  (segment (start 129.897953 108.79045) (end 129.954834 108.754709) (width 0.109) (layer "In4.Cu") (net 25))
  (segment (start 129.25045 109.41653) (end 129.297953 109.464033) (width 0.109) (layer "In4.Cu") (net 25))
  (segment (start 129.185 109.229484) (end 129.192521 109.29624) (width 0.109) (layer "In4.Cu") (net 25))
  (segment (start 130.085 108.725) (end 139.15 108.725) (width 0.109) (layer "In4.Cu") (net 25))
  (segment (start 129.777478 109.29624) (end 129.785 109.229484) (width 0.109) (layer "In4.Cu") (net 25))
  (segment (start 127.685 108.725) (end 127.751756 108.732521) (width 0.109) (layer "In4.Cu") (net 25))
  (segment (start 129.719549 109.41653) (end 129.75529 109.359649) (width 0.109) (layer "In4.Cu") (net 25))
  (segment (start 128.415165 109.499774) (end 128.472046 109.464033) (width 0.109) (layer "In4.Cu") (net 25))
  (segment (start 121.85 114.025) (end 127.15 108.725) (width 0.109) (layer "In4.Cu") (net 25))
  (segment (start 127.992521 109.29624) (end 128.014709 109.359649) (width 0.109) (layer "In4.Cu") (net 25))
  (segment (start 128.585 109.229484) (end 128.585 108.220516) (width 0.109) (layer "In4.Cu") (net 25))
  (segment (start 128.754834 107.950226) (end 128.818243 107.928038) (width 0.109) (layer "In4.Cu") (net 25))
  (segment (start 128.05045 109.41653) (end 128.097953 109.464033) (width 0.109) (layer "In4.Cu") (net 25))
  (segment (start 128.885 107.920516) (end 128.951756 107.928038) (width 0.109) (layer "In4.Cu") (net 25))
  (segment (start 128.097953 109.464033) (end 128.154834 109.499774) (width 0.109) (layer "In4.Cu") (net 25))
  (segment (start 128.585 108.220516) (end 128.592521 108.15376) (width 0.109) (layer "In4.Cu") (net 25))
  (segment (start 127.985 109.025) (end 127.985 109.229484) (width 0.109) (layer "In4.Cu") (net 25))
  (segment (start 129.792521 108.958243) (end 129.814709 108.894834) (width 0.109) (layer "In4.Cu") (net 25))
  (segment (start 127.15 108.725) (end 127.685 108.725) (width 0.109) (layer "In4.Cu") (net 25))
  (segment (start 129.551756 109.521962) (end 129.615165 109.499774) (width 0.109) (layer "In4.Cu") (net 25))
  (segment (start 129.418243 109.521962) (end 129.485 109.529484) (width 0.109) (layer "In4.Cu") (net 25))
  (segment (start 129.615165 109.499774) (end 129.672046 109.464033) (width 0.109) (layer "In4.Cu") (net 25))
  (segment (start 128.218243 109.521962) (end 128.285 109.529484) (width 0.109) (layer "In4.Cu") (net 25))
  (segment (start 129.177478 108.15376) (end 129.185 108.220516) (width 0.109) (layer "In4.Cu") (net 25))
  (segment (start 128.55529 109.359649) (end 128.577478 109.29624) (width 0.109) (layer "In4.Cu") (net 25))
  (segment (start 129.85045 108.837953) (end 129.897953 108.79045) (width 0.109) (layer "In4.Cu") (net 25))
  (segment (start 129.185 108.220516) (end 129.185 109.229484) (width 0.109) (layer "In4.Cu") (net 25))
  (segment (start 89.7 112.575) (end 95.525 112.575) (width 0.109) (layer "In4.Cu") (net 25))
  (segment (start 127.977478 108.958243) (end 127.985 109.025) (width 0.109) (layer "In4.Cu") (net 25))
  (segment (start 127.751756 108.732521) (end 127.815165 108.754709) (width 0.109) (layer "In4.Cu") (net 25))
  (segment (start 148.05 99.825) (end 148.05 95.362328) (width 0.109) (layer "In4.Cu") (net 25))
  (segment (start 128.592521 108.15376) (end 128.614709 108.090351) (width 0.109) (layer "In4.Cu") (net 25))
  (segment (start 89.4415 111.899) (end 89.4415 112.3165) (width 0.109) (layer "In4.Cu") (net 25))
  (segment (start 127.815165 108.754709) (end 127.872046 108.79045) (width 0.109) (layer "In4.Cu") (net 25))
  (segment (start 129.954834 108.754709) (end 130.018243 108.732521) (width 0.109) (layer "In4.Cu") (net 25))
  (segment (start 95.525 112.575) (end 96.975 114.025) (width 0.109) (layer "In4.Cu") (net 25))
  (segment (start 129.119549 108.03347) (end 129.15529 108.090351) (width 0.109) (layer "In4.Cu") (net 25))
  (segment (start 128.577478 109.29624) (end 128.585 109.229484) (width 0.109) (layer "In4.Cu") (net 25))
  (segment (start 127.872046 108.79045) (end 127.919549 108.837953) (width 0.109) (layer "In4.Cu") (net 25))
  (segment (start 139.15 108.725) (end 148.05 99.825) (width 0.109) (layer "In4.Cu") (net 25))
  (segment (start 128.519549 109.41653) (end 128.55529 109.359649) (width 0.109) (layer "In4.Cu") (net 25))
  (segment (start 127.95529 108.894834) (end 127.977478 108.958243) (width 0.109) (layer "In4.Cu") (net 25))
  (segment (start 129.672046 109.464033) (end 129.719549 109.41653) (width 0.109) (layer "In4.Cu") (net 25))
  (segment (start 128.014709 109.359649) (end 128.05045 109.41653) (width 0.109) (layer "In4.Cu") (net 25))
  (segment (start 96.975 114.025) (end 121.85 114.025) (width 0.109) (layer "In4.Cu") (net 25))
  (segment (start 128.614709 108.090351) (end 128.65045 108.03347) (width 0.109) (layer "In4.Cu") (net 25))
  (segment (start 128.154834 109.499774) (end 128.218243 109.521962) (width 0.109) (layer "In4.Cu") (net 25))
  (segment (start 151.3 93.9) (end 151.3 93.6) (width 0.182) (layer "F.Cu") (net 26))
  (segment (start 151.2225 93.0475) (end 151.3 92.97) (width 0.182) (layer "F.Cu") (net 26))
  (segment (start 151.225 93.525) (end 151.075 93.525) (width 0.182) (layer "F.Cu") (net 26))
  (segment (start 93.3265 110.319) (end 93.7115 110.009) (width 0.182) (layer "F.Cu") (net 26))
  (segment (start 151 93.45) (end 151 93.125) (width 0.182) (layer "F.Cu") (net 26))
  (segment (start 151.0775 93.0475) (end 151.2225 93.0475) (width 0.182) (layer "F.Cu") (net 26))
  (segment (start 151.3 93.6) (end 151.225 93.525) (width 0.182) (layer "F.Cu") (net 26))
  (segment (start 151.3 92.97) (end 151.3 92.75) (width 0.182) (layer "F.Cu") (net 26))
  (segment (start 151.115499 94.373269) (end 151.115499 94.084501) (width 0.182) (layer "F.Cu") (net 26))
  (segment (start 151.115499 94.084501) (end 151.3 93.9) (width 0.182) (layer "F.Cu") (net 26))
  (segment (start 151 93.125) (end 151.0775 93.0475) (width 0.182) (layer "F.Cu") (net 26))
  (segment (start 151.095912 92.545912) (end 151.095912 92.114036) (width 0.182) (layer "F.Cu") (net 26))
  (segment (start 151.075 93.525) (end 151 93.45) (width 0.182) (layer "F.Cu") (net 26))
  (segment (start 151.3 92.75) (end 151.095912 92.545912) (width 0.182) (layer "F.Cu") (net 26))
  (via (at 93.7115 110.009) (size 0.45) (drill 0.1) (layers "F.Cu" "B.Cu") (net 26))
  (via (at 151.115499 94.373269) (size 0.45) (drill 0.1) (layers "F.Cu" "B.Cu") (net 26))
  (segment (start 136.258815 105.01901) (end 136.243867 104.953516) (width 0.109) (layer "In2.Cu") (net 26))
  (segment (start 138.026903 103.435003) (end 137.985017 103.382482) (width 0.109) (layer "In2.Cu") (net 26))
  (segment (start 136.8644 106.355396) (end 136.929894 106.340448) (width 0.109) (layer "In2.Cu") (net 26))
  (segment (start 150.76572 95.34572) (end 150.76572 94.723048) (width 0.109) (layer "In2.Cu") (net 26))
  (segment (start 139.358127 102.976611) (end 139.358127 102.909432) (width 0.109) (layer "In2.Cu") (net 26))
  (segment (start 136.382372 104.665908) (end 136.442897 104.636762) (width 0.109) (layer "In2.Cu") (net 26))
  (segment (start 138.739997 104.148096) (end 138.026903 103.435003) (width 0.109) (layer "In2.Cu") (net 26))
  (segment (start 136.508392 104.621812) (end 136.57557 104.621813) (width 0.109) (layer "In2.Cu") (net 26))
  (segment (start 138.451167 103.01074) (end 139.16426 103.723834) (width 0.109) (layer "In2.Cu") (net 26))
  (segment (start 137.977451 105.242345) (end 137.977451 105.175166) (width 0.109) (layer "In2.Cu") (net 26))
  (segment (start 137.933355 105.368365) (end 137.962502 105.307839) (width 0.109) (layer "In2.Cu") (net 26))
  (segment (start 137.178376 104.28353) (end 137.13649 104.231009) (width 0.109) (layer "In2.Cu") (net 26))
  (segment (start 139.409981 103.809815) (end 139.475476 103.794867) (width 0.109) (layer "In2.Cu") (net 26))
  (segment (start 139.373075 103.042105) (end 139.358127 102.976611) (width 0.109) (layer "In2.Cu") (net 26))
  (segment (start 137.955869 103.321956) (end 137.940921 103.256462) (width 0.109) (layer "In2.Cu") (net 26))
  (segment (start 138.338119 102.939707) (end 138.398644 102.968855) (width 0.109) (layer "In2.Cu") (net 26))
  (segment (start 139.16426 103.723834) (end 139.216782 103.765719) (width 0.109) (layer "In2.Cu") (net 26))
  (segment (start 138.811029 104.459312) (end 138.825978 104.393818) (width 0.109) (layer "In2.Cu") (net 26))
  (segment (start 137.084828 106.216892) (end 137.113975 106.156366) (width 0.109) (layer "In2.Cu") (net 26))
  (segment (start 138.079426 102.968854) (end 138.139951 102.939708) (width 0.109) (layer "In2.Cu") (net 26))
  (segment (start 94.051 110.009) (end 94.31 109.75) (width 0.109) (layer "In2.Cu") (net 26))
  (segment (start 140.05 102.125) (end 145.9625 102.125) (width 0.109) (layer "In2.Cu") (net 26))
  (segment (start 136.287963 105.079536) (end 136.258815 105.01901) (width 0.109) (layer "In2.Cu") (net 26))
  (segment (start 139.588524 103.723834) (end 139.630409 103.671311) (width 0.109) (layer "In2.Cu") (net 26))
  (segment (start 137.933355 105.049146) (end 137.89147 104.996623) (width 0.109) (layer "In2.Cu") (net 26))
  (segment (start 136.258815 104.820842) (end 136.287964 104.760316) (width 0.109) (layer "In2.Cu") (net 26))
  (segment (start 136.671201 106.3113) (end 136.731727 106.340448) (width 0.109) (layer "In2.Cu") (net 26))
  (segment (start 137.940922 103.189282) (end 137.955869 103.123788) (width 0.109) (layer "In2.Cu") (net 26))
  (segment (start 137.424097 103.773286) (end 137.489592 103.788234) (width 0.109) (layer "In2.Cu") (net 26))
  (segment (start 137.985017 103.382482) (end 137.955869 103.321956) (width 0.109) (layer "In2.Cu") (net 26))
  (segment (start 138.315733 104.572361) (end 138.368255 104.614246) (width 0.109) (layer "In2.Cu") (net 26))
  (segment (start 137.092395 104.037809) (end 137.107342 103.972315) (width 0.109) (layer "In2.Cu") (net 26))
  (segment (start 150.86 95.44) (end 150.76572 95.34572) (width 0.109) (layer "In2.Cu") (net 26))
  (segment (start 136.99042 106.3113) (end 137.042943 106.269415) (width 0.109) (layer "In2.Cu") (net 26))
  (segment (start 94.31 109.75) (end 122.825 109.75) (width 0.109) (layer "In2.Cu") (net 26))
  (segment (start 138.781882 104.519838) (end 138.811029 104.459312) (width 0.109) (layer "In2.Cu") (net 26))
  (segment (start 139.277308 103.794867) (end 139.342802 103.809815) (width 0.109) (layer "In2.Cu") (net 26))
  (segment (start 138.368255 104.614246) (end 138.428781 104.643394) (width 0.109) (layer "In2.Cu") (net 26))
  (segment (start 138.825978 104.326639) (end 138.811029 104.261145) (width 0.109) (layer "In2.Cu") (net 26))
  (segment (start 138.272624 102.924759) (end 138.338119 102.939707) (width 0.109) (layer "In2.Cu") (net 26))
  (segment (start 137.178376 103.859266) (end 137.230899 103.817381) (width 0.109) (layer "In2.Cu") (net 26))
  (segment (start 138.811029 104.261145) (end 138.781882 104.200619) (width 0.109) (layer "In2.Cu") (net 26))
  (segment (start 136.05 106.125) (end 136.102522 106.083114) (width 0.109) (layer "In2.Cu") (net 26))
  (segment (start 136.57557 104.621813) (end 136.641065 104.636761) (width 0.109) (layer "In2.Cu") (net 26))
  (segment (start 93.7115 110.009) (end 94.051 110.009) (width 0.109) (layer "In2.Cu") (net 26))
  (segment (start 138.428781 104.643394) (end 138.494275 104.658342) (width 0.109) (layer "In2.Cu") (net 26))
  (segment (start 137.985018 103.063262) (end 138.026903 103.010739) (width 0.109) (layer "In2.Cu") (net 26))
  (segment (start 137.977451 105.175166) (end 137.962502 105.109672) (width 0.109) (layer "In2.Cu") (net 26))
  (segment (start 139.674505 103.545291) (end 139.674505 103.478112) (width 0.109) (layer "In2.Cu") (net 26))
  (segment (start 139.630409 103.671311) (end 139.659556 103.610785) (width 0.109) (layer "In2.Cu") (net 26))
  (segment (start 137.113975 106.156366) (end 137.128924 106.090872) (width 0.109) (layer "In2.Cu") (net 26))
  (segment (start 150.76572 94.723048) (end 151.115499 94.373269) (width 0.109) (layer "In2.Cu") (net 26))
  (segment (start 136.243867 104.953516) (end 136.243868 104.886336) (width 0.109) (layer "In2.Cu") (net 26))
  (segment (start 137.519728 105.462773) (end 137.580254 105.491921) (width 0.109) (layer "In2.Cu") (net 26))
  (segment (start 136.102522 106.083114) (end 136.163048 106.053967) (width 0.109) (layer "In2.Cu") (net 26))
  (segment (start 138.626949 104.643394) (end 138.687474 104.614246) (width 0.109) (layer "In2.Cu") (net 26))
  (segment (start 137.60264 103.859267) (end 138.315733 104.572361) (width 0.109) (layer "In2.Cu") (net 26))
  (segment (start 139.342802 103.809815) (end 139.409981 103.809815) (width 0.109) (layer "In2.Cu") (net 26))
  (segment (start 136.797221 106.355396) (end 136.8644 106.355396) (width 0.109) (layer "In2.Cu") (net 26))
  (segment (start 136.361215 106.053967) (end 136.421741 106.083114) (width 0.109) (layer "In2.Cu") (net 26))
  (segment (start 137.962502 105.109672) (end 137.933355 105.049146) (width 0.109) (layer "In2.Cu") (net 26))
  (segment (start 139.402223 102.783412) (end 139.444108 102.730889) (width 0.109) (layer "In2.Cu") (net 26))
  (segment (start 137.778422 105.491921) (end 137.838947 105.462773) (width 0.109) (layer "In2.Cu") (net 26))
  (segment (start 137.645748 105.506869) (end 137.712927 105.506869) (width 0.109) (layer "In2.Cu") (net 26))
  (segment (start 138.205446 102.924758) (end 138.272624 102.924759) (width 0.109) (layer "In2.Cu") (net 26))
  (segment (start 136.421741 106.083114) (end 136.474264 106.125) (width 0.109) (layer "In2.Cu") (net 26))
  (segment (start 136.641065 104.636761) (end 136.70159 104.665909) (width 0.109) (layer "In2.Cu") (net 26))
  (segment (start 139.216782 103.765719) (end 139.277308 103.794867) (width 0.109) (layer "In2.Cu") (net 26))
  (segment (start 137.955869 103.123788) (end 137.985018 103.063262) (width 0.109) (layer "In2.Cu") (net 26))
  (segment (start 137.580254 105.491921) (end 137.645748 105.506869) (width 0.109) (layer "In2.Cu") (net 26))
  (segment (start 136.754113 104.707794) (end 137.467206 105.420888) (width 0.109) (layer "In2.Cu") (net 26))
  (segment (start 137.042943 106.269415) (end 137.084828 106.216892) (width 0.109) (layer "In2.Cu") (net 26))
  (segment (start 137.940921 103.256462) (end 137.940922 103.189282) (width 0.109) (layer "In2.Cu") (net 26))
  (segment (start 136.618679 106.269415) (end 136.671201 106.3113) (width 0.109) (layer "In2.Cu") (net 26))
  (segment (start 137.489592 103.788234) (end 137.550117 103.817382) (width 0.109) (layer "In2.Cu") (net 26))
  (segment (start 136.287964 104.760316) (end 136.329849 104.707793) (width 0.109) (layer "In2.Cu") (net 26))
  (segment (start 137.13649 104.231009) (end 137.107342 104.170483) (width 0.109) (layer "In2.Cu") (net 26))
  (segment (start 139.536001 103.765719) (end 139.588524 103.723834) (width 0.109) (layer "In2.Cu") (net 26))
  (segment (start 139.674505 103.478112) (end 139.659556 103.412618) (width 0.109) (layer "In2.Cu") (net 26))
  (segment (start 137.113975 105.958199) (end 137.084828 105.897673) (width 0.109) (layer "In2.Cu") (net 26))
  (segment (start 137.467206 105.420888) (end 137.519728 105.462773) (width 0.109) (layer "In2.Cu") (net 26))
  (segment (start 138.781882 104.200619) (end 138.739997 104.148096) (width 0.109) (layer "In2.Cu") (net 26))
  (segment (start 139.588524 103.299569) (end 139.444108 103.155153) (width 0.109) (layer "In2.Cu") (net 26))
  (segment (start 136.474264 106.125) (end 136.618679 106.269415) (width 0.109) (layer "In2.Cu") (net 26))
  (segment (start 136.228542 106.039018) (end 136.295721 106.039018) (width 0.109) (layer "In2.Cu") (net 26))
  (segment (start 136.295721 106.039018) (end 136.361215 106.053967) (width 0.109) (layer "In2.Cu") (net 26))
  (segment (start 137.356919 103.773285) (end 137.424097 103.773286) (width 0.109) (layer "In2.Cu") (net 26))
  (segment (start 137.092394 104.104989) (end 137.092395 104.037809) (width 0.109) (layer "In2.Cu") (net 26))
  (segment (start 136.731727 106.340448) (end 136.797221 106.355396) (width 0.109) (layer "In2.Cu") (net 26))
  (segment (start 137.89147 105.420888) (end 137.933355 105.368365) (width 0.109) (layer "In2.Cu") (net 26))
  (segment (start 126.45 106.125) (end 136.05 106.125) (width 0.109) (layer "In2.Cu") (net 26))
  (segment (start 136.163048 106.053967) (end 136.228542 106.039018) (width 0.109) (layer "In2.Cu") (net 26))
  (segment (start 139.475476 103.794867) (end 139.536001 103.765719) (width 0.109) (layer "In2.Cu") (net 26))
  (segment (start 136.442897 104.636762) (end 136.508392 104.621812) (width 0.109) (layer "In2.Cu") (net 26))
  (segment (start 137.550117 103.817382) (end 137.60264 103.859267) (width 0.109) (layer "In2.Cu") (net 26))
  (segment (start 137.136491 103.911789) (end 137.178376 103.859266) (width 0.109) (layer "In2.Cu") (net 26))
  (segment (start 139.373075 102.843938) (end 139.402223 102.783412) (width 0.109) (layer "In2.Cu") (net 26))
  (segment (start 137.042943 105.84515) (end 136.329849 105.132057) (width 0.109) (layer "In2.Cu") (net 26))
  (segment (start 137.084828 105.897673) (end 137.042943 105.84515) (width 0.109) (layer "In2.Cu") (net 26))
  (segment (start 136.70159 104.665909) (end 136.754113 104.707794) (width 0.109) (layer "In2.Cu") (net 26))
  (segment (start 137.89147 104.996623) (end 137.178376 104.28353) (width 0.109) (layer "In2.Cu") (net 26))
  (segment (start 138.398644 102.968855) (end 138.451167 103.01074) (width 0.109) (layer "In2.Cu") (net 26))
  (segment (start 137.107342 103.972315) (end 137.136491 103.911789) (width 0.109) (layer "In2.Cu") (net 26))
  (segment (start 139.659556 103.610785) (end 139.674505 103.545291) (width 0.109) (layer "In2.Cu") (net 26))
  (segment (start 150.86 97.2275) (end 150.86 95.44) (width 0.109) (layer "In2.Cu") (net 26))
  (segment (start 137.128924 106.090872) (end 137.128924 106.023693) (width 0.109) (layer "In2.Cu") (net 26))
  (segment (start 136.329849 105.132057) (end 136.287963 105.079536) (width 0.109) (layer "In2.Cu") (net 26))
  (segment (start 138.739997 104.572361) (end 138.781882 104.519838) (width 0.109) (layer "In2.Cu") (net 26))
  (segment (start 139.630409 103.352092) (end 139.588524 103.299569) (width 0.109) (layer "In2.Cu") (net 26))
  (segment (start 139.358127 102.909432) (end 139.373075 102.843938) (width 0.109) (layer "In2.Cu") (net 26))
  (segment (start 139.444108 103.155153) (end 139.402223 103.102631) (width 0.109) (layer "In2.Cu") (net 26))
  (segment (start 137.712927 105.506869) (end 137.778422 105.491921) (width 0.109) (layer "In2.Cu") (net 26))
  (segment (start 137.291424 103.788235) (end 137.356919 103.773285) (width 0.109) (layer "In2.Cu") (net 26))
  (segment (start 137.230899 103.817381) (end 137.291424 103.788235) (width 0.109) (layer "In2.Cu") (net 26))
  (segment (start 136.929894 106.340448) (end 136.99042 106.3113) (width 0.109) (layer "In2.Cu") (net 26))
  (segment (start 139.659556 103.412618) (end 139.630409 103.352092) (width 0.109) (layer "In2.Cu") (net 26))
  (segment (start 136.329849 104.707793) (end 136.382372 104.665908) (width 0.109) (layer "In2.Cu") (net 26))
  (segment (start 138.139951 102.939708) (end 138.205446 102.924758) (width 0.109) (layer "In2.Cu") (net 26))
  (segment (start 122.825 109.75) (end 126.45 106.125) (width 0.109) (layer "In2.Cu") (net 26))
  (segment (start 137.128924 106.023693) (end 137.113975 105.958199) (width 0.109) (layer "In2.Cu") (net 26))
  (segment (start 137.962502 105.307839) (end 137.977451 105.242345) (width 0.109) (layer "In2.Cu") (net 26))
  (segment (start 137.838947 105.462773) (end 137.89147 105.420888) (width 0.109) (layer "In2.Cu") (net 26))
  (segment (start 138.561454 104.658342) (end 138.626949 104.643394) (width 0.109) (layer "In2.Cu") (net 26))
  (segment (start 138.494275 104.658342) (end 138.561454 104.658342) (width 0.109) (layer "In2.Cu") (net 26))
  (segment (start 138.026903 103.010739) (end 138.079426 102.968854) (width 0.109) (layer "In2.Cu") (net 26))
  (segment (start 138.687474 104.614246) (end 138.739997 104.572361) (width 0.109) (layer "In2.Cu") (net 26))
  (segment (start 138.825978 104.393818) (end 138.825978 104.326639) (width 0.109) (layer "In2.Cu") (net 26))
  (segment (start 137.107342 104.170483) (end 137.092394 104.104989) (width 0.109) (layer "In2.Cu") (net 26))
  (segment (start 145.9625 102.125) (end 150.86 97.2275) (width 0.109) (layer "In2.Cu") (net 26))
  (segment (start 136.243868 104.886336) (end 136.258815 104.820842) (width 0.109) (layer "In2.Cu") (net 26))
  (segment (start 139.402223 103.102631) (end 139.373075 103.042105) (width 0.109) (layer "In2.Cu") (net 26))
  (segment (start 139.444108 102.730889) (end 140.05 102.125) (width 0.109) (layer "In2.Cu") (net 26))
  (segment (start 151.595911 92.114036) (end 151.595911 94.799235) (width 0.182) (layer "F.Cu") (net 27))
  (segment (start 151.595911 94.799235) (end 151.463428 94.931718) (width 0.182) (layer "F.Cu") (net 27))
  (segment (start 151.463428 94.931718) (end 151.14523 94.931718) (width 0.182) (layer "F.Cu") (net 27))
  (segment (start 93.3265 109.684) (end 93.7115 109.373999) (width 0.182) (layer "F.Cu") (net 27))
  (via (at 93.7115 109.373999) (size 0.45) (drill 0.1) (layers "F.Cu" "B.Cu") (net 27))
  (via (at 151.14523 94.931718) (size 0.45) (drill 0.1) (layers "F.Cu" "B.Cu") (net 27))
  (segment (start 130.166894 107.534614) (end 130.187233 107.592739) (width 0.109) (layer "In2.Cu") (net 27))
  (segment (start 130.716894 106.715386) (end 130.737233 106.657261) (width 0.109) (layer "In2.Cu") (net 27))
  (segment (start 133.56354 107.688424) (end 133.615681 107.721187) (width 0.109) (layer "In2.Cu") (net 27))
  (segment (start 134.016894 107.338806) (end 134.037233 107.280681) (width 0.109) (layer "In2.Cu") (net 27))
  (segment (start 130.865681 106.528813) (end 130.923806 106.508474) (width 0.109) (layer "In2.Cu") (net 27))
  (segment (start 132.573806 107.741526) (end 132.635 107.748421) (width 0.109) (layer "In2.Cu") (net 27))
  (segment (start 132.256459 106.561576) (end 132.300003 106.60512) (width 0.109) (layer "In2.Cu") (net 27))
  (segment (start 132.300003 106.60512) (end 132.332766 106.657261) (width 0.109) (layer "In2.Cu") (net 27))
  (segment (start 95.15 110.39) (end 95.33 110.57) (width 0.109) (layer "In2.Cu") (net 27))
  (segment (start 131.706459 107.688424) (end 131.750003 107.64488) (width 0.109) (layer "In2.Cu") (net 27))
  (segment (start 130.16 107.4) (end 130.16 107.473421) (width 0.109) (layer "In2.Cu") (net 27))
  (segment (start 130.219996 107.64488) (end 130.26354 107.688424) (width 0.109) (layer "In2.Cu") (net 27))
  (segment (start 130.769996 106.60512) (end 130.81354 106.561576) (width 0.109) (layer "In2.Cu") (net 27))
  (segment (start 132.46354 107.688424) (end 132.515681 107.721187) (width 0.109) (layer "In2.Cu") (net 27))
  (segment (start 132.36 107.473421) (end 132.366894 107.534614) (width 0.109) (layer "In2.Cu") (net 27))
  (segment (start 131.26 106.776579) (end 131.26 107.473421) (width 0.109) (layer "In2.Cu") (net 27))
  (segment (start 131.782766 107.592739) (end 131.803105 107.534614) (width 0.109) (layer "In2.Cu") (net 27))
  (segment (start 93.3 109.785499) (end 93.3 110.25) (width 0.109) (layer "In2.Cu") (net 27))
  (segment (start 131.596193 107.741526) (end 131.654318 107.721187) (width 0.109) (layer "In2.Cu") (net 27))
  (segment (start 130.923806 106.508474) (end 130.985 106.501579) (width 0.109) (layer "In2.Cu") (net 27))
  (segment (start 137.05728 107.125) (end 141.08228 103.1) (width 0.109) (layer "In2.Cu") (net 27))
  (segment (start 132.204318 106.528813) (end 132.256459 106.561576) (width 0.109) (layer "In2.Cu") (net 27))
  (segment (start 141.08228 103.1) (end 146.025 103.1) (width 0.109) (layer "In2.Cu") (net 27))
  (segment (start 151.39 97.735) (end 151.39 95.176488) (width 0.109) (layer "In2.Cu") (net 27))
  (segment (start 134.285 107.125) (end 137.05728 107.125) (width 0.109) (layer "In2.Cu") (net 27))
  (segment (start 133.123806 106.508474) (end 133.185 106.501579) (width 0.109) (layer "In2.Cu") (net 27))
  (segment (start 130.373806 107.741526) (end 130.435 107.748421) (width 0.109) (layer "In2.Cu") (net 27))
  (segment (start 134.223806 107.131894) (end 134.285 107.125) (width 0.109) (layer "In2.Cu") (net 27))
  (segment (start 133.453105 106.715386) (end 133.46 106.776579) (width 0.109) (layer "In2.Cu") (net 27))
  (segment (start 130.985 106.501579) (end 131.046193 106.508474) (width 0.109) (layer "In2.Cu") (net 27))
  (segment (start 132.696193 107.741526) (end 132.754318 107.721187) (width 0.109) (layer "In2.Cu") (net 27))
  (segment (start 132.36 106.776579) (end 132.36 107.473421) (width 0.109) (layer "In2.Cu") (net 27))
  (segment (start 132.903105 107.534614) (end 132.91 107.473421) (width 0.109) (layer "In2.Cu") (net 27))
  (segment (start 131.36354 107.688424) (end 131.415681 107.721187) (width 0.109) (layer "In2.Cu") (net 27))
  (segment (start 95.33 110.57) (end 123.005 110.57) (width 0.109) (layer "In2.Cu") (net 27))
  (segment (start 123.005 110.57) (end 126.45 107.125) (width 0.109) (layer "In2.Cu") (net 27))
  (segment (start 132.91 106.776579) (end 132.916894 106.715386) (width 0.109) (layer "In2.Cu") (net 27))
  (segment (start 132.754318 107.721187) (end 132.806459 107.688424) (width 0.109) (layer "In2.Cu") (net 27))
  (segment (start 93.3 110.25) (end 93.44 110.39) (width 0.109) (layer "In2.Cu") (net 27))
  (segment (start 133.46 107.473421) (end 133.466894 107.534614) (width 0.109) (layer "In2.Cu") (net 27))
  (segment (start 131.046193 106.508474) (end 131.104318 106.528813) (width 0.109) (layer "In2.Cu") (net 27))
  (segment (start 130.132766 107.280681) (end 130.153105 107.338806) (width 0.109) (layer "In2.Cu") (net 27))
  (segment (start 130.004318 107.152233) (end 130.056459 107.184996) (width 0.109) (layer "In2.Cu") (net 27))
  (segment (start 131.816894 106.715386) (end 131.837233 106.657261) (width 0.109) (layer "In2.Cu") (net 27))
  (segment (start 131.91354 106.561576) (end 131.965681 106.528813) (width 0.109) (layer "In2.Cu") (net 27))
  (segment (start 134.01 107.4) (end 134.016894 107.338806) (width 0.109) (layer "In2.Cu") (net 27))
  (segment (start 131.319996 107.64488) (end 131.36354 107.688424) (width 0.109) (layer "In2.Cu") (net 27))
  (segment (start 131.253105 106.715386) (end 131.26 106.776579) (width 0.109) (layer "In2.Cu") (net 27))
  (segment (start 146.025 103.1) (end 151.39 97.735) (width 0.109) (layer "In2.Cu") (net 27))
  (segment (start 133.246193 106.508474) (end 133.304318 106.528813) (width 0.109) (layer "In2.Cu") (net 27))
  (segment (start 131.232766 106.657261) (end 131.253105 106.715386) (width 0.109) (layer "In2.Cu") (net 27))
  (segment (start 133.356459 106.561576) (end 133.400003 106.60512) (width 0.109) (layer "In2.Cu") (net 27))
  (segment (start 133.982766 107.592739) (end 134.003105 107.534614) (width 0.109) (layer "In2.Cu") (net 27))
  (segment (start 132.635 107.748421) (end 132.696193 107.741526) (width 0.109) (layer "In2.Cu") (net 27))
  (segment (start 133.065681 106.528813) (end 133.123806 106.508474) (width 0.109) (layer "In2.Cu") (net 27))
  (segment (start 131.415681 107.721187) (end 131.473806 107.741526) (width 0.109) (layer "In2.Cu") (net 27))
  (segment (start 131.26 107.473421) (end 131.266894 107.534614) (width 0.109) (layer "In2.Cu") (net 27))
  (segment (start 130.737233 106.657261) (end 130.769996 106.60512) (width 0.109) (layer "In2.Cu") (net 27))
  (segment (start 130.26354 107.688424) (end 130.315681 107.721187) (width 0.109) (layer "In2.Cu") (net 27))
  (segment (start 131.965681 106.528813) (end 132.023806 106.508474) (width 0.109) (layer "In2.Cu") (net 27))
  (segment (start 133.185 106.501579) (end 133.246193 106.508474) (width 0.109) (layer "In2.Cu") (net 27))
  (segment (start 131.837233 106.657261) (end 131.869996 106.60512) (width 0.109) (layer "In2.Cu") (net 27))
  (segment (start 131.803105 107.534614) (end 131.81 107.473421) (width 0.109) (layer "In2.Cu") (net 27))
  (segment (start 133.519996 107.64488) (end 133.56354 107.688424) (width 0.109) (layer "In2.Cu") (net 27))
  (segment (start 131.869996 106.60512) (end 131.91354 106.561576) (width 0.109) (layer "In2.Cu") (net 27))
  (segment (start 131.156459 106.561576) (end 131.200003 106.60512) (width 0.109) (layer "In2.Cu") (net 27))
  (segment (start 132.882766 107.592739) (end 132.903105 107.534614) (width 0.109) (layer "In2.Cu") (net 27))
  (segment (start 131.104318 106.528813) (end 131.156459 106.561576) (width 0.109) (layer "In2.Cu") (net 27))
  (segment (start 130.703105 107.534614) (end 130.71 107.473421) (width 0.109) (layer "In2.Cu") (net 27))
  (segment (start 131.81 107.473421) (end 131.81 106.776579) (width 0.109) (layer "In2.Cu") (net 27))
  (segment (start 133.46 106.776579) (end 133.46 107.473421) (width 0.109) (layer "In2.Cu") (net 27))
  (segment (start 131.473806 107.741526) (end 131.535 107.748421) (width 0.109) (layer "In2.Cu") (net 27))
  (segment (start 132.023806 106.508474) (end 132.085 106.501579) (width 0.109) (layer "In2.Cu") (net 27))
  (segment (start 132.850003 107.64488) (end 132.882766 107.592739) (width 0.109) (layer "In2.Cu") (net 27))
  (segment (start 132.353105 106.715386) (end 132.36 106.776579) (width 0.109) (layer "In2.Cu") (net 27))
  (segment (start 133.400003 106.60512) (end 133.432766 106.657261) (width 0.109) (layer "In2.Cu") (net 27))
  (segment (start 130.435 107.748421) (end 130.496193 107.741526) (width 0.109) (layer "In2.Cu") (net 27))
  (segment (start 93.7115 109.373999) (end 93.3 109.785499) (width 0.109) (layer "In2.Cu") (net 27))
  (segment (start 134.11354 107.184996) (end 134.165681 107.152233) (width 0.109) (layer "In2.Cu") (net 27))
  (segment (start 130.606459 107.688424) (end 130.650003 107.64488) (width 0.109) (layer "In2.Cu") (net 27))
  (segment (start 129.885 107.125) (end 129.946193 107.131894) (width 0.109) (layer "In2.Cu") (net 27))
  (segment (start 130.554318 107.721187) (end 130.606459 107.688424) (width 0.109) (layer "In2.Cu") (net 27))
  (segment (start 132.806459 107.688424) (end 132.850003 107.64488) (width 0.109) (layer "In2.Cu") (net 27))
  (segment (start 133.906459 107.688424) (end 133.950003 107.64488) (width 0.109) (layer "In2.Cu") (net 27))
  (segment (start 133.796193 107.741526) (end 133.854318 107.721187) (width 0.109) (layer "In2.Cu") (net 27))
  (segment (start 131.750003 107.64488) (end 131.782766 107.592739) (width 0.109) (layer "In2.Cu") (net 27))
  (segment (start 133.304318 106.528813) (end 133.356459 106.561576) (width 0.109) (layer "In2.Cu") (net 27))
  (segment (start 132.916894 106.715386) (end 132.937233 106.657261) (width 0.109) (layer "In2.Cu") (net 27))
  (segment (start 130.81354 106.561576) (end 130.865681 106.528813) (width 0.109) (layer "In2.Cu") (net 27))
  (segment (start 130.315681 107.721187) (end 130.373806 107.741526) (width 0.109) (layer "In2.Cu") (net 27))
  (segment (start 133.673806 107.741526) (end 133.735 107.748421) (width 0.109) (layer "In2.Cu") (net 27))
  (segment (start 132.515681 107.721187) (end 132.573806 107.741526) (width 0.109) (layer "In2.Cu") (net 27))
  (segment (start 134.165681 107.152233) (end 134.223806 107.131894) (width 0.109) (layer "In2.Cu") (net 27))
  (segment (start 134.003105 107.534614) (end 134.01 107.473421) (width 0.109) (layer "In2.Cu") (net 27))
  (segment (start 133.854318 107.721187) (end 133.906459 107.688424) (width 0.109) (layer "In2.Cu") (net 27))
  (segment (start 132.937233 106.657261) (end 132.969996 106.60512) (width 0.109) (layer "In2.Cu") (net 27))
  (segment (start 130.496193 107.741526) (end 130.554318 107.721187) (width 0.109) (layer "In2.Cu") (net 27))
  (segment (start 130.682766 107.592739) (end 130.703105 107.534614) (width 0.109) (layer "In2.Cu") (net 27))
  (segment (start 131.535 107.748421) (end 131.596193 107.741526) (width 0.109) (layer "In2.Cu") (net 27))
  (segment (start 130.71 107.473421) (end 130.71 106.776579) (width 0.109) (layer "In2.Cu") (net 27))
  (segment (start 133.01354 106.561576) (end 133.065681 106.528813) (width 0.109) (layer "In2.Cu") (net 27))
  (segment (start 134.069996 107.22854) (end 134.11354 107.184996) (width 0.109) (layer "In2.Cu") (net 27))
  (segment (start 130.056459 107.184996) (end 130.100003 107.22854) (width 0.109) (layer "In2.Cu") (net 27))
  (segment (start 132.419996 107.64488) (end 132.46354 107.688424) (width 0.109) (layer "In2.Cu") (net 27))
  (segment (start 130.16 107.473421) (end 130.166894 107.534614) (width 0.109) (layer "In2.Cu") (net 27))
  (segment (start 130.100003 107.22854) (end 130.132766 107.280681) (width 0.109) (layer "In2.Cu") (net 27))
  (segment (start 132.91 107.473421) (end 132.91 106.776579) (width 0.109) (layer "In2.Cu") (net 27))
  (segment (start 132.969996 106.60512) (end 133.01354 106.561576) (width 0.109) (layer "In2.Cu") (net 27))
  (segment (start 131.654318 107.721187) (end 131.706459 107.688424) (width 0.109) (layer "In2.Cu") (net 27))
  (segment (start 133.487233 107.592739) (end 133.519996 107.64488) (width 0.109) (layer "In2.Cu") (net 27))
  (segment (start 133.950003 107.64488) (end 133.982766 107.592739) (width 0.109) (layer "In2.Cu") (net 27))
  (segment (start 131.81 106.776579) (end 131.816894 106.715386) (width 0.109) (layer "In2.Cu") (net 27))
  (segment (start 126.45 107.125) (end 129.885 107.125) (width 0.109) (layer "In2.Cu") (net 27))
  (segment (start 131.266894 107.534614) (end 131.287233 107.592739) (width 0.109) (layer "In2.Cu") (net 27))
  (segment (start 133.615681 107.721187) (end 133.673806 107.741526) (width 0.109) (layer "In2.Cu") (net 27))
  (segment (start 132.332766 106.657261) (end 132.353105 106.715386) (width 0.109) (layer "In2.Cu") (net 27))
  (segment (start 129.946193 107.131894) (end 130.004318 107.152233) (width 0.109) (layer "In2.Cu") (net 27))
  (segment (start 131.287233 107.592739) (end 131.319996 107.64488) (width 0.109) (layer "In2.Cu") (net 27))
  (segment (start 93.44 110.39) (end 95.15 110.39) (width 0.109) (layer "In2.Cu") (net 27))
  (segment (start 132.085 106.501579) (end 132.146193 106.508474) (width 0.109) (layer "In2.Cu") (net 27))
  (segment (start 134.01 107.473421) (end 134.01 107.4) (width 0.109) (layer "In2.Cu") (net 27))
  (segment (start 132.366894 107.534614) (end 132.387233 107.592739) (width 0.109) (layer "In2.Cu") (net 27))
  (segment (start 134.037233 107.280681) (end 134.069996 107.22854) (width 0.109) (layer "In2.Cu") (net 27))
  (segment (start 131.200003 106.60512) (end 131.232766 106.657261) (width 0.109) (layer "In2.Cu") (net 27))
  (segment (start 130.650003 107.64488) (end 130.682766 107.592739) (width 0.109) (layer "In2.Cu") (net 27))
  (segment (start 130.153105 107.338806) (end 130.16 107.4) (width 0.109) (layer "In2.Cu") (net 27))
  (segment (start 132.387233 107.592739) (end 132.419996 107.64488) (width 0.109) (layer "In2.Cu") (net 27))
  (segment (start 133.735 107.748421) (end 133.796193 107.741526) (width 0.109) (layer "In2.Cu") (net 27))
  (segment (start 132.146193 106.508474) (end 132.204318 106.528813) (width 0.109) (layer "In2.Cu") (net 27))
  (segment (start 133.466894 107.534614) (end 133.487233 107.592739) (width 0.109) (layer "In2.Cu") (net 27))
  (segment (start 130.71 106.776579) (end 130.716894 106.715386) (width 0.109) (layer "In2.Cu") (net 27))
  (segment (start 133.432766 106.657261) (end 133.453105 106.715386) (width 0.109) (layer "In2.Cu") (net 27))
  (segment (start 130.187233 107.592739) (end 130.219996 107.64488) (width 0.109) (layer "In2.Cu") (net 27))
  (segment (start 151.39 95.176488) (end 151.14523 94.931718) (width 0.109) (layer "In2.Cu") (net 27))
  (segment (start 152.245912 90.964036) (end 152.724036 90.964036) (width 0.182) (layer "F.Cu") (net 28))
  (segment (start 92.84 109.365) (end 93.3265 109.049) (width 0.182) (layer "F.Cu") (net 28))
  (segment (start 153.595837 91.835837) (end 153.595837 93.116295) (width 0.182) (layer "F.Cu") (net 28))
  (segment (start 152.724036 90.964036) (end 153.595837 91.835837) (width 0.182) (layer "F.Cu") (net 28))
  (via (at 153.595837 93.116295) (size 0.45) (drill 0.1) (layers "F.Cu" "B.Cu") (net 28))
  (via (at 92.84 109.365) (size 0.45) (drill 0.1) (layers "F.Cu" "B.Cu") (net 28))
  (segment (start 138.05 108.125) (end 142.05 104.125) (width 0.109) (layer "In2.Cu") (net 28))
  (segment (start 129.229127 108.693455) (end 129.276529 108.72324) (width 0.109) (layer "In2.Cu") (net 28))
  (segment (start 127.829369 107.508271) (end 127.885 107.502002) (width 0.109) (layer "In2.Cu") (net 28))
  (segment (start 128.729127 107.556545) (end 128.776529 107.52676) (width 0.109) (layer "In2.Cu") (net 28))
  (segment (start 129.080457 107.59613) (end 129.110242 107.643532) (width 0.109) (layer "In2.Cu") (net 28))
  (segment (start 129.040872 107.556545) (end 129.080457 107.59613) (width 0.109) (layer "In2.Cu") (net 28))
  (segment (start 129.580457 108.65387) (end 129.610242 108.606468) (width 0.109) (layer "In2.Cu") (net 28))
  (segment (start 95.185 111.285) (end 123.29 111.285) (width 0.109) (layer "In2.Cu") (net 28))
  (segment (start 92.4 110.17) (end 92.855 110.625) (width 0.109) (layer "In2.Cu") (net 28))
  (segment (start 127.135 108.497998) (end 127.141268 108.553628) (width 0.109) (layer "In2.Cu") (net 28))
  (segment (start 127.641268 107.696372) (end 127.659757 107.643532) (width 0.109) (layer "In2.Cu") (net 28))
  (segment (start 128.44063 108.741729) (end 128.49347 108.72324) (width 0.109) (layer "In2.Cu") (net 28))
  (segment (start 129.135 107.752002) (end 129.135 108.497998) (width 0.109) (layer "In2.Cu") (net 28))
  (segment (start 92.84 109.365) (end 92.4 109.805) (width 0.109) (layer "In2.Cu") (net 28))
  (segment (start 129.729127 108.179542) (end 129.776529 108.149757) (width 0.109) (layer "In2.Cu") (net 28))
  (segment (start 126.94063 108.131268) (end 126.99347 108.149757) (width 0.109) (layer "In2.Cu") (net 28))
  (segment (start 127.99347 107.52676) (end 128.040872 107.556545) (width 0.109) (layer "In2.Cu") (net 28))
  (segment (start 129.329369 108.741729) (end 129.385 108.747998) (width 0.109) (layer "In2.Cu") (net 28))
  (segment (start 128.610242 108.606468) (end 128.628731 108.553628) (width 0.109) (layer "In2.Cu") (net 28))
  (segment (start 146.05 104.125) (end 151.898781 98.276219) (width 0.109) (layer "In2.Cu") (net 28))
  (segment (start 127.729127 107.556545) (end 127.776529 107.52676) (width 0.109) (layer "In2.Cu") (net 28))
  (segment (start 128.99347 107.52676) (end 129.040872 107.556545) (width 0.109) (layer "In2.Cu") (net 28))
  (segment (start 126.99347 108.149757) (end 127.040872 108.179542) (width 0.109) (layer "In2.Cu") (net 28))
  (segment (start 129.641268 108.319369) (end 129.659757 108.266529) (width 0.109) (layer "In2.Cu") (net 28))
  (segment (start 127.635 108.497998) (end 127.635 107.752002) (width 0.109) (layer "In2.Cu") (net 28))
  (segment (start 127.44063 108.741729) (end 127.49347 108.72324) (width 0.109) (layer "In2.Cu") (net 28))
  (segment (start 127.080457 108.219127) (end 127.110242 108.266529) (width 0.109) (layer "In2.Cu") (net 28))
  (segment (start 128.159757 108.606468) (end 128.189542 108.65387) (width 0.109) (layer "In2.Cu") (net 28))
  (segment (start 127.189542 108.65387) (end 127.229127 108.693455) (width 0.109) (layer "In2.Cu") (net 28))
  (segment (start 151.898781 94.321219) (end 153.103705 93.116295) (width 0.109) (layer "In2.Cu") (net 28))
  (segment (start 128.94063 107.508271) (end 128.99347 107.52676) (width 0.109) (layer "In2.Cu") (net 28))
  (segment (start 129.49347 108.72324) (end 129.540872 108.693455) (width 0.109) (layer "In2.Cu") (net 28))
  (segment (start 127.885 107.502002) (end 127.94063 107.508271) (width 0.109) (layer "In2.Cu") (net 28))
  (segment (start 128.689542 107.59613) (end 128.729127 107.556545) (width 0.109) (layer "In2.Cu") (net 28))
  (segment (start 128.276529 108.72324) (end 128.329369 108.741729) (width 0.109) (layer "In2.Cu") (net 28))
  (segment (start 128.040872 107.556545) (end 128.080457 107.59613) (width 0.109) (layer "In2.Cu") (net 28))
  (segment (start 128.141268 108.553628) (end 128.159757 108.606468) (width 0.109) (layer "In2.Cu") (net 28))
  (segment (start 127.635 107.752002) (end 127.641268 107.696372) (width 0.109) (layer "In2.Cu") (net 28))
  (segment (start 128.135 108.497998) (end 128.141268 108.553628) (width 0.109) (layer "In2.Cu") (net 28))
  (segment (start 127.540872 108.693455) (end 127.580457 108.65387) (width 0.109) (layer "In2.Cu") (net 28))
  (segment (start 128.229127 108.693455) (end 128.276529 108.72324) (width 0.109) (layer "In2.Cu") (net 28))
  (segment (start 129.885 108.125) (end 138.05 108.125) (width 0.109) (layer "In2.Cu") (net 28))
  (segment (start 128.641268 107.696372) (end 128.659757 107.643532) (width 0.109) (layer "In2.Cu") (net 28))
  (segment (start 129.385 108.747998) (end 129.44063 108.741729) (width 0.109) (layer "In2.Cu") (net 28))
  (segment (start 128.885 107.502002) (end 128.94063 107.508271) (width 0.109) (layer "In2.Cu") (net 28))
  (segment (start 127.94063 107.508271) (end 127.99347 107.52676) (width 0.109) (layer "In2.Cu") (net 28))
  (segment (start 128.329369 108.741729) (end 128.385 108.747998) (width 0.109) (layer "In2.Cu") (net 28))
  (segment (start 123.29 111.285) (end 126.45 108.125) (width 0.109) (layer "In2.Cu") (net 28))
  (segment (start 128.829369 107.508271) (end 128.885 107.502002) (width 0.109) (layer "In2.Cu") (net 28))
  (segment (start 129.635 108.375) (end 129.641268 108.319369) (width 0.109) (layer "In2.Cu") (net 28))
  (segment (start 127.159757 108.606468) (end 127.189542 108.65387) (width 0.109) (layer "In2.Cu") (net 28))
  (segment (start 127.628731 108.553628) (end 127.635 108.497998) (width 0.109) (layer "In2.Cu") (net 28))
  (segment (start 128.080457 107.59613) (end 128.110242 107.643532) (width 0.109) (layer "In2.Cu") (net 28))
  (segment (start 127.040872 108.179542) (end 127.080457 108.219127) (width 0.109) (layer "In2.Cu") (net 28))
  (segment (start 127.229127 108.693455) (end 127.276529 108.72324) (width 0.109) (layer "In2.Cu") (net 28))
  (segment (start 128.385 108.747998) (end 128.44063 108.741729) (width 0.109) (layer "In2.Cu") (net 28))
  (segment (start 129.610242 108.606468) (end 129.628731 108.553628) (width 0.109) (layer "In2.Cu") (net 28))
  (segment (start 129.628731 108.553628) (end 129.635 108.497998) (width 0.109) (layer "In2.Cu") (net 28))
  (segment (start 127.610242 108.606468) (end 127.628731 108.553628) (width 0.109) (layer "In2.Cu") (net 28))
  (segment (start 127.385 108.747998) (end 127.44063 108.741729) (width 0.109) (layer "In2.Cu") (net 28))
  (segment (start 128.776529 107.52676) (end 128.829369 107.508271) (width 0.109) (layer "In2.Cu") (net 28))
  (segment (start 128.540872 108.693455) (end 128.580457 108.65387) (width 0.109) (layer "In2.Cu") (net 28))
  (segment (start 92.855 110.625) (end 94.525 110.625) (width 0.109) (layer "In2.Cu") (net 28))
  (segment (start 127.659757 107.643532) (end 127.689542 107.59613) (width 0.109) (layer "In2.Cu") (net 28))
  (segment (start 94.525 110.625) (end 95.185 111.285) (width 0.109) (layer "In2.Cu") (net 28))
  (segment (start 142.05 104.125) (end 146.05 104.125) (width 0.109) (layer "In2.Cu") (net 28))
  (segment (start 128.628731 108.553628) (end 128.635 108.497998) (width 0.109) (layer "In2.Cu") (net 28))
  (segment (start 129.776529 108.149757) (end 129.829369 108.131268) (width 0.109) (layer "In2.Cu") (net 28))
  (segment (start 151.898781 98.276219) (end 151.898781 94.321219) (width 0.109) (layer "In2.Cu") (net 28))
  (segment (start 128.635 108.497998) (end 128.635 107.752002) (width 0.109) (layer "In2.Cu") (net 28))
  (segment (start 128.128731 107.696372) (end 128.135 107.752002) (width 0.109) (layer "In2.Cu") (net 28))
  (segment (start 127.141268 108.553628) (end 127.159757 108.606468) (width 0.109) (layer "In2.Cu") (net 28))
  (segment (start 129.141268 108.553628) (end 129.159757 108.606468) (width 0.109) (layer "In2.Cu") (net 28))
  (segment (start 129.635 108.497998) (end 129.635 108.375) (width 0.109) (layer "In2.Cu") (net 28))
  (segment (start 127.49347 108.72324) (end 127.540872 108.693455) (width 0.109) (layer "In2.Cu") (net 28))
  (segment (start 92.4 109.805) (end 92.4 110.17) (width 0.109) (layer "In2.Cu") (net 28))
  (segment (start 127.329369 108.741729) (end 127.385 108.747998) (width 0.109) (layer "In2.Cu") (net 28))
  (segment (start 128.635 107.752002) (end 128.641268 107.696372) (width 0.109) (layer "In2.Cu") (net 28))
  (segment (start 128.580457 108.65387) (end 128.610242 108.606468) (width 0.109) (layer "In2.Cu") (net 28))
  (segment (start 127.128731 108.319369) (end 127.135 108.375) (width 0.109) (layer "In2.Cu") (net 28))
  (segment (start 129.110242 107.643532) (end 129.128731 107.696372) (width 0.109) (layer "In2.Cu") (net 28))
  (segment (start 127.135 108.375) (end 127.135 108.497998) (width 0.109) (layer "In2.Cu") (net 28))
  (segment (start 126.45 108.125) (end 126.885 108.125) (width 0.109) (layer "In2.Cu") (net 28))
  (segment (start 127.580457 108.65387) (end 127.610242 108.606468) (width 0.109) (layer "In2.Cu") (net 28))
  (segment (start 126.885 108.125) (end 126.94063 108.131268) (width 0.109) (layer "In2.Cu") (net 28))
  (segment (start 127.689542 107.59613) (end 127.729127 107.556545) (width 0.109) (layer "In2.Cu") (net 28))
  (segment (start 129.44063 108.741729) (end 129.49347 108.72324) (width 0.109) (layer "In2.Cu") (net 28))
  (segment (start 127.776529 107.52676) (end 127.829369 107.508271) (width 0.109) (layer "In2.Cu") (net 28))
  (segment (start 128.49347 108.72324) (end 128.540872 108.693455) (width 0.109) (layer "In2.Cu") (net 28))
  (segment (start 128.189542 108.65387) (end 128.229127 108.693455) (width 0.109) (layer "In2.Cu") (net 28))
  (segment (start 129.159757 108.606468) (end 129.189542 108.65387) (width 0.109) (layer "In2.Cu") (net 28))
  (segment (start 129.659757 108.266529) (end 129.689542 108.219127) (width 0.109) (layer "In2.Cu") (net 28))
  (segment (start 127.110242 108.266529) (end 127.128731 108.319369) (width 0.109) (layer "In2.Cu") (net 28))
  (segment (start 127.276529 108.72324) (end 127.329369 108.741729) (width 0.109) (layer "In2.Cu") (net 28))
  (segment (start 128.659757 107.643532) (end 128.689542 107.59613) (width 0.109) (layer "In2.Cu") (net 28))
  (segment (start 128.110242 107.643532) (end 128.128731 107.696372) (width 0.109) (layer "In2.Cu") (net 28))
  (segment (start 129.128731 107.696372) (end 129.135 107.752002) (width 0.109) (layer "In2.Cu") (net 28))
  (segment (start 153.103705 93.116295) (end 153.595837 93.116295) (width 0.109) (layer "In2.Cu") (net 28))
  (segment (start 129.276529 108.72324) (end 129.329369 108.741729) (width 0.109) (layer "In2.Cu") (net 28))
  (segment (start 128.135 107.752002) (end 128.135 108.497998) (width 0.109) (layer "In2.Cu") (net 28))
  (segment (start 129.540872 108.693455) (end 129.580457 108.65387) (width 0.109) (layer "In2.Cu") (net 28))
  (segment (start 129.135 108.497998) (end 129.141268 108.553628) (width 0.109) (layer "In2.Cu") (net 28))
  (segment (start 129.829369 108.131268) (end 129.885 108.125) (width 0.109) (layer "In2.Cu") (net 28))
  (segment (start 129.189542 108.65387) (end 129.229127 108.693455) (width 0.109) (layer "In2.Cu") (net 28))
  (segment (start 129.689542 108.219127) (end 129.729127 108.179542) (width 0.109) (layer "In2.Cu") (net 28))
  (segment (start 154.144289 92.675) (end 154.144289 93.105711) (width 0.182) (layer "B.Cu") (net 28))
  (segment (start 153.629542 93.15) (end 153.595837 93.116295) (width 0.182) (layer "B.Cu") (net 28))
  (segment (start 154.1 93.15) (end 153.629542 93.15) (width 0.182) (layer "B.Cu") (net 28))
  (segment (start 154.144289 93.105711) (end 154.1 93.15) (width 0.182) (layer "B.Cu") (net 28))
  (segment (start 154.144289 93.635966) (end 154.130255 93.65) (width 0.182) (layer "B.Cu") (net 28))
  (segment (start 154.144289 93.105711) (end 154.144289 93.635966) (width 0.182) (layer "B.Cu") (net 28))
  (segment (start 149.595909 92.505909) (end 149.756911 92.666911) (width 0.182) (layer "F.Cu") (net 29))
  (segment (start 149.756911 92.666911) (end 149.756911 94.787696) (width 0.182) (layer "F.Cu") (net 29))
  (segment (start 91.9815 109.359) (end 92.3665 109.049) (width 0.182) (layer "F.Cu") (net 29))
  (segment (start 149.756911 94.787696) (end 149.627198 94.917409) (width 0.182) (layer "F.Cu") (net 29))
  (segment (start 149.595909 92.114036) (end 149.595909 92.505909) (width 0.182) (layer "F.Cu") (net 29))
  (via (at 149.627198 94.917409) (size 0.45) (drill 0.1) (layers "F.Cu" "B.Cu") (net 29))
  (via (at 91.9815 109.359) (size 0.45) (drill 0.1) (layers "F.Cu" "B.Cu") (net 29))
  (segment (start 127.70529 103.671019) (end 127.727478 103.60761) (width 0.109) (layer "In2.Cu") (net 29))
  (segment (start 127.435 103.840854) (end 127.501756 103.833332) (width 0.109) (layer "In2.Cu") (net 29))
  (segment (start 126.835 103.125) (end 126.901756 103.132521) (width 0.109) (layer "In2.Cu") (net 29))
  (segment (start 127.368243 103.833332) (end 127.435 103.840854) (width 0.109) (layer "In2.Cu") (net 29))
  (segment (start 127.622046 103.775403) (end 127.669549 103.7279) (width 0.109) (layer "In2.Cu") (net 29))
  (segment (start 91.6 108.9775) (end 91.6 108.725) (width 0.109) (layer "In2.Cu") (net 29))
  (segment (start 131.165165 103.811144) (end 131.222046 103.775403) (width 0.109) (layer "In2.Cu") (net 29))
  (segment (start 130.847953 103.775403) (end 130.904834 103.811144) (width 0.109) (layer "In2.Cu") (net 29))
  (segment (start 127.764709 102.578981) (end 127.80045 102.5221) (width 0.109) (layer "In2.Cu") (net 29))
  (segment (start 131.40045 102.5221) (end 131.447953 102.474597) (width 0.109) (layer "In2.Cu") (net 29))
  (segment (start 127.135 103.540854) (end 127.142521 103.60761) (width 0.109) (layer "In2.Cu") (net 29))
  (segment (start 128.935 102.709146) (end 128.942521 102.64239) (width 0.109) (layer "In2.Cu") (net 29))
  (segment (start 130.70529 102.578981) (end 130.727478 102.64239) (width 0.109) (layer "In2.Cu") (net 29))
  (segment (start 127.669549 103.7279) (end 127.70529 103.671019) (width 0.109) (layer "In2.Cu") (net 29))
  (segment (start 121.865 107.71) (end 126.45 103.125) (width 0.109) (layer "In2.Cu") (net 29))
  (segment (start 127.80045 102.5221) (end 127.847953 102.474597) (width 0.109) (layer "In2.Cu") (net 29))
  (segment (start 127.727478 103.60761) (end 127.735 103.540854) (width 0.109) (layer "In2.Cu") (net 29))
  (segment (start 130.727478 102.64239) (end 130.735 102.709146) (width 0.109) (layer "In2.Cu") (net 29))
  (segment (start 149.627198 95.422802) (end 149.627198 94.917409) (width 0.109) (layer "In2.Cu") (net 29))
  (segment (start 129.542521 103.60761) (end 129.564709 103.671019) (width 0.109) (layer "In2.Cu") (net 29))
  (segment (start 127.127478 103.358243) (end 127.135 103.425) (width 0.109) (layer "In2.Cu") (net 29))
  (segment (start 128.822046 103.775403) (end 128.869549 103.7279) (width 0.109) (layer "In2.Cu") (net 29))
  (segment (start 129.365165 102.438856) (end 129.422046 102.474597) (width 0.109) (layer "In2.Cu") (net 29))
  (segment (start 130.135 103.540854) (end 130.135 102.709146) (width 0.109) (layer "In2.Cu") (net 29))
  (segment (start 131.568243 102.416668) (end 131.635 102.409146) (width 0.109) (layer "In2.Cu") (net 29))
  (segment (start 127.735 102.709146) (end 127.742521 102.64239) (width 0.109) (layer "In2.Cu") (net 29))
  (segment (start 128.364709 103.671019) (end 128.40045 103.7279) (width 0.109) (layer "In2.Cu") (net 29))
  (segment (start 130.127478 103.60761) (end 130.135 103.540854) (width 0.109) (layer "In2.Cu") (net 29))
  (segment (start 131.927478 102.64239) (end 131.935 102.709146) (width 0.109) (layer "In2.Cu") (net 29))
  (segment (start 131.30529 103.671019) (end 131.327478 103.60761) (width 0.109) (layer "In2.Cu") (net 29))
  (segment (start 130.20045 102.5221) (end 130.247953 102.474597) (width 0.109) (layer "In2.Cu") (net 29))
  (segment (start 130.735 103.540854) (end 130.742521 103.60761) (width 0.109) (layer "In2.Cu") (net 29))
  (segment (start 131.822046 102.474597) (end 131.869549 102.5221) (width 0.109) (layer "In2.Cu") (net 29))
  (segment (start 127.742521 102.64239) (end 127.764709 102.578981) (width 0.109) (layer "In2.Cu") (net 29))
  (segment (start 128.964709 102.578981) (end 129.00045 102.5221) (width 0.109) (layer "In2.Cu") (net 29))
  (segment (start 131.364709 102.578981) (end 131.40045 102.5221) (width 0.109) (layer "In2.Cu") (net 29))
  (segment (start 131.90529 102.578981) (end 131.927478 102.64239) (width 0.109) (layer "In2.Cu") (net 29))
  (segment (start 128.935 103.540854) (end 128.935 102.709146) (width 0.109) (layer "In2.Cu") (net 29))
  (segment (start 128.30529 102.578981) (end 128.327478 102.64239) (width 0.109) (layer "In2.Cu") (net 29))
  (segment (start 129.00045 102.5221) (end 129.047953 102.474597) (width 0.109) (layer "In2.Cu") (net 29))
  (segment (start 131.942521 102.891757) (end 131.964709 102.955166) (width 0.109) (layer "In2.Cu") (net 29))
  (segment (start 129.469549 102.5221) (end 129.50529 102.578981) (width 0.109) (layer "In2.Cu") (net 29))
  (segment (start 133.05 103.125) (end 137.0375 99.1375) (width 0.109) (layer "In2.Cu") (net 29))
  (segment (start 130.135 102.709146) (end 130.142521 102.64239) (width 0.109) (layer "In2.Cu") (net 29))
  (segment (start 127.904834 102.438856) (end 127.968243 102.416668) (width 0.109) (layer "In2.Cu") (net 29))
  (segment (start 128.335 102.709146) (end 128.335 103.540854) (width 0.109) (layer "In2.Cu") (net 29))
  (segment (start 129.965165 103.811144) (end 130.022046 103.775403) (width 0.109) (layer "In2.Cu") (net 29))
  (segment (start 127.069549 103.237953) (end 127.10529 103.294834) (width 0.109) (layer "In2.Cu") (net 29))
  (segment (start 130.069549 103.7279) (end 130.10529 103.671019) (width 0.109) (layer "In2.Cu") (net 29))
  (segment (start 130.247953 102.474597) (end 130.304834 102.438856) (width 0.109) (layer "In2.Cu") (net 29))
  (segment (start 129.50529 102.578981) (end 129.527478 102.64239) (width 0.109) (layer "In2.Cu") (net 29))
  (segment (start 129.168243 102.416668) (end 129.235 102.409146) (width 0.109) (layer "In2.Cu") (net 29))
  (segment (start 130.764709 103.671019) (end 130.80045 103.7279) (width 0.109) (layer "In2.Cu") (net 29))
  (segment (start 91.6 108.725) (end 91.595499 108.720499) (width 0.109) (layer "In2.Cu") (net 29))
  (segment (start 131.935 102.825) (end 131.942521 102.891757) (width 0.109) (layer "In2.Cu") (net 29))
  (segment (start 128.568243 103.833332) (end 128.635 103.840854) (width 0.109) (layer "In2.Cu") (net 29))
  (segment (start 131.447953 102.474597) (end 131.504834 102.438856) (width 0.109) (layer "In2.Cu") (net 29))
  (segment (start 130.622046 102.474597) (end 130.669549 102.5221) (width 0.109) (layer "In2.Cu") (net 29))
  (segment (start 128.90529 103.671019) (end 128.927478 103.60761) (width 0.109) (layer "In2.Cu") (net 29))
  (segment (start 131.335 103.540854) (end 131.335 102.709146) (width 0.109) (layer "In2.Cu") (net 29))
  (segment (start 129.235 102.409146) (end 129.301756 102.416668) (width 0.109) (layer "In2.Cu") (net 29))
  (segment (start 127.304834 103.811144) (end 127.368243 103.833332) (width 0.109) (layer "In2.Cu") (net 29))
  (segment (start 131.635 102.409146) (end 131.701756 102.416668) (width 0.109) (layer "In2.Cu") (net 29))
  (segment (start 91.625 107.8) (end 91.625419 107.8) (width 0.109) (layer "In2.Cu") (net 29))
  (segment (start 129.647953 103.775403) (end 129.704834 103.811144) (width 0.109) (layer "In2.Cu") (net 29))
  (segment (start 127.847953 102.474597) (end 127.904834 102.438856) (width 0.109) (layer "In2.Cu") (net 29))
  (segment (start 128.927478 103.60761) (end 128.935 103.540854) (width 0.109) (layer "In2.Cu") (net 29))
  (segment (start 127.501756 103.833332) (end 127.565165 103.811144) (width 0.109) (layer "In2.Cu") (net 29))
  (segment (start 131.335 102.709146) (end 131.342521 102.64239) (width 0.109) (layer "In2.Cu") (net 29))
  (segment (start 131.101756 103.833332) (end 131.165165 103.811144) (width 0.109) (layer "In2.Cu") (net 29))
  (segment (start 127.164709 103.671019) (end 127.20045 103.7279) (width 0.109) (layer "In2.Cu") (net 29))
  (segment (start 145.9125 99.1375) (end 149.627198 95.422802) (width 0.109) (layer "In2.Cu") (net 29))
  (segment (start 129.901756 103.833332) (end 129.965165 103.811144) (width 0.109) (layer "In2.Cu") (net 29))
  (segment (start 131.327478 103.60761) (end 131.335 103.540854) (width 0.109) (layer "In2.Cu") (net 29))
  (segment (start 129.564709 103.671019) (end 129.60045 103.7279) (width 0.109) (layer "In2.Cu") (net 29))
  (segment (start 130.142521 102.64239) (end 130.164709 102.578981) (width 0.109) (layer "In2.Cu") (net 29))
  (segment (start 91.595499 107.829501) (end 91.625 107.8) (width 0.109) (layer "In2.Cu") (net 29))
  (segment (start 127.022046 103.19045) (end 127.069549 103.237953) (width 0.109) (layer "In2.Cu") (net 29))
  (segment (start 128.701756 103.833332) (end 128.765165 103.811144) (width 0.109) (layer "In2.Cu") (net 29))
  (segment (start 130.742521 103.60761) (end 130.764709 103.671019) (width 0.109) (layer "In2.Cu") (net 29))
  (segment (start 91.9815 109.359) (end 91.6 108.9775) (width 0.109) (layer "In2.Cu") (net 29))
  (segment (start 126.901756 103.132521) (end 126.965165 103.154709) (width 0.109) (layer "In2.Cu") (net 29))
  (segment (start 128.101756 102.416668) (end 128.165165 102.438856) (width 0.109) (layer "In2.Cu") (net 29))
  (segment (start 131.869549 102.5221) (end 131.90529 102.578981) (width 0.109) (layer "In2.Cu") (net 29))
  (segment (start 130.164709 102.578981) (end 130.20045 102.5221) (width 0.109) (layer "In2.Cu") (net 29))
  (segment (start 129.704834 103.811144) (end 129.768243 103.833332) (width 0.109) (layer "In2.Cu") (net 29))
  (segment (start 129.047953 102.474597) (end 129.104834 102.438856) (width 0.109) (layer "In2.Cu") (net 29))
  (segment (start 128.335 103.540854) (end 128.342521 103.60761) (width 0.109) (layer "In2.Cu") (net 29))
  (segment (start 91.625419 107.8) (end 91.825419 107.6) (width 0.109) (layer "In2.Cu") (net 29))
  (segment (start 127.735 103.540854) (end 127.735 102.709146) (width 0.109) (layer "In2.Cu") (net 29))
  (segment (start 126.965165 103.154709) (end 127.022046 103.19045) (width 0.109) (layer "In2.Cu") (net 29))
  (segment (start 94.16 107.6) (end 94.27 107.71) (width 0.109) (layer "In2.Cu") (net 29))
  (segment (start 127.565165 103.811144) (end 127.622046 103.775403) (width 0.109) (layer "In2.Cu") (net 29))
  (segment (start 130.968243 103.833332) (end 131.035 103.840854) (width 0.109) (layer "In2.Cu") (net 29))
  (segment (start 126.45 103.125) (end 126.835 103.125) (width 0.109) (layer "In2.Cu") (net 29))
  (segment (start 132.168243 103.117479) (end 132.235 103.125) (width 0.109) (layer "In2.Cu") (net 29))
  (segment (start 91.595499 108.720499) (end 91.595499 107.829501) (width 0.109) (layer "In2.Cu") (net 29))
  (segment (start 129.835 103.840854) (end 129.901756 103.833332) (width 0.109) (layer "In2.Cu") (net 29))
  (segment (start 130.80045 103.7279) (end 130.847953 103.775403) (width 0.109) (layer "In2.Cu") (net 29))
  (segment (start 128.342521 103.60761) (end 128.364709 103.671019) (width 0.109) (layer "In2.Cu") (net 29))
  (segment (start 128.035 102.409146) (end 128.101756 102.416668) (width 0.109) (layer "In2.Cu") (net 29))
  (segment (start 129.422046 102.474597) (end 129.469549 102.5221) (width 0.109) (layer "In2.Cu") (net 29))
  (segment (start 128.869549 103.7279) (end 128.90529 103.671019) (width 0.109) (layer "In2.Cu") (net 29))
  (segment (start 127.10529 103.294834) (end 127.127478 103.358243) (width 0.109) (layer "In2.Cu") (net 29))
  (segment (start 127.135 103.425) (end 127.135 103.540854) (width 0.109) (layer "In2.Cu") (net 29))
  (segment (start 132.047953 103.05955) (end 132.104834 103.095291) (width 0.109) (layer "In2.Cu") (net 29))
  (segment (start 130.022046 103.775403) (end 130.069549 103.7279) (width 0.109) (layer "In2.Cu") (net 29))
  (segment (start 130.435 102.409146) (end 130.501756 102.416668) (width 0.109) (layer "In2.Cu") (net 29))
  (segment (start 128.765165 103.811144) (end 128.822046 103.775403) (width 0.109) (layer "In2.Cu") (net 29))
  (segment (start 130.735 102.709146) (end 130.735 103.540854) (width 0.109) (layer "In2.Cu") (net 29))
  (segment (start 130.565165 102.438856) (end 130.622046 102.474597) (width 0.109) (layer "In2.Cu") (net 29))
  (segment (start 94.27 107.71) (end 121.865 107.71) (width 0.109) (layer "In2.Cu") (net 29))
  (segment (start 130.10529 103.671019) (end 130.127478 103.60761) (width 0.109) (layer "In2.Cu") (net 29))
  (segment (start 130.501756 102.416668) (end 130.565165 102.438856) (width 0.109) (layer "In2.Cu") (net 29))
  (segment (start 128.165165 102.438856) (end 128.222046 102.474597) (width 0.109) (layer "In2.Cu") (net 29))
  (segment (start 129.104834 102.438856) (end 129.168243 102.416668) (width 0.109) (layer "In2.Cu") (net 29))
  (segment (start 129.301756 102.416668) (end 129.365165 102.438856) (width 0.109) (layer "In2.Cu") (net 29))
  (segment (start 127.142521 103.60761) (end 127.164709 103.671019) (width 0.109) (layer "In2.Cu") (net 29))
  (segment (start 128.269549 102.5221) (end 128.30529 102.578981) (width 0.109) (layer "In2.Cu") (net 29))
  (segment (start 129.768243 103.833332) (end 129.835 103.840854) (width 0.109) (layer "In2.Cu") (net 29))
  (segment (start 129.535 102.709146) (end 129.535 103.540854) (width 0.109) (layer "In2.Cu") (net 29))
  (segment (start 128.222046 102.474597) (end 128.269549 102.5221) (width 0.109) (layer "In2.Cu") (net 29))
  (segment (start 132.104834 103.095291) (end 132.168243 103.117479) (width 0.109) (layer "In2.Cu") (net 29))
  (segment (start 132.00045 103.012047) (end 132.047953 103.05955) (width 0.109) (layer "In2.Cu") (net 29))
  (segment (start 127.20045 103.7279) (end 127.247953 103.775403) (width 0.109) (layer "In2.Cu") (net 29))
  (segment (start 131.222046 103.775403) (end 131.269549 103.7279) (width 0.109) (layer "In2.Cu") (net 29))
  (segment (start 128.40045 103.7279) (end 128.447953 103.775403) (width 0.109) (layer "In2.Cu") (net 29))
  (segment (start 131.504834 102.438856) (end 131.568243 102.416668) (width 0.109) (layer "In2.Cu") (net 29))
  (segment (start 91.825419 107.6) (end 94.16 107.6) (width 0.109) (layer "In2.Cu") (net 29))
  (segment (start 131.035 103.840854) (end 131.101756 103.833332) (width 0.109) (layer "In2.Cu") (net 29))
  (segment (start 129.527478 102.64239) (end 129.535 102.709146) (width 0.109) (layer "In2.Cu") (net 29))
  (segment (start 130.304834 102.438856) (end 130.368243 102.416668) (width 0.109) (layer "In2.Cu") (net 29))
  (segment (start 137.0375 99.1375) (end 145.9125 99.1375) (width 0.109) (layer "In2.Cu") (net 29))
  (segment (start 127.968243 102.416668) (end 128.035 102.409146) (width 0.109) (layer "In2.Cu") (net 29))
  (segment (start 131.269549 103.7279) (end 131.30529 103.671019) (width 0.109) (layer "In2.Cu") (net 29))
  (segment (start 128.327478 102.64239) (end 128.335 102.709146) (width 0.109) (layer "In2.Cu") (net 29))
  (segment (start 127.247953 103.775403) (end 127.304834 103.811144) (width 0.109) (layer "In2.Cu") (net 29))
  (segment (start 131.342521 102.64239) (end 131.364709 102.578981) (width 0.109) (layer "In2.Cu") (net 29))
  (segment (start 130.669549 102.5221) (end 130.70529 102.578981) (width 0.109) (layer "In2.Cu") (net 29))
  (segment (start 132.235 103.125) (end 133.05 103.125) (width 0.109) (layer "In2.Cu") (net 29))
  (segment (start 128.504834 103.811144) (end 128.568243 103.833332) (width 0.109) (layer "In2.Cu") (net 29))
  (segment (start 128.942521 102.64239) (end 128.964709 102.578981) (width 0.109) (layer "In2.Cu") (net 29))
  (segment (start 131.701756 102.416668) (end 131.765165 102.438856) (width 0.109) (layer "In2.Cu") (net 29))
  (segment (start 131.935 102.709146) (end 131.935 102.825) (width 0.109) (layer "In2.Cu") (net 29))
  (segment (start 129.535 103.540854) (end 129.542521 103.60761) (width 0.109) (layer "In2.Cu") (net 29))
  (segment (start 131.964709 102.955166) (end 132.00045 103.012047) (width 0.109) (layer "In2.Cu") (net 29))
  (segment (start 128.635 103.840854) (end 128.701756 103.833332) (width 0.109) (layer "In2.Cu") (net 29))
  (segment (start 130.368243 102.416668) (end 130.435 102.409146) (width 0.109) (layer "In2.Cu") (net 29))
  (segment (start 128.447953 103.775403) (end 128.504834 103.811144) (width 0.109) (layer "In2.Cu") (net 29))
  (segment (start 130.904834 103.811144) (end 130.968243 103.833332) (width 0.109) (layer "In2.Cu") (net 29))
  (segment (start 131.765165 102.438856) (end 131.822046 102.474597) (width 0.109) (layer "In2.Cu") (net 29))
  (segment (start 129.60045 103.7279) (end 129.647953 103.775403) (width 0.109) (layer "In2.Cu") (net 29))
  (segment (start 92.3665 108.414) (end 92.84 108.1) (width 0.2) (layer "F.Cu") (net 30))
  (segment (start 150.1 92.5) (end 150.2 92.6) (width 0.182) (layer "F.Cu") (net 30))
  (segment (start 150.1 92.118125) (end 150.1 92.5) (width 0.182) (layer "F.Cu") (net 30))
  (segment (start 150.2 92.6) (end 150.2 94.35) (width 0.182) (layer "F.Cu") (net 30))
  (via (at 92.84 108.1) (size 0.45) (drill 0.1) (layers "F.Cu" "B.Cu") (net 30))
  (via (at 150.2 94.35) (size 0.45) (drill 0.1) (layers "F.Cu" "B.Cu") (net 30))
  (segment (start 136.297925 100.891864) (end 136.346071 100.930257) (width 0.109) (layer "In2.Cu") (net 30))
  (segment (start 136.143129 103.280937) (end 136.156832 103.2209) (width 0.109) (layer "In2.Cu") (net 30))
  (segment (start 136.11641 103.336419) (end 136.143129 103.280937) (width 0.109) (layer "In2.Cu") (net 30))
  (segment (start 93.24 108.5) (end 94.26 108.5) (width 0.109) (layer "In2.Cu") (net 30))
  (segment (start 134.336412 102.771174) (end 134.322708 102.711139) (width 0.109) (layer "In2.Cu") (net 30))
  (segment (start 135.11423 101.993356) (end 135.100526 101.933321) (width 0.109) (layer "In2.Cu") (net 30))
  (segment (start 137.313656 101.08151) (end 137.299953 101.021473) (width 0.109) (layer "In2.Cu") (net 30))
  (segment (start 135.918767 100.978403) (end 135.957161 100.930258) (width 0.109) (layer "In2.Cu") (net 30))
  (segment (start 135.914352 103.463382) (end 135.974388 103.449679) (width 0.109) (layer "In2.Cu") (net 30))
  (segment (start 137.633652 101.828929) (end 137.672046 101.780783) (width 0.109) (layer "In2.Cu") (net 30))
  (segment (start 134.401525 102.485894) (end 134.449671 102.4475) (width 0.109) (layer "In2.Cu") (net 30))
  (segment (start 137.340374 100.844374) (end 137.378769 100.796228) (width 0.109) (layer "In2.Cu") (net 30))
  (segment (start 92.84 108.1) (end 93.24 108.5) (width 0.109) (layer "In2.Cu") (net 30))
  (segment (start 135.100526 101.933321) (end 135.100527 101.871739) (width 0.109) (layer "In2.Cu") (net 30))
  (segment (start 135.014917 104.227495) (end 135.074954 104.241198) (width 0.109) (layer "In2.Cu") (net 30))
  (segment (start 136.156832 103.2209) (end 136.156832 103.15932) (width 0.109) (layer "In2.Cu") (net 30))
  (segment (start 135.300199 103.773473) (end 134.401526 102.874802) (width 0.109) (layer "In2.Cu") (net 30))
  (segment (start 137.633652 101.44002) (end 137.378769 101.185137) (width 0.109) (layer "In2.Cu") (net 30))
  (segment (start 135.379015 103.998717) (end 135.379015 103.937137) (width 0.109) (layer "In2.Cu") (net 30))
  (segment (start 135.074954 104.241198) (end 135.136534 104.241198) (width 0.109) (layer "In2.Cu") (net 30))
  (segment (start 135.892048 101.215538) (end 135.878344 101.155503) (width 0.109) (layer "In2.Cu") (net 30))
  (segment (start 135.136534 104.241198) (end 135.196571 104.227495) (width 0.109) (layer "In2.Cu") (net 30))
  (segment (start 136.894228 102.265983) (end 136.855834 102.217838) (width 0.109) (layer "In2.Cu") (net 30))
  (segment (start 136.143129 103.099283) (end 136.11641 103.043801) (width 0.109) (layer "In2.Cu") (net 30))
  (segment (start 137.469988 101.907746) (end 137.530024 101.894043) (width 0.109) (layer "In2.Cu") (net 30))
  (segment (start 134.790435 102.485893) (end 135.689107 103.384565) (width 0.109) (layer "In2.Cu") (net 30))
  (segment (start 136.855834 102.606747) (end 136.894228 102.558601) (width 0.109) (layer "In2.Cu") (net 30))
  (segment (start 136.078016 103.384565) (end 136.11641 103.336419) (width 0.109) (layer "In2.Cu") (net 30))
  (segment (start 134.2675 103.9075) (end 134.315645 103.869105) (width 0.109) (layer "In2.Cu") (net 30))
  (segment (start 137.340374 101.136992) (end 137.313656 101.08151) (width 0.109) (layer "In2.Cu") (net 30))
  (segment (start 134.449671 102.4475) (end 134.505154 102.42078) (width 0.109) (layer "In2.Cu") (net 30))
  (segment (start 135.792735 103.449679) (end 135.852771 103.463382) (width 0.109) (layer "In2.Cu") (net 30))
  (segment (start 134.371127 103.842386) (end 134.431164 103.828683) (width 0.109) (layer "In2.Cu") (net 30))
  (segment (start 135.892047 101.033886) (end 135.918767 100.978403) (width 0.109) (layer "In2.Cu") (net 30))
  (segment (start 135.689107 103.384565) (end 135.737253 103.42296) (width 0.109) (layer "In2.Cu") (net 30))
  (segment (start 134.05 104.125) (end 134.2675 103.9075) (width 0.109) (layer "In2.Cu") (net 30))
  (segment (start 137.348371 101.894043) (end 137.408407 101.907746) (width 0.109) (layer "In2.Cu") (net 30))
  (segment (start 136.515071 102.645142) (end 136.570553 102.671861) (width 0.109) (layer "In2.Cu") (net 30))
  (segment (start 136.920947 102.321465) (end 136.894228 102.265983) (width 0.109) (layer "In2.Cu") (net 30))
  (segment (start 135.140948 102.048839) (end 135.11423 101.993356) (width 0.109) (layer "In2.Cu") (net 30))
  (segment (start 136.570553 102.671861) (end 136.630589 102.685564) (width 0.109) (layer "In2.Cu") (net 30))
  (segment (start 135.300199 104.162382) (end 135.338593 104.114236) (width 0.109) (layer "In2.Cu") (net 30))
  (segment (start 137.378769 100.796228) (end 138.05 100.125) (width 0.109) (layer "In2.Cu") (net 30))
  (segment (start 94.335 108.425) (end 122.15 108.425) (width 0.109) (layer "In2.Cu") (net 30))
  (segment (start 136.466925 102.606747) (end 136.515071 102.645142) (width 0.109) (layer "In2.Cu") (net 30))
  (segment (start 135.100527 101.871739) (end 135.114229 101.811704) (width 0.109) (layer "In2.Cu") (net 30))
  (segment (start 135.464626 101.642962) (end 135.520107 101.669682) (width 0.109) (layer "In2.Cu") (net 30))
  (segment (start 135.957162 101.319166) (end 135.918766 101.271021) (width 0.109) (layer "In2.Cu") (net 30))
  (segment (start 136.630589 102.685564) (end 136.69217 102.685564) (width 0.109) (layer "In2.Cu") (net 30))
  (segment (start 137.408407 101.907746) (end 137.469988 101.907746) (width 0.109) (layer "In2.Cu") (net 30))
  (segment (start 134.363131 102.534039) (end 134.401525 102.485894) (width 0.109) (layer "In2.Cu") (net 30))
  (segment (start 134.322709 102.649557) (end 134.336411 102.589522) (width 0.109) (layer "In2.Cu") (net 30))
  (segment (start 136.93465 102.443082) (end 136.93465 102.381502) (width 0.109) (layer "In2.Cu") (net 30))
  (segment (start 135.365312 104.058754) (end 135.379015 103.998717) (width 0.109) (layer "In2.Cu") (net 30))
  (segment (start 137.244743 101.828929) (end 137.292889 101.867324) (width 0.109) (layer "In2.Cu") (net 30))
  (segment (start 136.242444 100.865144) (end 136.297925 100.891864) (width 0.109) (layer "In2.Cu") (net 30))
  (segment (start 146 100.125) (end 150.006708 96.118292) (width 0.109) (layer "In2.Cu") (net 30))
  (segment (start 136.182407 100.851441) (end 136.242444 100.865144) (width 0.109) (layer "In2.Cu") (net 30))
  (segment (start 135.282972 101.642962) (end 135.343009 101.629259) (width 0.109) (layer "In2.Cu") (net 30))
  (segment (start 137.292889 101.867324) (end 137.348371 101.894043) (width 0.109) (layer "In2.Cu") (net 30))
  (segment (start 134.431164 103.828683) (end 134.492744 103.828683) (width 0.109) (layer "In2.Cu") (net 30))
  (segment (start 136.807688 102.645142) (end 136.855834 102.606747) (width 0.109) (layer "In2.Cu") (net 30))
  (segment (start 136.120827 100.851441) (end 136.182407 100.851441) (width 0.109) (layer "In2.Cu") (net 30))
  (segment (start 134.742289 102.4475) (end 134.790435 102.485893) (width 0.109) (layer "In2.Cu") (net 30))
  (segment (start 135.343009 101.629259) (end 135.404589 101.629259) (width 0.109) (layer "In2.Cu") (net 30))
  (segment (start 137.530024 101.894043) (end 137.585506 101.867324) (width 0.109) (layer "In2.Cu") (net 30))
  (segment (start 136.855834 102.217838) (end 135.957162 101.319166) (width 0.109) (layer "In2.Cu") (net 30))
  (segment (start 134.959435 104.200777) (end 135.014917 104.227495) (width 0.109) (layer "In2.Cu") (net 30))
  (segment (start 136.06079 100.865144) (end 136.120827 100.851441) (width 0.109) (layer "In2.Cu") (net 30))
  (segment (start 135.404589 101.629259) (end 135.464626 101.642962) (width 0.109) (layer "In2.Cu") (net 30))
  (segment (start 137.299953 101.021473) (end 137.299953 100.959893) (width 0.109) (layer "In2.Cu") (net 30))
  (segment (start 150.006708 94.543292) (end 150.2 94.35) (width 0.109) (layer "In2.Cu") (net 30))
  (segment (start 135.974388 103.449679) (end 136.02987 103.42296) (width 0.109) (layer "In2.Cu") (net 30))
  (segment (start 135.227489 101.669682) (end 135.282972 101.642962) (width 0.109) (layer "In2.Cu") (net 30))
  (segment (start 135.852771 103.463382) (end 135.914352 103.463382) (width 0.109) (layer "In2.Cu") (net 30))
  (segment (start 136.920947 102.503119) (end 136.93465 102.443082) (width 0.109) (layer "In2.Cu") (net 30))
  (segment (start 94.26 108.5) (end 94.335 108.425) (width 0.109) (layer "In2.Cu") (net 30))
  (segment (start 135.140949 101.756221) (end 135.179343 101.708076) (width 0.109) (layer "In2.Cu") (net 30))
  (segment (start 134.552781 103.842386) (end 134.608263 103.869105) (width 0.109) (layer "In2.Cu") (net 30))
  (segment (start 136.752206 102.671861) (end 136.807688 102.645142) (width 0.109) (layer "In2.Cu") (net 30))
  (segment (start 135.338593 103.821618) (end 135.300199 103.773473) (width 0.109) (layer "In2.Cu") (net 30))
  (segment (start 137.712468 101.603684) (end 137.698765 101.543647) (width 0.109) (layer "In2.Cu") (net 30))
  (segment (start 137.672046 101.488165) (end 137.633652 101.44002) (width 0.109) (layer "In2.Cu") (net 30))
  (segment (start 150.006708 96.118292) (end 150.006708 94.543292) (width 0.109) (layer "In2.Cu") (net 30))
  (segment (start 135.179343 101.708076) (end 135.227489 101.669682) (width 0.109) (layer "In2.Cu") (net 30))
  (segment (start 137.378769 101.185137) (end 137.340374 101.136992) (width 0.109) (layer "In2.Cu") (net 30))
  (segment (start 136.078016 102.995656) (end 135.179344 102.096984) (width 0.109) (layer "In2.Cu") (net 30))
  (segment (start 136.894228 102.558601) (end 136.920947 102.503119) (width 0.109) (layer "In2.Cu") (net 30))
  (segment (start 135.252053 104.200777) (end 135.300199 104.162382) (width 0.109) (layer "In2.Cu") (net 30))
  (segment (start 137.585506 101.867324) (end 137.633652 101.828929) (width 0.109) (layer "In2.Cu") (net 30))
  (segment (start 135.957161 100.930258) (end 136.005307 100.891864) (width 0.109) (layer "In2.Cu") (net 30))
  (segment (start 137.313656 100.899856) (end 137.340374 100.844374) (width 0.109) (layer "In2.Cu") (net 30))
  (segment (start 137.672046 101.780783) (end 137.698765 101.725301) (width 0.109) (layer "In2.Cu") (net 30))
  (segment (start 136.156832 103.15932) (end 136.143129 103.099283) (width 0.109) (layer "In2.Cu") (net 30))
  (segment (start 134.36313 102.826657) (end 134.336412 102.771174) (width 0.109) (layer "In2.Cu") (net 30))
  (segment (start 122.15 108.425) (end 126.45 104.125) (width 0.109) (layer "In2.Cu") (net 30))
  (segment (start 135.365312 103.8771) (end 135.338593 103.821618) (width 0.109) (layer "In2.Cu") (net 30))
  (segment (start 134.656408 103.9075) (end 134.91129 104.162382) (width 0.109) (layer "In2.Cu") (net 30))
  (segment (start 136.11641 103.043801) (end 136.078016 102.995656) (width 0.109) (layer "In2.Cu") (net 30))
  (segment (start 134.608263 103.869105) (end 134.656408 103.9075) (width 0.109) (layer "In2.Cu") (net 30))
  (segment (start 135.114229 101.811704) (end 135.140949 101.756221) (width 0.109) (layer "In2.Cu") (net 30))
  (segment (start 135.179344 102.096984) (end 135.140948 102.048839) (width 0.109) (layer "In2.Cu") (net 30))
  (segment (start 135.520107 101.669682) (end 135.568253 101.708075) (width 0.109) (layer "In2.Cu") (net 30))
  (segment (start 136.02987 103.42296) (end 136.078016 103.384565) (width 0.109) (layer "In2.Cu") (net 30))
  (segment (start 138.05 100.125) (end 146 100.125) (width 0.109) (layer "In2.Cu") (net 30))
  (segment (start 134.492744 103.828683) (end 134.552781 103.842386) (width 0.109) (layer "In2.Cu") (net 30))
  (segment (start 134.565191 102.407077) (end 134.626771 102.407077) (width 0.109) (layer "In2.Cu") (net 30))
  (segment (start 136.69217 102.685564) (end 136.752206 102.671861) (width 0.109) (layer "In2.Cu") (net 30))
  (segment (start 126.45 104.125) (end 134.05 104.125) (width 0.109) (layer "In2.Cu") (net 30))
  (segment (start 134.91129 104.162382) (end 134.959435 104.200777) (width 0.109) (layer "In2.Cu") (net 30))
  (segment (start 134.686808 102.42078) (end 134.742289 102.4475) (width 0.109) (layer "In2.Cu") (net 30))
  (segment (start 134.315645 103.869105) (end 134.371127 103.842386) (width 0.109) (layer "In2.Cu") (net 30))
  (segment (start 135.878344 101.155503) (end 135.878345 101.093921) (width 0.109) (layer "In2.Cu") (net 30))
  (segment (start 136.005307 100.891864) (end 136.06079 100.865144) (width 0.109) (layer "In2.Cu") (net 30))
  (segment (start 135.338593 104.114236) (end 135.365312 104.058754) (width 0.109) (layer "In2.Cu") (net 30))
  (segment (start 135.878345 101.093921) (end 135.892047 101.033886) (width 0.109) (layer "In2.Cu") (net 30))
  (segment (start 134.336411 102.589522) (end 134.363131 102.534039) (width 0.109) (layer "In2.Cu") (net 30))
  (segment (start 136.346071 100.930257) (end 137.244743 101.828929) (width 0.109) (layer "In2.Cu") (net 30))
  (segment (start 135.196571 104.227495) (end 135.252053 104.200777) (width 0.109) (layer "In2.Cu") (net 30))
  (segment (start 134.505154 102.42078) (end 134.565191 102.407077) (width 0.109) (layer "In2.Cu") (net 30))
  (segment (start 135.737253 103.42296) (end 135.792735 103.449679) (width 0.109) (layer "In2.Cu") (net 30))
  (segment (start 137.698765 101.725301) (end 137.712468 101.665264) (width 0.109) (layer "In2.Cu") (net 30))
  (segment (start 135.918766 101.271021) (end 135.892048 101.215538) (width 0.109) (layer "In2.Cu") (net 30))
  (segment (start 134.401526 102.874802) (end 134.36313 102.826657) (width 0.109) (layer "In2.Cu") (net 30))
  (segment (start 137.698765 101.543647) (end 137.672046 101.488165) (width 0.109) (layer "In2.Cu") (net 30))
  (segment (start 135.379015 103.937137) (end 135.365312 103.8771) (width 0.109) (layer "In2.Cu") (net 30))
  (segment (start 137.299953 100.959893) (end 137.313656 100.899856) (width 0.109) (layer "In2.Cu") (net 30))
  (segment (start 134.322708 102.711139) (end 134.322709 102.649557) (width 0.109) (layer "In2.Cu") (net 30))
  (segment (start 134.626771 102.407077) (end 134.686808 102.42078) (width 0.109) (layer "In2.Cu") (net 30))
  (segment (start 135.568253 101.708075) (end 136.466925 102.606747) (width 0.109) (layer "In2.Cu") (net 30))
  (segment (start 137.712468 101.665264) (end 137.712468 101.603684) (width 0.109) (layer "In2.Cu") (net 30))
  (segment (start 136.93465 102.381502) (end 136.920947 102.321465) (width 0.109) (layer "In2.Cu") (net 30))
  (segment (start 150.298287 94.201713) (end 150.415 94.085) (width 0.182) (layer "B.Cu") (net 30))
  (segment (start 150.415 93.7) (end 150.415 92.815) (width 0.182) (layer "B.Cu") (net 30))
  (segment (start 150.415 92.815) (end 150.4 92.8) (width 0.182) (layer "B.Cu") (net 30))
  (segment (start 150.298287 94.434137) (end 150.298287 94.201713) (width 0.182) (layer "B.Cu") (net 30))
  (segment (start 150.415 94.085) (end 150.415 93.7) (width 0.182) (layer "B.Cu") (net 30))
  (segment (start 150.59591 92.596035) (end 150.699489 92.699614) (width 0.182) (layer "F.Cu") (net 31))
  (segment (start 150.59591 92.114036) (end 150.59591 92.596035) (width 0.182) (layer "F.Cu") (net 31))
  (segment (start 150.699489 94.614532) (end 150.386218 94.927803) (width 0.182) (layer "F.Cu") (net 31))
  (segment (start 91.975 108.074334) (end 92.3665 107.779) (width 0.182) (layer "F.Cu") (net 31))
  (segment (start 150.699489 92.699614) (end 150.699489 94.614532) (width 0.182) (layer "F.Cu") (net 31))
  (via (at 150.386218 94.927803) (size 0.45) (drill 0.1) (layers "F.Cu" "B.Cu") (net 31))
  (via (at 91.975 108.074334) (size 0.45) (drill 0.1) (layers "F.Cu" "B.Cu") (net 31))
  (segment (start 130.472766 104.713342) (end 130.493105 104.771467) (width 0.109) (layer "In2.Cu") (net 31))
  (segment (start 130.05354 104.617657) (end 130.105681 104.584894) (width 0.109) (layer "In2.Cu") (net 31))
  (segment (start 131.875 105.69234) (end 131.936193 105.685445) (width 0.109) (layer "In2.Cu") (net 31))
  (segment (start 131.659996 105.588799) (end 131.70354 105.632343) (width 0.109) (layer "In2.Cu") (net 31))
  (segment (start 130.493105 104.771467) (end 130.5 104.83266) (width 0.109) (layer "In2.Cu") (net 31))
  (segment (start 127.536193 105.685445) (end 127.594318 105.665106) (width 0.109) (layer "In2.Cu") (net 31))
  (segment (start 132.672766 104.713342) (end 132.693105 104.771467) (width 0.109) (layer "In2.Cu") (net 31))
  (segment (start 128.240003 104.661201) (end 128.272766 104.713342) (width 0.109) (layer "In2.Cu") (net 31))
  (segment (start 132.177233 104.713342) (end 132.209996 104.661201) (width 0.109) (layer "In2.Cu") (net 31))
  (segment (start 132.640003 104.661201) (end 132.672766 104.713342) (width 0.109) (layer "In2.Cu") (net 31))
  (segment (start 128.513806 105.685445) (end 128.575 105.69234) (width 0.109) (layer "In2.Cu") (net 31))
  (segment (start 132.15 105.41734) (end 132.15 104.83266) (width 0.109) (layer "In2.Cu") (net 31))
  (segment (start 127.096459 105.184996) (end 127.140003 105.22854) (width 0.109) (layer "In2.Cu") (net 31))
  (segment (start 131.109996 104.661201) (end 131.15354 104.617657) (width 0.109) (layer "In2.Cu") (net 31))
  (segment (start 129.4 105.41734) (end 129.406894 105.478533) (width 0.109) (layer "In2.Cu") (net 31))
  (segment (start 130.894318 105.665106) (end 130.946459 105.632343) (width 0.109) (layer "In2.Cu") (net 31))
  (segment (start 127.809996 104.661201) (end 127.85354 104.617657) (width 0.109) (layer "In2.Cu") (net 31))
  (segment (start 130.286193 104.564555) (end 130.344318 104.584894) (width 0.109) (layer "In2.Cu") (net 31))
  (segment (start 128.3 104.83266) (end 128.3 105.41734) (width 0.109) (layer "In2.Cu") (net 31))
  (segment (start 129.890003 105.588799) (end 129.922766 105.536658) (width 0.109) (layer "In2.Cu") (net 31))
  (segment (start 127.963806 104.564555) (end 128.025 104.55766) (width 0.109) (layer "In2.Cu") (net 31))
  (segment (start 131.936193 105.685445) (end 131.994318 105.665106) (width 0.109) (layer "In2.Cu") (net 31))
  (segment (start 130.527233 105.536658) (end 130.559996 105.588799) (width 0.109) (layer "In2.Cu") (net 31))
  (segment (start 127.646459 105.632343) (end 127.690003 105.588799) (width 0.109) (layer "In2.Cu") (net 31))
  (segment (start 132.693105 104.771467) (end 132.7 104.83266) (width 0.109) (layer "In2.Cu") (net 31))
  (segment (start 131.994318 105.665106) (end 132.046459 105.632343) (width 0.109) (layer "In2.Cu") (net 31))
  (segment (start 127.30354 105.632343) (end 127.355681 105.665106) (width 0.109) (layer "In2.Cu") (net 31))
  (segment (start 130.5 105.41734) (end 130.506894 105.478533) (width 0.109) (layer "In2.Cu") (net 31))
  (segment (start 92.800666 108.9) (end 94.06 108.9) (width 0.109) (layer "In2.Cu") (net 31))
  (segment (start 127.756894 104.771467) (end 127.777233 104.713342) (width 0.109) (layer "In2.Cu") (net 31))
  (segment (start 131.627233 105.536658) (end 131.659996 105.588799) (width 0.109) (layer "In2.Cu") (net 31))
  (segment (start 128.272766 104.713342) (end 128.293105 104.771467) (width 0.109) (layer "In2.Cu") (net 31))
  (segment (start 131.6 105.41734) (end 131.606894 105.478533) (width 0.109) (layer "In2.Cu") (net 31))
  (segment (start 132.855681 105.097767) (end 132.913806 105.118106) (width 0.109) (layer "In2.Cu") (net 31))
  (segment (start 129.406894 105.478533) (end 129.427233 105.536658) (width 0.109) (layer "In2.Cu") (net 31))
  (segment (start 129.794318 105.665106) (end 129.846459 105.632343) (width 0.109) (layer "In2.Cu") (net 31))
  (segment (start 132.913806 105.118106) (end 132.975 105.125) (width 0.109) (layer "In2.Cu") (net 31))
  (segment (start 127.259996 105.588799) (end 127.30354 105.632343) (width 0.109) (layer "In2.Cu") (net 31))
  (segment (start 130.009996 104.661201) (end 130.05354 104.617657) (width 0.109) (layer "In2.Cu") (net 31))
  (segment (start 129.555681 105.665106) (end 129.613806 105.685445) (width 0.109) (layer "In2.Cu") (net 31))
  (segment (start 127.75 104.83266) (end 127.756894 104.771467) (width 0.109) (layer "In2.Cu") (net 31))
  (segment (start 135.05 105.125) (end 139.05 101.125) (width 0.109) (layer "In2.Cu") (net 31))
  (segment (start 132.975 105.125) (end 135.05 105.125) (width 0.109) (layer "In2.Cu") (net 31))
  (segment (start 130.60354 105.632343) (end 130.655681 105.665106) (width 0.109) (layer "In2.Cu") (net 31))
  (segment (start 131.325 104.55766) (end 131.386193 104.564555) (width 0.109) (layer "In2.Cu") (net 31))
  (segment (start 127.690003 105.588799) (end 127.722766 105.536658) (width 0.109) (layer "In2.Cu") (net 31))
  (segment (start 128.144318 104.584894) (end 128.196459 104.617657) (width 0.109) (layer "In2.Cu") (net 31))
  (segment (start 132.425 104.55766) (end 132.486193 104.564555) (width 0.109) (layer "In2.Cu") (net 31))
  (segment (start 128.694318 105.665106) (end 128.746459 105.632343) (width 0.109) (layer "In2.Cu") (net 31))
  (segment (start 150.386218 96.726282) (end 150.386218 94.927803) (width 0.109) (layer "In2.Cu") (net 31))
  (segment (start 132.305681 104.584894) (end 132.363806 104.564555) (width 0.109) (layer "In2.Cu") (net 31))
  (segment (start 130.440003 104.661201) (end 130.472766 104.713342) (width 0.109) (layer "In2.Cu") (net 31))
  (segment (start 129.427233 105.536658) (end 129.459996 105.588799) (width 0.109) (layer "In2.Cu") (net 31))
  (segment (start 131.70354 105.632343) (end 131.755681 105.665106) (width 0.109) (layer "In2.Cu") (net 31))
  (segment (start 128.85 104.83266) (end 128.856894 104.771467) (width 0.109) (layer "In2.Cu") (net 31))
  (segment (start 122.435 109.14) (end 126.45 105.125) (width 0.109) (layer "In2.Cu") (net 31))
  (segment (start 129.125 104.55766) (end 129.186193 104.564555) (width 0.109) (layer "In2.Cu") (net 31))
  (segment (start 131.263806 104.564555) (end 131.325 104.55766) (width 0.109) (layer "In2.Cu") (net 31))
  (segment (start 131.755681 105.665106) (end 131.813806 105.685445) (width 0.109) (layer "In2.Cu") (net 31))
  (segment (start 127.193105 105.338806) (end 127.2 105.4) (width 0.109) (layer "In2.Cu") (net 31))
  (segment (start 132.486193 104.564555) (end 132.544318 104.584894) (width 0.109) (layer "In2.Cu") (net 31))
  (segment (start 129.977233 104.713342) (end 130.009996 104.661201) (width 0.109) (layer "In2.Cu") (net 31))
  (segment (start 129.675 105.69234) (end 129.736193 105.685445) (width 0.109) (layer "In2.Cu") (net 31))
  (segment (start 126.45 105.125) (end 126.925 105.125) (width 0.109) (layer "In2.Cu") (net 31))
  (segment (start 130.163806 104.564555) (end 130.225 104.55766) (width 0.109) (layer "In2.Cu") (net 31))
  (segment (start 130.225 104.55766) (end 130.286193 104.564555) (width 0.109) (layer "In2.Cu") (net 31))
  (segment (start 128.877233 104.713342) (end 128.909996 104.661201) (width 0.109) (layer "In2.Cu") (net 31))
  (segment (start 131.496459 104.617657) (end 131.540003 104.661201) (width 0.109) (layer "In2.Cu") (net 31))
  (segment (start 127.85354 104.617657) (end 127.905681 104.584894) (width 0.109) (layer "In2.Cu") (net 31))
  (segment (start 131.572766 104.713342) (end 131.593105 104.771467) (width 0.109) (layer "In2.Cu") (net 31))
  (segment (start 131.022766 105.536658) (end 131.043105 105.478533) (width 0.109) (layer "In2.Cu") (net 31))
  (segment (start 145.9875 101.125) (end 150.386218 96.726282) (width 0.109) (layer "In2.Cu") (net 31))
  (segment (start 132.363806 104.564555) (end 132.425 104.55766) (width 0.109) (layer "In2.Cu") (net 31))
  (segment (start 132.7 104.83266) (end 132.7 104.85) (width 0.109) (layer "In2.Cu") (net 31))
  (segment (start 131.077233 104.713342) (end 131.109996 104.661201) (width 0.109) (layer "In2.Cu") (net 31))
  (segment (start 91.975 108.074334) (end 92.800666 108.9) (width 0.109) (layer "In2.Cu") (net 31))
  (segment (start 126.925 105.125) (end 126.986193 105.131894) (width 0.109) (layer "In2.Cu") (net 31))
  (segment (start 130.105681 104.584894) (end 130.163806 104.564555) (width 0.109) (layer "In2.Cu") (net 31))
  (segment (start 132.090003 105.588799) (end 132.122766 105.536658) (width 0.109) (layer "In2.Cu") (net 31))
  (segment (start 129.005681 104.584894) (end 129.063806 104.564555) (width 0.109) (layer "In2.Cu") (net 31))
  (segment (start 127.905681 104.584894) (end 127.963806 104.564555) (width 0.109) (layer "In2.Cu") (net 31))
  (segment (start 129.186193 104.564555) (end 129.244318 104.584894) (width 0.109) (layer "In2.Cu") (net 31))
  (segment (start 139.05 101.125) (end 145.9875 101.125) (width 0.109) (layer "In2.Cu") (net 31))
  (segment (start 132.046459 105.632343) (end 132.090003 105.588799) (width 0.109) (layer "In2.Cu") (net 31))
  (segment (start 127.2 105.41734) (end 127.206894 105.478533) (width 0.109) (layer "In2.Cu") (net 31))
  (segment (start 94.06 108.9) (end 94.3 109.14) (width 0.109) (layer "In2.Cu") (net 31))
  (segment (start 129.846459 105.632343) (end 129.890003 105.588799) (width 0.109) (layer "In2.Cu") (net 31))
  (segment (start 128.636193 105.685445) (end 128.694318 105.665106) (width 0.109) (layer "In2.Cu") (net 31))
  (segment (start 132.706894 104.911194) (end 132.727233 104.969319) (width 0.109) (layer "In2.Cu") (net 31))
  (segment (start 130.713806 105.685445) (end 130.775 105.69234) (width 0.109) (layer "In2.Cu") (net 31))
  (segment (start 128.306894 105.478533) (end 128.327233 105.536658) (width 0.109) (layer "In2.Cu") (net 31))
  (segment (start 132.727233 104.969319) (end 132.759996 105.02146) (width 0.109) (layer "In2.Cu") (net 31))
  (segment (start 127.594318 105.665106) (end 127.646459 105.632343) (width 0.109) (layer "In2.Cu") (net 31))
  (segment (start 128.95354 104.617657) (end 129.005681 104.584894) (width 0.109) (layer "In2.Cu") (net 31))
  (segment (start 132.143105 105.478533) (end 132.15 105.41734) (width 0.109) (layer "In2.Cu") (net 31))
  (segment (start 130.5 104.83266) (end 130.5 105.41734) (width 0.109) (layer "In2.Cu") (net 31))
  (segment (start 129.296459 104.617657) (end 129.340003 104.661201) (width 0.109) (layer "In2.Cu") (net 31))
  (segment (start 129.922766 105.536658) (end 129.943105 105.478533) (width 0.109) (layer "In2.Cu") (net 31))
  (segment (start 128.196459 104.617657) (end 128.240003 104.661201) (width 0.109) (layer "In2.Cu") (net 31))
  (segment (start 128.293105 104.771467) (end 128.3 104.83266) (width 0.109) (layer "In2.Cu") (net 31))
  (segment (start 131.205681 104.584894) (end 131.263806 104.564555) (width 0.109) (layer "In2.Cu") (net 31))
  (segment (start 129.4 104.83266) (end 129.4 105.41734) (width 0.109) (layer "In2.Cu") (net 31))
  (segment (start 127.2 105.4) (end 127.2 105.41734) (width 0.109) (layer "In2.Cu") (net 31))
  (segment (start 132.122766 105.536658) (end 132.143105 105.478533) (width 0.109) (layer "In2.Cu") (net 31))
  (segment (start 132.25354 104.617657) (end 132.305681 104.584894) (width 0.109) (layer "In2.Cu") (net 31))
  (segment (start 130.946459 105.632343) (end 130.990003 105.588799) (width 0.109) (layer "In2.Cu") (net 31))
  (segment (start 127.140003 105.22854) (end 127.172766 105.280681) (width 0.109) (layer "In2.Cu") (net 31))
  (segment (start 127.475 105.69234) (end 127.536193 105.685445) (width 0.109) (layer "In2.Cu") (net 31))
  (segment (start 127.743105 105.478533) (end 127.75 105.41734) (width 0.109) (layer "In2.Cu") (net 31))
  (segment (start 130.836193 105.685445) (end 130.894318 105.665106) (width 0.109) (layer "In2.Cu") (net 31))
  (segment (start 131.043105 105.478533) (end 131.05 105.41734) (width 0.109) (layer "In2.Cu") (net 31))
  (segment (start 129.393105 104.771467) (end 129.4 104.83266) (width 0.109) (layer "In2.Cu") (net 31))
  (segment (start 130.559996 105.588799) (end 130.60354 105.632343) (width 0.109) (layer "In2.Cu") (net 31))
  (segment (start 132.15 104.83266) (end 132.156894 104.771467) (width 0.109) (layer "In2.Cu") (net 31))
  (segment (start 128.025 104.55766) (end 128.086193 104.564555) (width 0.109) (layer "In2.Cu") (net 31))
  (segment (start 129.372766 104.713342) (end 129.393105 104.771467) (width 0.109) (layer "In2.Cu") (net 31))
  (segment (start 128.856894 104.771467) (end 128.877233 104.713342) (width 0.109) (layer "In2.Cu") (net 31))
  (segment (start 129.956894 104.771467) (end 129.977233 104.713342) (width 0.109) (layer "In2.Cu") (net 31))
  (segment (start 129.244318 104.584894) (end 129.296459 104.617657) (width 0.109) (layer "In2.Cu") (net 31))
  (segment (start 128.575 105.69234) (end 128.636193 105.685445) (width 0.109) (layer "In2.Cu") (net 31))
  (segment (start 132.544318 104.584894) (end 132.596459 104.617657) (width 0.109) (layer "In2.Cu") (net 31))
  (segment (start 131.05 105.41734) (end 131.05 104.83266) (width 0.109) (layer "In2.Cu") (net 31))
  (segment (start 127.777233 104.713342) (end 127.809996 104.661201) (width 0.109) (layer "In2.Cu") (net 31))
  (segment (start 131.444318 104.584894) (end 131.496459 104.617657) (width 0.109) (layer "In2.Cu") (net 31))
  (segment (start 126.986193 105.131894) (end 127.044318 105.152233) (width 0.109) (layer "In2.Cu") (net 31))
  (segment (start 131.606894 105.478533) (end 131.627233 105.536658) (width 0.109) (layer "In2.Cu") (net 31))
  (segment (start 131.6 104.83266) (end 131.6 105.41734) (width 0.109) (layer "In2.Cu") (net 31))
  (segment (start 128.790003 105.588799) (end 128.822766 105.536658) (width 0.109) (layer "In2.Cu") (net 31))
  (segment (start 131.593105 104.771467) (end 131.6 104.83266) (width 0.109) (layer "In2.Cu") (net 31))
  (segment (start 127.355681 105.665106) (end 127.413806 105.685445) (width 0.109) (layer "In2.Cu") (net 31))
  (segment (start 130.506894 105.478533) (end 130.527233 105.536658) (width 0.109) (layer "In2.Cu") (net 31))
  (segment (start 129.95 104.83266) (end 129.956894 104.771467) (width 0.109) (layer "In2.Cu") (net 31))
  (segment (start 127.206894 105.478533) (end 127.227233 105.536658) (width 0.109) (layer "In2.Cu") (net 31))
  (segment (start 131.386193 104.564555) (end 131.444318 104.584894) (width 0.109) (layer "In2.Cu") (net 31))
  (segment (start 129.943105 105.478533) (end 129.95 105.41734) (width 0.109) (layer "In2.Cu") (net 31))
  (segment (start 127.044318 105.152233) (end 127.096459 105.184996) (width 0.109) (layer "In2.Cu") (net 31))
  (segment (start 132.209996 104.661201) (end 132.25354 104.617657) (width 0.109) (layer "In2.Cu") (net 31))
  (segment (start 129.340003 104.661201) (end 129.372766 104.713342) (width 0.109) (layer "In2.Cu") (net 31))
  (segment (start 131.813806 105.685445) (end 131.875 105.69234) (width 0.109) (layer "In2.Cu") (net 31))
  (segment (start 128.746459 105.632343) (end 128.790003 105.588799) (width 0.109) (layer "In2.Cu") (net 31))
  (segment (start 131.05 104.83266) (end 131.056894 104.771467) (width 0.109) (layer "In2.Cu") (net 31))
  (segment (start 127.722766 105.536658) (end 127.743105 105.478533) (width 0.109) (layer "In2.Cu") (net 31))
  (segment (start 128.3 105.41734) (end 128.306894 105.478533) (width 0.109) (layer "In2.Cu") (net 31))
  (segment (start 129.613806 105.685445) (end 129.675 105.69234) (width 0.109) (layer "In2.Cu") (net 31))
  (segment (start 131.15354 104.617657) (end 131.205681 104.584894) (width 0.109) (layer "In2.Cu") (net 31))
  (segment (start 132.7 104.85) (end 132.706894 104.911194) (width 0.109) (layer "In2.Cu") (net 31))
  (segment (start 129.736193 105.685445) (end 129.794318 105.665106) (width 0.109) (layer "In2.Cu") (net 31))
  (segment (start 127.172766 105.280681) (end 127.193105 105.338806) (width 0.109) (layer "In2.Cu") (net 31))
  (segment (start 132.156894 104.771467) (end 132.177233 104.713342) (width 0.109) (layer "In2.Cu") (net 31))
  (segment (start 130.344318 104.584894) (end 130.396459 104.617657) (width 0.109) (layer "In2.Cu") (net 31))
  (segment (start 130.990003 105.588799) (end 131.022766 105.536658) (width 0.109) (layer "In2.Cu") (net 31))
  (segment (start 128.086193 104.564555) (end 128.144318 104.584894) (width 0.109) (layer "In2.Cu") (net 31))
  (segment (start 128.359996 105.588799) (end 128.40354 105.632343) (width 0.109) (layer "In2.Cu") (net 31))
  (segment (start 130.655681 105.665106) (end 130.713806 105.685445) (width 0.109) (layer "In2.Cu") (net 31))
  (segment (start 129.063806 104.564555) (end 129.125 104.55766) (width 0.109) (layer "In2.Cu") (net 31))
  (segment (start 130.775 105.69234) (end 130.836193 105.685445) (width 0.109) (layer "In2.Cu") (net 31))
  (segment (start 129.459996 105.588799) (end 129.50354 105.632343) (width 0.109) (layer "In2.Cu") (net 31))
  (segment (start 129.50354 105.632343) (end 129.555681 105.665106) (width 0.109) (layer "In2.Cu") (net 31))
  (segment (start 132.759996 105.02146) (end 132.80354 105.065004) (width 0.109) (layer "In2.Cu") (net 31))
  (segment (start 130.396459 104.617657) (end 130.440003 104.661201) (width 0.109) (layer "In2.Cu") (net 31))
  (segment (start 128.843105 105.478533) (end 128.85 105.41734) (width 0.109) (layer "In2.Cu") (net 31))
  (segment (start 128.85 105.41734) (end 128.85 104.83266) (width 0.109) (layer "In2.Cu") (net 31))
  (segment (start 94.3 109.14) (end 122.435 109.14) (width 0.109) (layer "In2.Cu") (net 31))
  (segment (start 128.40354 105.632343) (end 128.455681 105.665106) (width 0.109) (layer "In2.Cu") (net 31))
  (segment (start 132.80354 105.065004) (end 132.855681 105.097767) (width 0.109) (layer "In2.Cu") (net 31))
  (segment (start 131.056894 104.771467) (end 131.077233 104.713342) (width 0.109) (layer "In2.Cu") (net 31))
  (segment (start 127.413806 105.685445) (end 127.475 105.69234) (width 0.109) (layer "In2.Cu") (net 31))
  (segment (start 128.327233 105.536658) (end 128.359996 105.588799) (width 0.109) (layer "In2.Cu") (net 31))
  (segment (start 129.95 105.41734) (end 129.95 104.83266) (width 0.109) (layer "In2.Cu") (net 31))
  (segment (start 132.596459 104.617657) (end 132.640003 104.661201) (width 0.109) (layer "In2.Cu") (net 31))
  (segment (start 128.822766 105.536658) (end 128.843105 105.478533) (width 0.109) (layer "In2.Cu") (net 31))
  (segment (start 127.75 105.41734) (end 127.75 104.83266) (width 0.109) (layer "In2.Cu") (net 31))
  (segment (start 128.909996 104.661201) (end 128.95354 104.617657) (width 0.109) (layer "In2.Cu") (net 31))
  (segment (start 127.227233 105.536658) (end 127.259996 105.588799) (width 0.109) (layer "In2.Cu") (net 31))
  (segment (start 128.455681 105.665106) (end 128.513806 105.685445) (width 0.109) (layer "In2.Cu") (net 31))
  (segment (start 131.540003 104.661201) (end 131.572766 104.713342) (width 0.109) (layer "In2.Cu") (net 31))
  (segment (start 146.125 93.75) (end 146 93.625) (width 0.182) (layer "F.Cu") (net 32))
  (segment (start 146.39 92.75) (end 146.59591 92.54409) (width 0.182) (layer "F.Cu") (net 32))
  (segment (start 146 93.36) (end 146.39 92.97) (width 0.182) (layer "F.Cu") (net 32))
  (segment (start 146 93.625) (end 146 93.36) (width 0.182) (layer "F.Cu") (net 32))
  (segment (start 90.7865 110.319) (end 91.1715 110.009) (width 0.182) (layer "F.Cu") (net 32))
  (segment (start 146.241926 94.087443) (end 146.3625 93.966869) (width 0.182) (layer "F.Cu") (net 32))
  (segment (start 146.3625 93.8375) (end 146.275 93.75) (width 0.182) (layer "F.Cu") (net 32))
  (segment (start 146.59591 92.54409) (end 146.59591 92.114036) (width 0.182) (layer "F.Cu") (net 32))
  (segment (start 146.3625 93.966869) (end 146.3625 93.8375) (width 0.182) (layer "F.Cu") (net 32))
  (segment (start 146.275 93.75) (end 146.125 93.75) (width 0.182) (layer "F.Cu") (net 32))
  (segment (start 146.241926 94.373602) (end 146.241926 94.087443) (width 0.182) (layer "F.Cu") (net 32))
  (segment (start 146.39 92.97) (end 146.39 92.75) (width 0.182) (layer "F.Cu") (net 32))
  (segment (start 146.254673 94.386349) (end 146.241926 94.373602) (width 0.182) (layer "F.Cu") (net 32))
  (via (at 146.254673 94.386349) (size 0.45) (drill 0.1) (layers "F.Cu" "B.Cu") (net 32))
  (via (at 91.1715 110.009) (size 0.45) (drill 0.1) (layers "F.Cu" "B.Cu") (net 32))
  (segment (start 129.48854 101.802438) (end 129.540681 101.769675) (width 0.109) (layer "In4.Cu") (net 32))
  (segment (start 132.23854 102.665004) (end 132.290681 102.697767) (width 0.109) (layer "In4.Cu") (net 32))
  (segment (start 131.591894 101.956248) (end 131.612233 101.898123) (width 0.109) (layer "In4.Cu") (net 32))
  (segment (start 130.485 103.432559) (end 130.485 102.017441) (width 0.109) (layer "In4.Cu") (net 32))
  (segment (start 129.994996 103.604018) (end 130.03854 103.647562) (width 0.109) (layer "In4.Cu") (net 32))
  (segment (start 130.975003 101.845982) (end 131.007766 101.898123) (width 0.109) (layer "In4.Cu") (net 32))
  (segment (start 131.13854 103.647562) (end 131.190681 103.680325) (width 0.109) (layer "In4.Cu") (net 32))
  (segment (start 131.429318 103.680325) (end 131.481459 103.647562) (width 0.109) (layer "In4.Cu") (net 32))
  (segment (start 131.68854 101.802438) (end 131.740681 101.769675) (width 0.109) (layer "In4.Cu") (net 32))
  (segment (start 128.841894 103.493752) (end 128.862233 103.551877) (width 0.109) (layer "In4.Cu") (net 32))
  (segment (start 128.621193 102.731894) (end 128.679318 102.752233) (width 0.109) (layer "In4.Cu") (net 32))
  (segment (start 132.348806 102.718106) (end 132.41 102.725) (width 0.109) (layer "In4.Cu") (net 32))
  (segment (start 132.141894 102.511194) (end 132.162233 102.569319) (width 0.109) (layer "In4.Cu") (net 32))
  (segment (start 112.25 111.625) (end 113.75 110.125) (width 0.109) (layer "In4.Cu") (net 32))
  (segment (start 130.640681 101.769675) (end 130.698806 101.749336) (width 0.109) (layer "In4.Cu") (net 32))
  (segment (start 132.107766 101.898123) (end 132.128105 101.956248) (width 0.109) (layer "In4.Cu") (net 32))
  (segment (start 131.041894 103.493752) (end 131.062233 103.551877) (width 0.109) (layer "In4.Cu") (net 32))
  (segment (start 146.254673 97.120327) (end 146.254673 94.386349) (width 0.109) (layer "In4.Cu") (net 32))
  (segment (start 129.412233 101.898123) (end 129.444996 101.845982) (width 0.109) (layer "In4.Cu") (net 32))
  (segment (start 128.807766 102.880681) (end 128.828105 102.938806) (width 0.109) (layer "In4.Cu") (net 32))
  (segment (start 129.385 103.432559) (end 129.385 102.017441) (width 0.109) (layer "In4.Cu") (net 32))
  (segment (start 130.271193 103.700664) (end 130.329318 103.680325) (width 0.109) (layer "In4.Cu") (net 32))
  (segment (start 131.798806 101.749336) (end 131.86 101.742441) (width 0.109) (layer "In4.Cu") (net 32))
  (segment (start 129.444996 101.845982) (end 129.48854 101.802438) (width 0.109) (layer "In4.Cu") (net 32))
  (segment (start 131.644996 101.845982) (end 131.68854 101.802438) (width 0.109) (layer "In4.Cu") (net 32))
  (segment (start 113.75 110.125) (end 120.95 110.125) (width 0.109) (layer "In4.Cu") (net 32))
  (segment (start 129.831459 101.802438) (end 129.875003 101.845982) (width 0.109) (layer "In4.Cu") (net 32))
  (segment (start 129.171193 103.700664) (end 129.229318 103.680325) (width 0.109) (layer "In4.Cu") (net 32))
  (segment (start 131.921193 101.749336) (end 131.979318 101.769675) (width 0.109) (layer "In4.Cu") (net 32))
  (segment (start 131.86 101.742441) (end 131.921193 101.749336) (width 0.109) (layer "In4.Cu") (net 32))
  (segment (start 131.578105 103.493752) (end 131.585 103.432559) (width 0.109) (layer "In4.Cu") (net 32))
  (segment (start 129.540681 101.769675) (end 129.598806 101.749336) (width 0.109) (layer "In4.Cu") (net 32))
  (segment (start 91.553489 110.390989) (end 95.715989 110.390989) (width 0.109) (layer "In4.Cu") (net 32))
  (segment (start 129.357766 103.551877) (end 129.378105 103.493752) (width 0.109) (layer "In4.Cu") (net 32))
  (segment (start 132.135 102.45) (end 132.141894 102.511194) (width 0.109) (layer "In4.Cu") (net 32))
  (segment (start 91.1715 110.009) (end 91.553489 110.390989) (width 0.109) (layer "In4.Cu") (net 32))
  (segment (start 129.721193 101.749336) (end 129.779318 101.769675) (width 0.109) (layer "In4.Cu") (net 32))
  (segment (start 132.128105 101.956248) (end 132.135 102.017441) (width 0.109) (layer "In4.Cu") (net 32))
  (segment (start 130.544996 101.845982) (end 130.58854 101.802438) (width 0.109) (layer "In4.Cu") (net 32))
  (segment (start 130.03854 103.647562) (end 130.090681 103.680325) (width 0.109) (layer "In4.Cu") (net 32))
  (segment (start 131.557766 103.551877) (end 131.578105 103.493752) (width 0.109) (layer "In4.Cu") (net 32))
  (segment (start 129.935 102.017441) (end 129.935 103.432559) (width 0.109) (layer "In4.Cu") (net 32))
  (segment (start 131.007766 101.898123) (end 131.028105 101.956248) (width 0.109) (layer "In4.Cu") (net 32))
  (segment (start 132.075003 101.845982) (end 132.107766 101.898123) (width 0.109) (layer "In4.Cu") (net 32))
  (segment (start 128.835 103) (end 128.835 103.432559) (width 0.109) (layer "In4.Cu") (net 32))
  (segment (start 129.598806 101.749336) (end 129.66 101.742441) (width 0.109) (layer "In4.Cu") (net 32))
  (segment (start 131.035 102.017441) (end 131.035 103.432559) (width 0.109) (layer "In4.Cu") (net 32))
  (segment (start 128.835 103.432559) (end 128.841894 103.493752) (width 0.109) (layer "In4.Cu") (net 32))
  (segment (start 130.329318 103.680325) (end 130.381459 103.647562) (width 0.109) (layer "In4.Cu") (net 32))
  (segment (start 129.281459 103.647562) (end 129.325003 103.604018) (width 0.109) (layer "In4.Cu") (net 32))
  (segment (start 128.679318 102.752233) (end 128.731459 102.784996) (width 0.109) (layer "In4.Cu") (net 32))
  (segment (start 131.371193 103.700664) (end 131.429318 103.680325) (width 0.109) (layer "In4.Cu") (net 32))
  (segment (start 129.391894 101.956248) (end 129.412233 101.898123) (width 0.109) (layer "In4.Cu") (net 32))
  (segment (start 130.879318 101.769675) (end 130.931459 101.802438) (width 0.109) (layer "In4.Cu") (net 32))
  (segment (start 129.325003 103.604018) (end 129.357766 103.551877) (width 0.109) (layer "In4.Cu") (net 32))
  (segment (start 130.425003 103.604018) (end 130.457766 103.551877) (width 0.109) (layer "In4.Cu") (net 32))
  (segment (start 130.931459 101.802438) (end 130.975003 101.845982) (width 0.109) (layer "In4.Cu") (net 32))
  (segment (start 129.928105 101.956248) (end 129.935 102.017441) (width 0.109) (layer "In4.Cu") (net 32))
  (segment (start 128.731459 102.784996) (end 128.775003 102.82854) (width 0.109) (layer "In4.Cu") (net 32))
  (segment (start 130.821193 101.749336) (end 130.879318 101.769675) (width 0.109) (layer "In4.Cu") (net 32))
  (segment (start 130.148806 103.700664) (end 130.21 103.707559) (width 0.109) (layer "In4.Cu") (net 32))
  (segment (start 132.290681 102.697767) (end 132.348806 102.718106) (width 0.109) (layer "In4.Cu") (net 32))
  (segment (start 131.062233 103.551877) (end 131.094996 103.604018) (width 0.109) (layer "In4.Cu") (net 32))
  (segment (start 130.21 103.707559) (end 130.271193 103.700664) (width 0.109) (layer "In4.Cu") (net 32))
  (segment (start 132.194996 102.62146) (end 132.23854 102.665004) (width 0.109) (layer "In4.Cu") (net 32))
  (segment (start 128.35 102.725) (end 128.56 102.725) (width 0.109) (layer "In4.Cu") (net 32))
  (segment (start 130.090681 103.680325) (end 130.148806 103.700664) (width 0.109) (layer "In4.Cu") (net 32))
  (segment (start 128.894996 103.604018) (end 128.93854 103.647562) (width 0.109) (layer "In4.Cu") (net 32))
  (segment (start 131.035 103.432559) (end 131.041894 103.493752) (width 0.109) (layer "In4.Cu") (net 32))
  (segment (start 128.93854 103.647562) (end 128.990681 103.680325) (width 0.109) (layer "In4.Cu") (net 32))
  (segment (start 131.525003 103.604018) (end 131.557766 103.551877) (width 0.109) (layer "In4.Cu") (net 32))
  (segment (start 132.162233 102.569319) (end 132.194996 102.62146) (width 0.109) (layer "In4.Cu") (net 32))
  (segment (start 129.048806 103.700664) (end 129.11 103.707559) (width 0.109) (layer "In4.Cu") (net 32))
  (segment (start 128.990681 103.680325) (end 129.048806 103.700664) (width 0.109) (layer "In4.Cu") (net 32))
  (segment (start 129.962233 103.551877) (end 129.994996 103.604018) (width 0.109) (layer "In4.Cu") (net 32))
  (segment (start 128.775003 102.82854) (end 128.807766 102.880681) (width 0.109) (layer "In4.Cu") (net 32))
  (segment (start 128.862233 103.551877) (end 128.894996 103.604018) (width 0.109) (layer "In4.Cu") (net 32))
  (segment (start 128.828105 102.938806) (end 128.835 103) (width 0.109) (layer "In4.Cu") (net 32))
  (segment (start 140.65 102.725) (end 146.254673 97.120327) (width 0.109) (layer "In4.Cu") (net 32))
  (segment (start 130.58854 101.802438) (end 130.640681 101.769675) (width 0.109) (layer "In4.Cu") (net 32))
  (segment (start 128.56 102.725) (end 128.621193 102.731894) (width 0.109) (layer "In4.Cu") (net 32))
  (segment (start 131.31 103.707559) (end 131.371193 103.700664) (width 0.109) (layer "In4.Cu") (net 32))
  (segment (start 129.66 101.742441) (end 129.721193 101.749336) (width 0.109) (layer "In4.Cu") (net 32))
  (segment (start 129.907766 101.898123) (end 129.928105 101.956248) (width 0.109) (layer "In4.Cu") (net 32))
  (segment (start 130.491894 101.956248) (end 130.512233 101.898123) (width 0.109) (layer "In4.Cu") (net 32))
  (segment (start 131.248806 103.700664) (end 131.31 103.707559) (width 0.109) (layer "In4.Cu") (net 32))
  (segment (start 130.485 102.017441) (end 130.491894 101.956248) (width 0.109) (layer "In4.Cu") (net 32))
  (segment (start 129.935 103.432559) (end 129.941894 103.493752) (width 0.109) (layer "In4.Cu") (net 32))
  (segment (start 132.41 102.725) (end 140.65 102.725) (width 0.109) (layer "In4.Cu") (net 32))
  (segment (start 120.95 110.125) (end 128.35 102.725) (width 0.109) (layer "In4.Cu") (net 32))
  (segment (start 129.941894 103.493752) (end 129.962233 103.551877) (width 0.109) (layer "In4.Cu") (net 32))
  (segment (start 95.715989 110.390989) (end 96.95 111.625) (width 0.109) (layer "In4.Cu") (net 32))
  (segment (start 131.979318 101.769675) (end 132.031459 101.802438) (width 0.109) (layer "In4.Cu") (net 32))
  (segment (start 130.698806 101.749336) (end 130.76 101.742441) (width 0.109) (layer "In4.Cu") (net 32))
  (segment (start 129.11 103.707559) (end 129.171193 103.700664) (width 0.109) (layer "In4.Cu") (net 32))
  (segment (start 130.457766 103.551877) (end 130.478105 103.493752) (width 0.109) (layer "In4.Cu") (net 32))
  (segment (start 131.190681 103.680325) (end 131.248806 103.700664) (width 0.109) (layer "In4.Cu") (net 32))
  (segment (start 130.478105 103.493752) (end 130.485 103.432559) (width 0.109) (layer "In4.Cu") (net 32))
  (segment (start 130.381459 103.647562) (end 130.425003 103.604018) (width 0.109) (layer "In4.Cu") (net 32))
  (segment (start 129.229318 103.680325) (end 129.281459 103.647562) (width 0.109) (layer "In4.Cu") (net 32))
  (segment (start 131.585 103.432559) (end 131.585 102.017441) (width 0.109) (layer "In4.Cu") (net 32))
  (segment (start 131.612233 101.898123) (end 131.644996 101.845982) (width 0.109) (layer "In4.Cu") (net 32))
  (segment (start 131.585 102.017441) (end 131.591894 101.956248) (width 0.109) (layer "In4.Cu") (net 32))
  (segment (start 131.740681 101.769675) (end 131.798806 101.749336) (width 0.109) (layer "In4.Cu") (net 32))
  (segment (start 129.385 102.017441) (end 129.391894 101.956248) (width 0.109) (layer "In4.Cu") (net 32))
  (segment (start 129.378105 103.493752) (end 129.385 103.432559) (width 0.109) (layer "In4.Cu") (net 32))
  (segment (start 129.875003 101.845982) (end 129.907766 101.898123) (width 0.109) (layer "In4.Cu") (net 32))
  (segment (start 131.481459 103.647562) (end 131.525003 103.604018) (width 0.109) (layer "In4.Cu") (net 32))
  (segment (start 131.094996 103.604018) (end 131.13854 103.647562) (width 0.109) (layer "In4.Cu") (net 32))
  (segment (start 96.95 111.625) (end 112.25 111.625) (width 0.109) (layer "In4.Cu") (net 32))
  (segment (start 130.512233 101.898123) (end 130.544996 101.845982) (width 0.109) (layer "In4.Cu") (net 32))
  (segment (start 132.135 102.017441) (end 132.135 102.45) (width 0.109) (layer "In4.Cu") (net 32))
  (segment (start 129.779318 101.769675) (end 129.831459 101.802438) (width 0.109) (layer "In4.Cu") (net 32))
  (segment (start 130.76 101.742441) (end 130.821193 101.749336) (width 0.109) (layer "In4.Cu") (net 32))
  (segment (start 132.031459 101.802438) (end 132.075003 101.845982) (width 0.109) (layer "In4.Cu") (net 32))
  (segment (start 131.028105 101.956248) (end 131.035 102.017441) (width 0.109) (layer "In4.Cu") (net 32))
  (segment (start 145.817662 94.884062) (end 145.640886 94.707285) (width 0.182) (layer "F.Cu") (net 33))
  (segment (start 145.640886 94.707285) (end 145.640886 92.939518) (width 0.182) (layer "F.Cu") (net 33))
  (segment (start 145.640886 92.939518) (end 146.095911 92.484493) (width 0.182) (layer "F.Cu") (net 33))
  (segment (start 146.095911 92.484493) (end 146.095911 92.114036) (width 0.182) (layer "F.Cu") (net 33))
  (segment (start 90.7865 109.684) (end 91.1715 109.373999) (width 0.182) (layer "F.Cu") (net 33))
  (via (at 145.817662 94.884062) (size 0.45) (drill 0.1) (layers "F.Cu" "B.Cu") (net 33))
  (via (at 91.1715 109.373999) (size 0.45) (drill 0.1) (layers "F.Cu" "B.Cu") (net 33))
  (segment (start 94.825 109.7) (end 95.775 109.7) (width 0.109) (layer "In4.Cu") (net 33))
  (segment (start 136.379834 101.663706) (end 136.443243 101.685894) (width 0.109) (layer "In4.Cu") (net 33))
  (segment (start 135.31 101.693416) (end 135.376756 101.685894) (width 0.109) (layer "In4.Cu") (net 33))
  (segment (start 137.417521 101.460172) (end 137.439709 101.523581) (width 0.109) (layer "In4.Cu") (net 33))
  (segment (start 95.775 109.7) (end 96.9 110.825) (width 0.109) (layer "In4.Cu") (net 33))
  (segment (start 136.839709 99.926419) (end 136.87545 99.869538) (width 0.109) (layer "In4.Cu") (net 33))
  (segment (start 137.579834 101.663706) (end 137.643243 101.685894) (width 0.109) (layer "In4.Cu") (net 33))
  (segment (start 91.1715 109.373999) (end 91.720499 108.825) (width 0.109) (layer "In4.Cu") (net 33))
  (segment (start 133.81 101.393416) (end 133.817521 101.460172) (width 0.109) (layer "In4.Cu") (net 33))
  (segment (start 138.122953 100.79045) (end 138.179834 100.754709) (width 0.109) (layer "In4.Cu") (net 33))
  (segment (start 135.602478 101.460172) (end 135.61 101.393416) (width 0.109) (layer "In4.Cu") (net 33))
  (segment (start 133.744549 100.837953) (end 133.78029 100.894834) (width 0.109) (layer "In4.Cu") (net 33))
  (segment (start 133.87545 101.580462) (end 133.922953 101.627965) (width 0.109) (layer "In4.Cu") (net 33))
  (segment (start 135.779834 99.786294) (end 135.843243 99.764106) (width 0.109) (layer "In4.Cu") (net 33))
  (segment (start 135.722953 99.822035) (end 135.779834 99.786294) (width 0.109) (layer "In4.Cu") (net 33))
  (segment (start 135.843243 99.764106) (end 135.91 99.756584) (width 0.109) (layer "In4.Cu") (net 33))
  (segment (start 135.01 101.393416) (end 135.017521 101.460172) (width 0.109) (layer "In4.Cu") (net 33))
  (segment (start 135.243243 101.685894) (end 135.31 101.693416) (width 0.109) (layer "In4.Cu") (net 33))
  (segment (start 134.643243 99.764106) (end 134.71 99.756584) (width 0.109) (layer "In4.Cu") (net 33))
  (segment (start 137.240165 99.786294) (end 137.297046 99.822035) (width 0.109) (layer "In4.Cu") (net 33))
  (segment (start 137.944549 101.580462) (end 137.98029 101.523581) (width 0.109) (layer "In4.Cu") (net 33))
  (segment (start 137.71 101.693416) (end 137.776756 101.685894) (width 0.109) (layer "In4.Cu") (net 33))
  (segment (start 133.81 101.025) (end 133.81 101.393416) (width 0.109) (layer "In4.Cu") (net 33))
  (segment (start 145.65 95.051724) (end 145.817662 94.884062) (width 0.109) (layer "In4.Cu") (net 33))
  (segment (start 136.78029 101.523581) (end 136.802478 101.460172) (width 0.109) (layer "In4.Cu") (net 33))
  (segment (start 135.017521 101.460172) (end 135.039709 101.523581) (width 0.109) (layer "In4.Cu") (net 33))
  (segment (start 134.579834 99.786294) (end 134.643243 99.764106) (width 0.109) (layer "In4.Cu") (net 33))
  (segment (start 133.922953 101.627965) (end 133.979834 101.663706) (width 0.109) (layer "In4.Cu") (net 33))
  (segment (start 137.41 100.056584) (end 137.41 101.393416) (width 0.109) (layer "In4.Cu") (net 33))
  (segment (start 137.41 101.393416) (end 137.417521 101.460172) (width 0.109) (layer "In4.Cu") (net 33))
  (segment (start 133.802478 100.958243) (end 133.81 101.025) (width 0.109) (layer "In4.Cu") (net 33))
  (segment (start 111.75 110.825) (end 113.75 108.825) (width 0.109) (layer "In4.Cu") (net 33))
  (segment (start 136.87545 99.869538) (end 136.922953 99.822035) (width 0.109) (layer "In4.Cu") (net 33))
  (segment (start 135.617521 99.989828) (end 135.639709 99.926419) (width 0.109) (layer "In4.Cu") (net 33))
  (segment (start 135.639709 99.926419) (end 135.67545 99.869538) (width 0.109) (layer "In4.Cu") (net 33))
  (segment (start 136.51 101.693416) (end 136.576756 101.685894) (width 0.109) (layer "In4.Cu") (net 33))
  (segment (start 138.01 101.393416) (end 138.01 101.025) (width 0.109) (layer "In4.Cu") (net 33))
  (segment (start 136.81 100.056584) (end 136.817521 99.989828) (width 0.109) (layer "In4.Cu") (net 33))
  (segment (start 137.043243 99.764106) (end 137.11 99.756584) (width 0.109) (layer "In4.Cu") (net 33))
  (segment (start 138.243243 100.732521) (end 138.31 100.725) (width 0.109) (layer "In4.Cu") (net 33))
  (segment (start 134.47545 99.869538) (end 134.522953 99.822035) (width 0.109) (layer "In4.Cu") (net 33))
  (segment (start 136.27545 101.580462) (end 136.322953 101.627965) (width 0.109) (layer "In4.Cu") (net 33))
  (segment (start 136.979834 99.786294) (end 137.043243 99.764106) (width 0.109) (layer "In4.Cu") (net 33))
  (segment (start 133.817521 101.460172) (end 133.839709 101.523581) (width 0.109) (layer "In4.Cu") (net 33))
  (segment (start 93.95 108.825) (end 94.825 109.7) (width 0.109) (layer "In4.Cu") (net 33))
  (segment (start 137.643243 101.685894) (end 137.71 101.693416) (width 0.109) (layer "In4.Cu") (net 33))
  (segment (start 133.78029 100.894834) (end 133.802478 100.958243) (width 0.109) (layer "In4.Cu") (net 33))
  (segment (start 137.840165 101.663706) (end 137.897046 101.627965) (width 0.109) (layer "In4.Cu") (net 33))
  (segment (start 134.776756 99.764106) (end 134.840165 99.786294) (width 0.109) (layer "In4.Cu") (net 33))
  (segment (start 138.07545 100.837953) (end 138.122953 100.79045) (width 0.109) (layer "In4.Cu") (net 33))
  (segment (start 134.522953 99.822035) (end 134.579834 99.786294) (width 0.109) (layer "In4.Cu") (net 33))
  (segment (start 133.979834 101.663706) (end 134.043243 101.685894) (width 0.109) (layer "In4.Cu") (net 33))
  (segment (start 136.097046 99.822035) (end 136.144549 99.869538) (width 0.109) (layer "In4.Cu") (net 33))
  (segment (start 134.38029 101.523581) (end 134.402478 101.460172) (width 0.109) (layer "In4.Cu") (net 33))
  (segment (start 135.002478 99.989828) (end 135.01 100.056584) (width 0.109) (layer "In4.Cu") (net 33))
  (segment (start 135.039709 101.523581) (end 135.07545 101.580462) (width 0.109) (layer "In4.Cu") (net 33))
  (segment (start 136.922953 99.822035) (end 136.979834 99.786294) (width 0.109) (layer "In4.Cu") (net 33))
  (segment (start 133.839709 101.523581) (end 133.87545 101.580462) (width 0.109) (layer "In4.Cu") (net 33))
  (segment (start 134.439709 99.926419) (end 134.47545 99.869538) (width 0.109) (layer "In4.Cu") (net 33))
  (segment (start 136.640165 101.663706) (end 136.697046 101.627965) (width 0.109) (layer "In4.Cu") (net 33))
  (segment (start 134.176756 101.685894) (end 134.240165 101.663706) (width 0.109) (layer "In4.Cu") (net 33))
  (segment (start 133.576756 100.732521) (end 133.640165 100.754709) (width 0.109) (layer "In4.Cu") (net 33))
  (segment (start 134.297046 101.627965) (end 134.344549 101.580462) (width 0.109) (layer "In4.Cu") (net 33))
  (segment (start 137.897046 101.627965) (end 137.944549 101.580462) (width 0.109) (layer "In4.Cu") (net 33))
  (segment (start 91.720499 108.825) (end 93.95 108.825) (width 0.109) (layer "In4.Cu") (net 33))
  (segment (start 134.11 101.693416) (end 134.176756 101.685894) (width 0.109) (layer "In4.Cu") (net 33))
  (segment (start 136.040165 99.786294) (end 136.097046 99.822035) (width 0.109) (layer "In4.Cu") (net 33))
  (segment (start 135.07545 101.580462) (end 135.122953 101.627965) (width 0.109) (layer "In4.Cu") (net 33))
  (segment (start 135.544549 101.580462) (end 135.58029 101.523581) (width 0.109) (layer "In4.Cu") (net 33))
  (segment (start 136.443243 101.685894) (end 136.51 101.693416) (width 0.109) (layer "In4.Cu") (net 33))
  (segment (start 133.640165 100.754709) (end 133.697046 100.79045) (width 0.109) (layer "In4.Cu") (net 33))
  (segment (start 135.01 100.056584) (end 135.01 101.393416) (width 0.109) (layer "In4.Cu") (net 33))
  (segment (start 135.91 99.756584) (end 135.976756 99.764106) (width 0.109) (layer "In4.Cu") (net 33))
  (segment (start 134.41 100.056584) (end 134.417521 99.989828) (width 0.109) (layer "In4.Cu") (net 33))
  (segment (start 135.67545 99.869538) (end 135.722953 99.822035) (width 0.109) (layer "In4.Cu") (net 33))
  (segment (start 134.043243 101.685894) (end 134.11 101.693416) (width 0.109) (layer "In4.Cu") (net 33))
  (segment (start 136.817521 99.989828) (end 136.839709 99.926419) (width 0.109) (layer "In4.Cu") (net 33))
  (segment (start 134.98029 99.926419) (end 135.002478 99.989828) (width 0.109) (layer "In4.Cu") (net 33))
  (segment (start 138.002478 101.460172) (end 138.01 101.393416) (width 0.109) (layer "In4.Cu") (net 33))
  (segment (start 134.240165 101.663706) (end 134.297046 101.627965) (width 0.109) (layer "In4.Cu") (net 33))
  (segment (start 136.217521 101.460172) (end 136.239709 101.523581) (width 0.109) (layer "In4.Cu") (net 33))
  (segment (start 135.976756 99.764106) (end 136.040165 99.786294) (width 0.109) (layer "In4.Cu") (net 33))
  (segment (start 145.65 96.225) (end 145.65 95.051724) (width 0.109) (layer "In4.Cu") (net 33))
  (segment (start 136.202478 99.989828) (end 136.21 100.056584) (width 0.109) (layer "In4.Cu") (net 33))
  (segment (start 136.744549 101.580462) (end 136.78029 101.523581) (width 0.109) (layer "In4.Cu") (net 33))
  (segment (start 138.179834 100.754709) (end 138.243243 100.732521) (width 0.109) (layer "In4.Cu") (net 33))
  (segment (start 137.98029 101.523581) (end 138.002478 101.460172) (width 0.109) (layer "In4.Cu") (net 33))
  (segment (start 137.176756 99.764106) (end 137.240165 99.786294) (width 0.109) (layer "In4.Cu") (net 33))
  (segment (start 134.344549 101.580462) (end 134.38029 101.523581) (width 0.109) (layer "In4.Cu") (net 33))
  (segment (start 136.697046 101.627965) (end 136.744549 101.580462) (width 0.109) (layer "In4.Cu") (net 33))
  (segment (start 133.697046 100.79045) (end 133.744549 100.837953) (width 0.109) (layer "In4.Cu") (net 33))
  (segment (start 135.440165 101.663706) (end 135.497046 101.627965) (width 0.109) (layer "In4.Cu") (net 33))
  (segment (start 137.38029 99.926419) (end 137.402478 99.989828) (width 0.109) (layer "In4.Cu") (net 33))
  (segment (start 138.039709 100.894834) (end 138.07545 100.837953) (width 0.109) (layer "In4.Cu") (net 33))
  (segment (start 133.51 100.725) (end 133.576756 100.732521) (width 0.109) (layer "In4.Cu") (net 33))
  (segment (start 135.376756 101.685894) (end 135.440165 101.663706) (width 0.109) (layer "In4.Cu") (net 33))
  (segment (start 134.417521 99.989828) (end 134.439709 99.926419) (width 0.109) (layer "In4.Cu") (net 33))
  (segment (start 137.344549 99.869538) (end 137.38029 99.926419) (width 0.109) (layer "In4.Cu") (net 33))
  (segment (start 136.144549 99.869538) (end 136.18029 99.926419) (width 0.109) (layer "In4.Cu") (net 33))
  (segment (start 137.47545 101.580462) (end 137.522953 101.627965) (width 0.109) (layer "In4.Cu") (net 33))
  (segment (start 141.15 100.725) (end 145.65 96.225) (width 0.109) (layer "In4.Cu") (net 33))
  (segment (start 136.239709 101.523581) (end 136.27545 101.580462) (width 0.109) (layer "In4.Cu") (net 33))
  (segment (start 137.11 99.756584) (end 137.176756 99.764106) (width 0.109) (layer "In4.Cu") (net 33))
  (segment (start 134.71 99.756584) (end 134.776756 99.764106) (width 0.109) (layer "In4.Cu") (net 33))
  (segment (start 134.402478 101.460172) (end 134.41 101.393416) (width 0.109) (layer "In4.Cu") (net 33))
  (segment (start 137.402478 99.989828) (end 137.41 100.056584) (width 0.109) (layer "In4.Cu") (net 33))
  (segment (start 137.776756 101.685894) (end 137.840165 101.663706) (width 0.109) (layer "In4.Cu") (net 33))
  (segment (start 136.21 100.056584) (end 136.21 101.393416) (width 0.109) (layer "In4.Cu") (net 33))
  (segment (start 138.01 101.025) (end 138.017521 100.958243) (width 0.109) (layer "In4.Cu") (net 33))
  (segment (start 134.840165 99.786294) (end 134.897046 99.822035) (width 0.109) (layer "In4.Cu") (net 33))
  (segment (start 134.944549 99.869538) (end 134.98029 99.926419) (width 0.109) (layer "In4.Cu") (net 33))
  (segment (start 135.179834 101.663706) (end 135.243243 101.685894) (width 0.109) (layer "In4.Cu") (net 33))
  (segment (start 135.61 101.393416) (end 135.61 100.056584) (width 0.109) (layer "In4.Cu") (net 33))
  (segment (start 138.017521 100.958243) (end 138.039709 100.894834) (width 0.109) (layer "In4.Cu") (net 33))
  (segment (start 136.802478 101.460172) (end 136.81 101.393416) (width 0.109) (layer "In4.Cu") (net 33))
  (segment (start 120.65 108.825) (end 128.75 100.725) (width 0.109) (layer "In4.Cu") (net 33))
  (segment (start 136.21 101.393416) (end 136.217521 101.460172) (width 0.109) (layer "In4.Cu") (net 33))
  (segment (start 136.322953 101.627965) (end 136.379834 101.663706) (width 0.109) (layer "In4.Cu") (net 33))
  (segment (start 137.522953 101.627965) (end 137.579834 101.663706) (width 0.109) (layer "In4.Cu") (net 33))
  (segment (start 136.81 101.393416) (end 136.81 100.056584) (width 0.109) (layer "In4.Cu") (net 33))
  (segment (start 134.41 101.393416) (end 134.41 100.056584) (width 0.109) (layer "In4.Cu") (net 33))
  (segment (start 136.576756 101.685894) (end 136.640165 101.663706) (width 0.109) (layer "In4.Cu") (net 33))
  (segment (start 96.9 110.825) (end 111.75 110.825) (width 0.109) (layer "In4.Cu") (net 33))
  (segment (start 137.439709 101.523581) (end 137.47545 101.580462) (width 0.109) (layer "In4.Cu") (net 33))
  (segment (start 113.75 108.825) (end 120.65 108.825) (width 0.109) (layer "In4.Cu") (net 33))
  (segment (start 136.18029 99.926419) (end 136.202478 99.989828) (width 0.109) (layer "In4.Cu") (net 33))
  (segment (start 134.897046 99.822035) (end 134.944549 99.869538) (width 0.109) (layer "In4.Cu") (net 33))
  (segment (start 135.497046 101.627965) (end 135.544549 101.580462) (width 0.109) (layer "In4.Cu") (net 33))
  (segment (start 138.31 100.725) (end 141.15 100.725) (width 0.109) (layer "In4.Cu") (net 33))
  (segment (start 137.297046 99.822035) (end 137.344549 99.869538) (width 0.109) (layer "In4.Cu") (net 33))
  (segment (start 135.122953 101.627965) (end 135.179834 101.663706) (width 0.109) (layer "In4.Cu") (net 33))
  (segment (start 128.75 100.725) (end 133.51 100.725) (width 0.109) (layer "In4.Cu") (net 33))
  (segment (start 135.61 100.056584) (end 135.617521 99.989828) (width 0.109) (layer "In4.Cu") (net 33))
  (segment (start 135.58029 101.523581) (end 135.602478 101.460172) (width 0.109) (layer "In4.Cu") (net 33))
  (segment (start 152.650683 91.464035) (end 152.245911 91.464035) (width 0.182) (layer "F.Cu") (net 34))
  (segment (start 153.171573 92.55061) (end 153.171573 91.984924) (width 0.182) (layer "F.Cu") (net 34))
  (segment (start 152.924086 92.798097) (end 153.171573 92.55061) (width 0.182) (layer "F.Cu") (net 34))
  (segment (start 152.924086 93.417974) (end 152.924086 92.798097) (width 0.182) (layer "F.Cu") (net 34))
  (segment (start 153.168986 93.662874) (end 152.924086 93.417974) (width 0.182) (layer "F.Cu") (net 34))
  (segment (start 153.171573 91.984924) (end 152.650683 91.464035) (width 0.182) (layer "F.Cu") (net 34))
  (segment (start 90.343031 109.396769) (end 90.7865 109.049) (width 0.182) (layer "F.Cu") (net 34))
  (via (at 153.168986 93.662874) (size 0.45) (drill 0.1) (layers "F.Cu" "B.Cu") (net 34))
  (via (at 90.343031 109.396769) (size 0.45) (drill 0.1) (layers "F.Cu" "B.Cu") (net 34))
  (segment (start 153.168986 93.662874) (end 153.168986 94.106014) (width 0.109) (layer "In2.Cu") (net 34))
  (segment (start 93.979011 110.879011) (end 92.396218 110.879011) (width 0.109) (layer "In2.Cu") (net 34))
  (segment (start 90.99 110.6) (end 90.74 110.35) (width 0.109) (layer "In2.Cu") (net 34))
  (segment (start 90.343031 109.396769) (end 90.74 109.793738) (width 0.109) (layer "In2.Cu") (net 34))
  (segment (start 90.74 110.35) (end 90.74 109.793738) (width 0.109) (layer "In2.Cu") (net 34))
  (segment (start 126.45 109.125) (end 123.575 112) (width 0.109) (layer "In2.Cu") (net 34))
  (segment (start 153.168986 94.106014) (end 152.393755 94.881245) (width 0.109) (layer "In2.Cu") (net 34))
  (segment (start 123.575 112) (end 95.1 112) (width 0.109) (layer "In2.Cu") (net 34))
  (segment (start 139.05 109.125) (end 126.45 109.125) (width 0.109) (layer "In2.Cu") (net 34))
  (segment (start 92.117207 110.6) (end 90.99 110.6) (width 0.109) (layer "In2.Cu") (net 34))
  (segment (start 92.396218 110.879011) (end 92.117207 110.6) (width 0.109) (layer "In2.Cu") (net 34))
  (segment (start 152.393755 98.856245) (end 146.3 104.95) (width 0.109) (layer "In2.Cu") (net 34))
  (segment (start 143.225 104.95) (end 139.05 109.125) (width 0.109) (layer "In2.Cu") (net 34))
  (segment (start 152.393755 94.881245) (end 152.393755 98.856245) (width 0.109) (layer "In2.Cu") (net 34))
  (segment (start 146.3 104.95) (end 143.225 104.95) (width 0.109) (layer "In2.Cu") (net 34))
  (segment (start 95.1 112) (end 93.979011 110.879011) (width 0.109) (layer "In2.Cu") (net 34))
  (segment (start 147.480206 92.669794) (end 147.480206 92.879794) (width 0.182) (layer "F.Cu") (net 35))
  (segment (start 147.45 93.83) (end 147.151006 94.128994) (width 0.182) (layer "F.Cu") (net 35))
  (segment (start 147.595911 92.114036) (end 147.595911 92.554089) (width 0.182) (layer "F.Cu") (net 35))
  (segment (start 147.45 93.71) (end 147.45 93.83) (width 0.182) (layer "F.Cu") (net 35))
  (segment (start 147.12 93.38) (end 147.45 93.71) (width 0.182) (layer "F.Cu") (net 35))
  (segment (start 147.12 93.24) (end 147.12 93.38) (width 0.182) (layer "F.Cu") (net 35))
  (segment (start 89.4415 111.264) (end 89.8265 110.954) (width 0.182) (layer "F.Cu") (net 35))
  (segment (start 147.151006 94.128994) (end 147.151006 94.389087) (width 0.182) (layer "F.Cu") (net 35))
  (segment (start 147.595911 92.554089) (end 147.480206 92.669794) (width 0.182) (layer "F.Cu") (net 35))
  (segment (start 147.480206 92.879794) (end 147.12 93.24) (width 0.182) (layer "F.Cu") (net 35))
  (via (at 147.151006 94.389087) (size 0.45) (drill 0.1) (layers "F.Cu" "B.Cu") (net 35))
  (via (at 89.4415 111.264) (size 0.45) (drill 0.1) (layers "F.Cu" "B.Cu") (net 35))
  (segment (start 132.47545 106.837953) (end 132.522953 106.79045) (width 0.109) (layer "In4.Cu") (net 35))
  (segment (start 130.91 107.659814) (end 130.976756 107.652292) (width 0.109) (layer "In4.Cu") (net 35))
  (segment (start 130.779834 107.630104) (end 130.843243 107.652292) (width 0.109) (layer "In4.Cu") (net 35))
  (segment (start 131.81 106.090186) (end 131.81 107.359814) (width 0.109) (layer "In4.Cu") (net 35))
  (segment (start 131.18029 107.489979) (end 131.202478 107.42657) (width 0.109) (layer "In4.Cu") (net 35))
  (segment (start 131.802478 106.02343) (end 131.81 106.090186) (width 0.109) (layer "In4.Cu") (net 35))
  (segment (start 131.744549 105.90314) (end 131.78029 105.960021) (width 0.109) (layer "In4.Cu") (net 35))
  (segment (start 97.000551 113.225) (end 113.25 113.225) (width 0.109) (layer "In4.Cu") (net 35))
  (segment (start 95.700551 111.925) (end 97.000551 113.225) (width 0.109) (layer "In4.Cu") (net 35))
  (segment (start 130.843243 107.652292) (end 130.91 107.659814) (width 0.109) (layer "In4.Cu") (net 35))
  (segment (start 147.151006 95.626006) (end 147.151006 94.389087) (width 0.109) (layer "In4.Cu") (net 35))
  (segment (start 130.31 106.725) (end 130.376756 106.732521) (width 0.109) (layer "In4.Cu") (net 35))
  (segment (start 89.875 111.6975) (end 89.875 112.175) (width 0.109) (layer "In4.Cu") (net 35))
  (segment (start 130.61 107.025) (end 130.61 107.359814) (width 0.109) (layer "In4.Cu") (net 35))
  (segment (start 130.61 107.359814) (end 130.617521 107.42657) (width 0.109) (layer "In4.Cu") (net 35))
  (segment (start 131.81 107.359814) (end 131.817521 107.42657) (width 0.109) (layer "In4.Cu") (net 35))
  (segment (start 131.202478 107.42657) (end 131.21 107.359814) (width 0.109) (layer "In4.Cu") (net 35))
  (segment (start 147.45 98.925) (end 147.45 95.925) (width 0.109) (layer "In4.Cu") (net 35))
  (segment (start 130.976756 107.652292) (end 131.040165 107.630104) (width 0.109) (layer "In4.Cu") (net 35))
  (segment (start 132.579834 106.754709) (end 132.643243 106.732521) (width 0.109) (layer "In4.Cu") (net 35))
  (segment (start 121.55 112.725) (end 127.55 106.725) (width 0.109) (layer "In4.Cu") (net 35))
  (segment (start 131.21 107.359814) (end 131.21 106.090186) (width 0.109) (layer "In4.Cu") (net 35))
  (segment (start 131.78029 105.960021) (end 131.802478 106.02343) (width 0.109) (layer "In4.Cu") (net 35))
  (segment (start 90.025 112.325) (end 94.15 112.325) (width 0.109) (layer "In4.Cu") (net 35))
  (segment (start 132.439709 106.894834) (end 132.47545 106.837953) (width 0.109) (layer "In4.Cu") (net 35))
  (segment (start 131.217521 106.02343) (end 131.239709 105.960021) (width 0.109) (layer "In4.Cu") (net 35))
  (segment (start 130.722953 107.594363) (end 130.779834 107.630104) (width 0.109) (layer "In4.Cu") (net 35))
  (segment (start 132.344549 107.54686) (end 132.38029 107.489979) (width 0.109) (layer "In4.Cu") (net 35))
  (segment (start 132.522953 106.79045) (end 132.579834 106.754709) (width 0.109) (layer "In4.Cu") (net 35))
  (segment (start 132.176756 107.652292) (end 132.240165 107.630104) (width 0.109) (layer "In4.Cu") (net 35))
  (segment (start 131.097046 107.594363) (end 131.144549 107.54686) (width 0.109) (layer "In4.Cu") (net 35))
  (segment (start 131.697046 105.855637) (end 131.744549 105.90314) (width 0.109) (layer "In4.Cu") (net 35))
  (segment (start 94.15 112.325) (end 94.55 111.925) (width 0.109) (layer "In4.Cu") (net 35))
  (segment (start 131.576756 105.797708) (end 131.640165 105.819896) (width 0.109) (layer "In4.Cu") (net 35))
  (segment (start 130.67545 107.54686) (end 130.722953 107.594363) (width 0.109) (layer "In4.Cu") (net 35))
  (segment (start 127.55 106.725) (end 130.31 106.725) (width 0.109) (layer "In4.Cu") (net 35))
  (segment (start 131.144549 107.54686) (end 131.18029 107.489979) (width 0.109) (layer "In4.Cu") (net 35))
  (segment (start 132.402478 107.42657) (end 132.41 107.359814) (width 0.109) (layer "In4.Cu") (net 35))
  (segment (start 132.71 106.725) (end 139.65 106.725) (width 0.109) (layer "In4.Cu") (net 35))
  (segment (start 113.25 113.225) (end 113.75 112.725) (width 0.109) (layer "In4.Cu") (net 35))
  (segment (start 89.875 112.175) (end 90.025 112.325) (width 0.109) (layer "In4.Cu") (net 35))
  (segment (start 132.41 107.025) (end 132.417521 106.958243) (width 0.109) (layer "In4.Cu") (net 35))
  (segment (start 131.21 106.090186) (end 131.217521 106.02343) (width 0.109) (layer "In4.Cu") (net 35))
  (segment (start 147.45 95.925) (end 147.151006 95.626006) (width 0.109) (layer "In4.Cu") (net 35))
  (segment (start 130.440165 106.754709) (end 130.497046 106.79045) (width 0.109) (layer "In4.Cu") (net 35))
  (segment (start 131.51 105.790186) (end 131.576756 105.797708) (width 0.109) (layer "In4.Cu") (net 35))
  (segment (start 132.417521 106.958243) (end 132.439709 106.894834) (width 0.109) (layer "In4.Cu") (net 35))
  (segment (start 131.640165 105.819896) (end 131.697046 105.855637) (width 0.109) (layer "In4.Cu") (net 35))
  (segment (start 131.239709 105.960021) (end 131.27545 105.90314) (width 0.109) (layer "In4.Cu") (net 35))
  (segment (start 132.38029 107.489979) (end 132.402478 107.42657) (width 0.109) (layer "In4.Cu") (net 35))
  (segment (start 131.040165 107.630104) (end 131.097046 107.594363) (width 0.109) (layer "In4.Cu") (net 35))
  (segment (start 131.979834 107.630104) (end 132.043243 107.652292) (width 0.109) (layer "In4.Cu") (net 35))
  (segment (start 132.240165 107.630104) (end 132.297046 107.594363) (width 0.109) (layer "In4.Cu") (net 35))
  (segment (start 130.376756 106.732521) (end 130.440165 106.754709) (width 0.109) (layer "In4.Cu") (net 35))
  (segment (start 130.544549 106.837953) (end 130.58029 106.894834) (width 0.109) (layer "In4.Cu") (net 35))
  (segment (start 130.58029 106.894834) (end 130.602478 106.958243) (width 0.109) (layer "In4.Cu") (net 35))
  (segment (start 132.297046 107.594363) (end 132.344549 107.54686) (width 0.109) (layer "In4.Cu") (net 35))
  (segment (start 130.617521 107.42657) (end 130.639709 107.489979) (width 0.109) (layer "In4.Cu") (net 35))
  (segment (start 131.839709 107.489979) (end 131.87545 107.54686) (width 0.109) (layer "In4.Cu") (net 35))
  (segment (start 130.497046 106.79045) (end 130.544549 106.837953) (width 0.109) (layer "In4.Cu") (net 35))
  (segment (start 130.602478 106.958243) (end 130.61 107.025) (width 0.109) (layer "In4.Cu") (net 35))
  (segment (start 132.043243 107.652292) (end 132.11 107.659814) (width 0.109) (layer "In4.Cu") (net 35))
  (segment (start 132.11 107.659814) (end 132.176756 107.652292) (width 0.109) (layer "In4.Cu") (net 35))
  (segment (start 132.643243 106.732521) (end 132.71 106.725) (width 0.109) (layer "In4.Cu") (net 35))
  (segment (start 131.817521 107.42657) (end 131.839709 107.489979) (width 0.109) (layer "In4.Cu") (net 35))
  (segment (start 89.4415 111.264) (end 89.875 111.6975) (width 0.109) (layer "In4.Cu") (net 35))
  (segment (start 113.75 112.725) (end 121.55 112.725) (width 0.109) (layer "In4.Cu") (net 35))
  (segment (start 131.379834 105.819896) (end 131.443243 105.797708) (width 0.109) (layer "In4.Cu") (net 35))
  (segment (start 131.443243 105.797708) (end 131.51 105.790186) (width 0.109) (layer "In4.Cu") (net 35))
  (segment (start 94.55 111.925) (end 95.700551 111.925) (width 0.109) (layer "In4.Cu") (net 35))
  (segment (start 130.639709 107.489979) (end 130.67545 107.54686) (width 0.109) (layer "In4.Cu") (net 35))
  (segment (start 132.41 107.359814) (end 132.41 107.025) (width 0.109) (layer "In4.Cu") (net 35))
  (segment (start 131.87545 107.54686) (end 131.922953 107.594363) (width 0.109) (layer "In4.Cu") (net 35))
  (segment (start 131.322953 105.855637) (end 131.379834 105.819896) (width 0.109) (layer "In4.Cu") (net 35))
  (segment (start 131.27545 105.90314) (end 131.322953 105.855637) (width 0.109) (layer "In4.Cu") (net 35))
  (segment (start 139.65 106.725) (end 147.45 98.925) (width 0.109) (layer "In4.Cu") (net 35))
  (segment (start 131.922953 107.594363) (end 131.979834 107.630104) (width 0.109) (layer "In4.Cu") (net 35))
  (segment (start 89.8265 110.319) (end 90.3 110.005) (width 0.182) (layer "F.Cu") (net 36))
  (segment (start 146.713994 92.916006) (end 147.095908 92.534092) (width 0.182) (layer "F.Cu") (net 36))
  (segment (start 146.724154 94.935666) (end 146.713994 94.925506) (width 0.182) (layer "F.Cu") (net 36))
  (segment (start 146.713994 94.925506) (end 146.713994 92.916006) (width 0.182) (layer "F.Cu") (net 36))
  (segment (start 147.095908 92.534092) (end 147.095908 92.114036) (width 0.182) (layer "F.Cu") (net 36))
  (via (at 146.724154 94.935666) (size 0.45) (drill 0.1) (layers "F.Cu" "B.Cu") (net 36))
  (via (at 90.3 110.005) (size 0.45) (drill 0.1) (layers "F.Cu" "B.Cu") (net 36))
  (segment (start 127.8 104.725) (end 133.235 104.725) (width 0.109) (layer "In4.Cu") (net 36))
  (segment (start 134.247953 103.855817) (end 134.304834 103.820076) (width 0.109) (layer "In4.Cu") (net 36))
  (segment (start 134.727478 104.02361) (end 134.735 104.090366) (width 0.109) (layer "In4.Cu") (net 36))
  (segment (start 146.724154 95.899154) (end 146.724154 94.935666) (width 0.109) (layer "In4.Cu") (net 36))
  (segment (start 133.965165 105.629924) (end 134.022046 105.594183) (width 0.109) (layer "In4.Cu") (net 36))
  (segment (start 135.504834 103.820076) (end 135.568243 103.797888) (width 0.109) (layer "In4.Cu") (net 36))
  (segment (start 133.704834 105.629924) (end 133.768243 105.652112) (width 0.109) (layer "In4.Cu") (net 36))
  (segment (start 134.904834 105.629924) (end 134.968243 105.652112) (width 0.109) (layer "In4.Cu") (net 36))
  (segment (start 135.935 104.090366) (end 135.935 105.359634) (width 0.109) (layer "In4.Cu") (net 36))
  (segment (start 134.10529 105.489799) (end 134.127478 105.42639) (width 0.109) (layer "In4.Cu") (net 36))
  (segment (start 136.768243 104.732521) (end 136.835 104.725) (width 0.109) (layer "In4.Cu") (net 36))
  (segment (start 135.869549 103.90332) (end 135.90529 103.960201) (width 0.109) (layer "In4.Cu") (net 36))
  (segment (start 133.564709 105.489799) (end 133.60045 105.54668) (width 0.109) (layer "In4.Cu") (net 36))
  (segment (start 135.935 105.359634) (end 135.942521 105.42639) (width 0.109) (layer "In4.Cu") (net 36))
  (segment (start 135.822046 103.855817) (end 135.869549 103.90332) (width 0.109) (layer "In4.Cu") (net 36))
  (segment (start 136.564709 104.894834) (end 136.60045 104.837953) (width 0.109) (layer "In4.Cu") (net 36))
  (segment (start 134.135 104.090366) (end 134.142521 104.02361) (width 0.109) (layer "In4.Cu") (net 36))
  (segment (start 133.647953 105.594183) (end 133.704834 105.629924) (width 0.109) (layer "In4.Cu") (net 36))
  (segment (start 135.335 104.090366) (end 135.342521 104.02361) (width 0.109) (layer "In4.Cu") (net 36))
  (segment (start 96.875 112.425) (end 112.85 112.425) (width 0.109) (layer "In4.Cu") (net 36))
  (segment (start 136.104834 105.629924) (end 136.168243 105.652112) (width 0.109) (layer "In4.Cu") (net 36))
  (segment (start 134.142521 104.02361) (end 134.164709 103.960201) (width 0.109) (layer "In4.Cu") (net 36))
  (segment (start 146.85 98.025) (end 146.85 96.025) (width 0.109) (layer "In4.Cu") (net 36))
  (segment (start 133.422046 104.79045) (end 133.469549 104.837953) (width 0.109) (layer "In4.Cu") (net 36))
  (segment (start 113.85 111.425) (end 121.1 111.425) (width 0.109) (layer "In4.Cu") (net 36))
  (segment (start 133.235 104.725) (end 133.301756 104.732521) (width 0.109) (layer "In4.Cu") (net 36))
  (segment (start 134.304834 103.820076) (end 134.368243 103.797888) (width 0.109) (layer "In4.Cu") (net 36))
  (segment (start 135.942521 105.42639) (end 135.964709 105.489799) (width 0.109) (layer "In4.Cu") (net 36))
  (segment (start 134.764709 105.489799) (end 134.80045 105.54668) (width 0.109) (layer "In4.Cu") (net 36))
  (segment (start 136.647953 104.79045) (end 136.704834 104.754709) (width 0.109) (layer "In4.Cu") (net 36))
  (segment (start 136.542521 104.958243) (end 136.564709 104.894834) (width 0.109) (layer "In4.Cu") (net 36))
  (segment (start 134.435 103.790366) (end 134.501756 103.797888) (width 0.109) (layer "In4.Cu") (net 36))
  (segment (start 140.15 104.725) (end 146.85 98.025) (width 0.109) (layer "In4.Cu") (net 36))
  (segment (start 135.222046 105.594183) (end 135.269549 105.54668) (width 0.109) (layer "In4.Cu") (net 36))
  (segment (start 135.327478 105.42639) (end 135.335 105.359634) (width 0.109) (layer "In4.Cu") (net 36))
  (segment (start 135.964709 105.489799) (end 136.00045 105.54668) (width 0.109) (layer "In4.Cu") (net 36))
  (segment (start 133.835 105.659634) (end 133.901756 105.652112) (width 0.109) (layer "In4.Cu") (net 36))
  (segment (start 135.342521 104.02361) (end 135.364709 103.960201) (width 0.109) (layer "In4.Cu") (net 36))
  (segment (start 133.60045 105.54668) (end 133.647953 105.594183) (width 0.109) (layer "In4.Cu") (net 36))
  (segment (start 94.6875 111.2125) (end 95.6625 111.2125) (width 0.109) (layer "In4.Cu") (net 36))
  (segment (start 135.90529 103.960201) (end 135.927478 104.02361) (width 0.109) (layer "In4.Cu") (net 36))
  (segment (start 136.835 104.725) (end 140.15 104.725) (width 0.109) (layer "In4.Cu") (net 36))
  (segment (start 134.669549 103.90332) (end 134.70529 103.960201) (width 0.109) (layer "In4.Cu") (net 36))
  (segment (start 135.568243 103.797888) (end 135.635 103.790366) (width 0.109) (layer "In4.Cu") (net 36))
  (segment (start 136.00045 105.54668) (end 136.047953 105.594183) (width 0.109) (layer "In4.Cu") (net 36))
  (segment (start 134.368243 103.797888) (end 134.435 103.790366) (width 0.109) (layer "In4.Cu") (net 36))
  (segment (start 134.735 105.359634) (end 134.742521 105.42639) (width 0.109) (layer "In4.Cu") (net 36))
  (segment (start 121.1 111.425) (end 127.8 104.725) (width 0.109) (layer "In4.Cu") (net 36))
  (segment (start 136.469549 105.54668) (end 136.50529 105.489799) (width 0.109) (layer "In4.Cu") (net 36))
  (segment (start 134.735 104.090366) (end 134.735 105.359634) (width 0.109) (layer "In4.Cu") (net 36))
  (segment (start 133.301756 104.732521) (end 133.365165 104.754709) (width 0.109) (layer "In4.Cu") (net 36))
  (segment (start 135.335 105.359634) (end 135.335 104.090366) (width 0.109) (layer "In4.Cu") (net 36))
  (segment (start 136.50529 105.489799) (end 136.527478 105.42639) (width 0.109) (layer "In4.Cu") (net 36))
  (segment (start 135.165165 105.629924) (end 135.222046 105.594183) (width 0.109) (layer "In4.Cu") (net 36))
  (segment (start 135.635 103.790366) (end 135.701756 103.797888) (width 0.109) (layer "In4.Cu") (net 36))
  (segment (start 135.701756 103.797888) (end 135.765165 103.820076) (width 0.109) (layer "In4.Cu") (net 36))
  (segment (start 135.40045 103.90332) (end 135.447953 103.855817) (width 0.109) (layer "In4.Cu") (net 36))
  (segment (start 134.70529 103.960201) (end 134.727478 104.02361) (width 0.109) (layer "In4.Cu") (net 36))
  (segment (start 90.3 110.005) (end 90.960011 110.665011) (width 0.109) (layer "In4.Cu") (net 36))
  (segment (start 133.535 105.359634) (end 133.542521 105.42639) (width 0.109) (layer "In4.Cu") (net 36))
  (segment (start 136.301756 105.652112) (end 136.365165 105.629924) (width 0.109) (layer "In4.Cu") (net 36))
  (segment (start 133.768243 105.652112) (end 133.835 105.659634) (width 0.109) (layer "In4.Cu") (net 36))
  (segment (start 95.6625 111.2125) (end 96.875 112.425) (width 0.109) (layer "In4.Cu") (net 36))
  (segment (start 133.365165 104.754709) (end 133.422046 104.79045) (width 0.109) (layer "In4.Cu") (net 36))
  (segment (start 135.30529 105.489799) (end 135.327478 105.42639) (width 0.109) (layer "In4.Cu") (net 36))
  (segment (start 136.704834 104.754709) (end 136.768243 104.732521) (width 0.109) (layer "In4.Cu") (net 36))
  (segment (start 133.901756 105.652112) (end 133.965165 105.629924) (width 0.109) (layer "In4.Cu") (net 36))
  (segment (start 133.469549 104.837953) (end 133.50529 104.894834) (width 0.109) (layer "In4.Cu") (net 36))
  (segment (start 134.742521 105.42639) (end 134.764709 105.489799) (width 0.109) (layer "In4.Cu") (net 36))
  (segment (start 133.50529 104.894834) (end 133.527478 104.958243) (width 0.109) (layer "In4.Cu") (net 36))
  (segment (start 136.168243 105.652112) (end 136.235 105.659634) (width 0.109) (layer "In4.Cu") (net 36))
  (segment (start 135.035 105.659634) (end 135.101756 105.652112) (width 0.109) (layer "In4.Cu") (net 36))
  (segment (start 134.20045 103.90332) (end 134.247953 103.855817) (width 0.109) (layer "In4.Cu") (net 36))
  (segment (start 136.422046 105.594183) (end 136.469549 105.54668) (width 0.109) (layer "In4.Cu") (net 36))
  (segment (start 134.127478 105.42639) (end 134.135 105.359634) (width 0.109) (layer "In4.Cu") (net 36))
  (segment (start 134.847953 105.594183) (end 134.904834 105.629924) (width 0.109) (layer "In4.Cu") (net 36))
  (segment (start 134.622046 103.855817) (end 134.669549 103.90332) (width 0.109) (layer "In4.Cu") (net 36))
  (segment (start 135.927478 104.02361) (end 135.935 104.090366) (width 0.109) (layer "In4.Cu") (net 36))
  (segment (start 112.85 112.425) (end 113.85 111.425) (width 0.109) (layer "In4.Cu") (net 36))
  (segment (start 134.164709 103.960201) (end 134.20045 103.90332) (width 0.109) (layer "In4.Cu") (net 36))
  (segment (start 136.60045 104.837953) (end 136.647953 104.79045) (width 0.109) (layer "In4.Cu") (net 36))
  (segment (start 135.269549 105.54668) (end 135.30529 105.489799) (width 0.109) (layer "In4.Cu") (net 36))
  (segment (start 133.542521 105.42639) (end 133.564709 105.489799) (width 0.109) (layer "In4.Cu") (net 36))
  (segment (start 135.447953 103.855817) (end 135.504834 103.820076) (width 0.109) (layer "In4.Cu") (net 36))
  (segment (start 135.364709 103.960201) (end 135.40045 103.90332) (width 0.109) (layer "In4.Cu") (net 36))
  (segment (start 135.765165 103.820076) (end 135.822046 103.855817) (width 0.109) (layer "In4.Cu") (net 36))
  (segment (start 134.135 105.359634) (end 134.135 104.090366) (width 0.109) (layer "In4.Cu") (net 36))
  (segment (start 136.527478 105.42639) (end 136.535 105.359634) (width 0.109) (layer "In4.Cu") (net 36))
  (segment (start 136.235 105.659634) (end 136.301756 105.652112) (width 0.109) (layer "In4.Cu") (net 36))
  (segment (start 136.047953 105.594183) (end 136.104834 105.629924) (width 0.109) (layer "In4.Cu") (net 36))
  (segment (start 133.535 105.025) (end 133.535 105.359634) (width 0.109) (layer "In4.Cu") (net 36))
  (segment (start 134.069549 105.54668) (end 134.10529 105.489799) (width 0.109) (layer "In4.Cu") (net 36))
  (segment (start 136.535 105.025) (end 136.542521 104.958243) (width 0.109) (layer "In4.Cu") (net 36))
  (segment (start 136.535 105.359634) (end 136.535 105.025) (width 0.109) (layer "In4.Cu") (net 36))
  (segment (start 90.960011 110.665011) (end 94.140011 110.665011) (width 0.109) (layer "In4.Cu") (net 36))
  (segment (start 134.80045 105.54668) (end 134.847953 105.594183) (width 0.109) (layer "In4.Cu") (net 36))
  (segment (start 146.85 96.025) (end 146.724154 95.899154) (width 0.109) (layer "In4.Cu") (net 36))
  (segment (start 134.968243 105.652112) (end 135.035 105.659634) (width 0.109) (layer "In4.Cu") (net 36))
  (segment (start 135.101756 105.652112) (end 135.165165 105.629924) (width 0.109) (layer "In4.Cu") (net 36))
  (segment (start 134.022046 105.594183) (end 134.069549 105.54668) (width 0.109) (layer "In4.Cu") (net 36))
  (segment (start 134.501756 103.797888) (end 134.565165 103.820076) (width 0.109) (layer "In4.Cu") (net 36))
  (segment (start 94.140011 110.665011) (end 94.6875 111.2125) (width 0.109) (layer "In4.Cu") (net 36))
  (segment (start 134.565165 103.820076) (end 134.622046 103.855817) (width 0.109) (layer "In4.Cu") (net 36))
  (segment (start 133.527478 104.958243) (end 133.535 105.025) (width 0.109) (layer "In4.Cu") (net 36))
  (segment (start 136.365165 105.629924) (end 136.422046 105.594183) (width 0.109) (layer "In4.Cu") (net 36))
  (segment (start 116.713396 98.511492) (end 117.271492 98.511492) (width 0.182) (layer "F.Cu") (net 37))
  (segment (start 92.84 113.175) (end 93.3265 112.859) (width 0.182) (layer "F.Cu") (net 37))
  (segment (start 117.307984 98.475) (end 119.1829 98.475) (width 0.182) (layer "F.Cu") (net 37))
  (segment (start 117.271492 98.511492) (end 117.307984 98.475) (width 0.182) (layer "F.Cu") (net 37))
  (via (at 116.713396 98.511492) (size 0.45) (drill 0.1) (layers "F.Cu" "B.Cu") (net 37))
  (via (at 92.84 113.175) (size 0.45) (drill 0.1) (layers "F.Cu" "B.Cu") (net 37))
  (segment (start 112.346058 108.270332) (end 112.385 108.265944) (width 0.109) (layer "In6.Cu") (net 37))
  (segment (start 111.492669 109.134985) (end 111.505612 109.097997) (width 0.109) (layer "In6.Cu") (net 37))
  (segment (start 109.623941 108.270332) (end 109.660929 108.283275) (width 0.109) (layer "In6.Cu") (net 37))
  (segment (start 114.722324 107.988225) (end 114.713605 107.950019) (width 0.109) (layer "In6.Cu") (net 37))
  (segment (start 115.695806 107.996263) (end 115.258737 107.559193) (width 0.109) (layer "In6.Cu") (net 37))
  (segment (start 107.835 109.234056) (end 107.873941 109.229668) (width 0.109) (layer "In6.Cu") (net 37))
  (segment (start 112.073941 109.229668) (end 112.110929 109.216725) (width 0.109) (layer "In6.Cu") (net 37))
  (segment (start 112.91 108.440944) (end 112.914387 108.402003) (width 0.109) (layer "In6.Cu") (net 37))
  (segment (start 115.629862 108.285187) (end 115.665168 108.268184) (width 0.109) (layer "In6.Cu") (net 37))
  (segment (start 113.648179 108.331834) (end 113.675889 108.304124) (width 0.109) (layer "In6.Cu") (net 37))
  (segment (start 107.642669 108.84907) (end 107.655612 108.886058) (width 0.109) (layer "In6.Cu") (net 37))
  (segment (start 115.601016 107.406499) (end 115.631655 107.430931) (width 0.109) (layer "In6.Cu") (net 37))
  (segment (start 108.260929 108.283275) (end 108.29411 108.304124) (width 0.109) (layer "In6.Cu") (net 37))
  (segment (start 111.86 109.059056) (end 111.864387 109.097997) (width 0.109) (layer "In6.Cu") (net 37))
  (segment (start 110.39411 108.304124) (end 110.42182 108.331834) (width 0.109) (layer "In6.Cu") (net 37))
  (segment (start 112.914387 108.402003) (end 112.92733 108.365015) (width 0.109) (layer "In6.Cu") (net 37))
  (segment (start 110.848179 108.331834) (end 110.875889 108.304124) (width 0.109) (layer "In6.Cu") (net 37))
  (segment (start 114.945303 107.765248) (end 114.980611 107.782249) (width 0.109) (layer "In6.Cu") (net 37))
  (segment (start 115.234304 107.342344) (end 115.258736 107.311707) (width 0.109) (layer "In6.Cu") (net 37))
  (segment (start 108.32182 108.331834) (end 108.342669 108.365015) (width 0.109) (layer "In6.Cu") (net 37))
  (segment (start 112.555612 108.402003) (end 112.56 108.440944) (width 0.109) (layer "In6.Cu") (net 37))
  (segment (start 113.325889 109.195876) (end 113.35907 109.216725) (width 0.109) (layer "In6.Cu") (net 37))
  (segment (start 112.696058 109.229668) (end 112.735 109.234056) (width 0.109) (layer "In6.Cu") (net 37))
  (segment (start 111.60907 108.283275) (end 111.646058 108.270332) (width 0.109) (layer "In6.Cu") (net 37))
  (segment (start 110.010929 109.216725) (end 110.04411 109.195876) (width 0.109) (layer "In6.Cu") (net 37))
  (segment (start 107.873941 109.229668) (end 107.910929 109.216725) (width 0.109) (layer "In6.Cu") (net 37))
  (segment (start 113.61 108.440944) (end 113.614387 108.402003) (width 0.109) (layer "In6.Cu") (net 37))
  (segment (start 111.855612 108.402003) (end 111.86 108.440944) (width 0.109) (layer "In6.Cu") (net 37))
  (segment (start 108.496058 109.229668) (end 108.535 109.234056) (width 0.109) (layer "In6.Cu") (net 37))
  (segment (start 111.198179 109.168166) (end 111.225889 109.195876) (width 0.109) (layer "In6.Cu") (net 37))
  (segment (start 108.535 109.234056) (end 108.573941 109.229668) (width 0.109) (layer "In6.Cu") (net 37))
  (segment (start 112.22733 108.365015) (end 112.248179 108.331834) (width 0.109) (layer "In6.Cu") (net 37))
  (segment (start 112.810929 109.216725) (end 112.84411 109.195876) (width 0.109) (layer "In6.Cu") (net 37))
  (segment (start 115.250986 108.595388) (end 115.242266 108.557183) (width 0.109) (layer "In6.Cu") (net 37))
  (segment (start 114.611065 108.643935) (end 114.641703 108.619501) (width 0.109) (layer "In6.Cu") (net 37))
  (segment (start 113.54411 109.195876) (end 113.57182 109.168166) (width 0.109) (layer "In6.Cu") (net 37))
  (segment (start 109.42733 108.365015) (end 109.448179 108.331834) (width 0.109) (layer "In6.Cu") (net 37))
  (segment (start 112.205612 109.097997) (end 112.21 109.059056) (width 0.109) (layer "In6.Cu") (net 37))
  (segment (start 92.317685 110.802315) (end 92.445 110.675) (width 0.109) (layer "In6.Cu") (net 37))
  (segment (start 114.829705 107.765248) (end 114.867911 107.756527) (width 0.109) (layer "In6.Cu") (net 37))
  (segment (start 115.2173 107.377651) (end 115.234304 107.342344) (width 0.109) (layer "In6.Cu") (net 37))
  (segment (start 110.596058 109.229668) (end 110.635 109.234056) (width 0.109) (layer "In6.Cu") (net 37))
  (segment (start 89.95 112.3) (end 89.85 112.2) (width 0.109) (layer "In6.Cu") (net 37))
  (segment (start 108.048179 108.331834) (end 108.075889 108.304124) (width 0.109) (layer "In6.Cu") (net 37))
  (segment (start 108.64411 109.195876) (end 108.67182 109.168166) (width 0.109) (layer "In6.Cu") (net 37))
  (segment (start 108.005612 109.097997) (end 108.01 109.059056) (width 0.109) (layer "In6.Cu") (net 37))
  (segment (start 108.748179 108.331834) (end 108.775889 108.304124) (width 0.109) (layer "In6.Cu") (net 37))
  (segment (start 109.660929 108.283275) (end 109.69411 108.304124) (width 0.109) (layer "In6.Cu") (net 37))
  (segment (start 115.019288 108.780162) (end 115.057493 108.788882) (width 0.109) (layer "In6.Cu") (net 37))
  (segment (start 115.096681 108.788882) (end 115.134886 108.780162) (width 0.109) (layer "In6.Cu") (net 37))
  (segment (start 107.560929 108.76733) (end 107.59411 108.788179) (width 0.109) (layer "In6.Cu") (net 37))
  (segment (start 113.255612 108.402003) (end 113.26 108.440944) (width 0.109) (layer "In6.Cu") (net 37))
  (segment (start 115.170193 108.763159) (end 115.200831 108.738726) (width 0.109) (layer "In6.Cu") (net 37))
  (segment (start 108.10907 108.283275) (end 108.146058 108.270332) (width 0.109) (layer "In6.Cu") (net 37))
  (segment (start 113.123941 108.270332) (end 113.160929 108.283275) (width 0.109) (layer "In6.Cu") (net 37))
  (segment (start 108.72733 108.365015) (end 108.748179 108.331834) (width 0.109) (layer "In6.Cu") (net 37))
  (segment (start 108.36 109.059056) (end 108.364387 109.097997) (width 0.109) (layer "In6.Cu") (net 37))
  (segment (start 113.92182 108.331834) (end 113.942669 108.365015) (width 0.109) (layer "In6.Cu") (net 37))
  (segment (start 111.296058 109.229668) (end 111.335 109.234056) (width 0.109) (layer "In6.Cu") (net 37))
  (segment (start 108.355612 108.402003) (end 108.36 108.440944) (width 0.109) (layer "In6.Cu") (net 37))
  (segment (start 112.57733 109.134985) (end 112.598179 109.168166) (width 0.109) (layer "In6.Cu") (net 37))
  (segment (start 110.81 108.440944) (end 110.814387 108.402003) (width 0.109) (layer "In6.Cu") (net 37))
  (segment (start 111.575889 108.304124) (end 111.60907 108.283275) (width 0.109) (layer "In6.Cu") (net 37))
  (segment (start 112.735 109.234056) (end 112.773941 109.229668) (width 0.109) (layer "In6.Cu") (net 37))
  (segment (start 111.47182 109.168166) (end 111.492669 109.134985) (width 0.109) (layer "In6.Cu") (net 37))
  (segment (start 115.78256 107.447934) (end 115.817867 107.430931) (width 0.109) (layer "In6.Cu") (net 37))
  (segment (start 115.229784 108.025219) (end 115.229784 108.025216) (width 0.109) (layer "In6.Cu") (net 37))
  (segment (start 114.505 108.75) (end 114.611065 108.643935) (width 0.109) (layer "In6.Cu") (net 37))
  (segment (start 114.980611 107.782249) (end 115.011248 107.806683) (width 0.109) (layer "In6.Cu") (net 37))
  (segment (start 110.105612 109.097997) (end 110.11 109.059056) (width 0.109) (layer "In6.Cu") (net 37))
  (segment (start 108.705612 109.097997) (end 108.71 109.059056) (width 0.109) (layer "In6.Cu") (net 37))
  (segment (start 110.673941 109.229668) (end 110.710929 109.216725) (width 0.109) (layer "In6.Cu") (net 37))
  (segment (start 108.71 109.059056) (end 108.71 108.440944) (width 0.109) (layer "In6.Cu") (net 37))
  (segment (start 111.09411 108.304124) (end 111.12182 108.331834) (width 0.109) (layer "In6.Cu") (net 37))
  (segment (start 115.848504 107.406499) (end 117.6 105.655) (width 0.109) (layer "In6.Cu") (net 37))
  (segment (start 114.677009 108.602499) (end 114.715214 108.593779) (width 0.109) (layer "In6.Cu") (net 37))
  (segment (start 114.983981 108.763159) (end 115.019288 108.780162) (width 0.109) (layer "In6.Cu") (net 37))
  (segment (start 111.898179 109.168166) (end 111.925889 109.195876) (width 0.109) (layer "In6.Cu") (net 37))
  (segment (start 109.764387 109.097997) (end 109.77733 109.134985) (width 0.109) (layer "In6.Cu") (net 37))
  (segment (start 115.057493 108.788882) (end 115.096681 108.788882) (width 0.109) (layer "In6.Cu") (net 37))
  (segment (start 92.445 110.675) (end 94.341584 110.675) (width 0.109) (layer "In6.Cu") (net 37))
  (segment (start 112.892669 109.134985) (end 112.905612 109.097997) (width 0.109) (layer "In6.Cu") (net 37))
  (segment (start 115.720239 108.213112) (end 115.737241 108.177806) (width 0.109) (layer "In6.Cu") (net 37))
  (segment (start 115.208581 107.455043) (end 115.208581 107.415855) (width 0.109) (layer "In6.Cu") (net 37))
  (segment (start 112.17182 109.168166) (end 112.192669 109.134985) (width 0.109) (layer "In6.Cu") (net 37))
  (segment (start 109.77733 109.134985) (end 109.798179 109.168166) (width 0.109) (layer "In6.Cu") (net 37))
  (segment (start 115.720239 108.026901) (end 115.695806 107.996263) (width 0.109) (layer "In6.Cu") (net 37))
  (segment (start 115.200831 108.491238) (end 114.763761 108.054169) (width 0.109) (layer "In6.Cu") (net 37))
  (segment (start 108.29411 108.304124) (end 108.32182 108.331834) (width 0.109) (layer "In6.Cu") (net 37))
  (segment (start 110.74411 109.195876) (end 110.77182 109.168166) (width 0.109) (layer "In6.Cu") (net 37))
  (segment (start 111.996058 109.229668) (end 112.035 109.234056) (width 0.109) (layer "In6.Cu") (net 37))
  (segment (start 108.342669 108.365015) (end 108.355612 108.402003) (width 0.109) (layer "In6.Cu") (net 37))
  (segment (start 110.42182 108.331834) (end 110.442669 108.365015) (width 0.109) (layer "In6.Cu") (net 37))
  (segment (start 115.440279 107.270272) (end 115.475587 107.287273) (width 0.109) (layer "In6.Cu") (net 37))
  (segment (start 108.01 109.059056) (end 108.01 108.440944) (width 0.109) (layer "In6.Cu") (net 37))
  (segment (start 109.064387 109.097997) (end 109.07733 109.134985) (width 0.109) (layer "In6.Cu") (net 37))
  (segment (start 115.229784 108.025216) (end 115.448319 108.243751) (width 0.109) (layer "In6.Cu") (net 37))
  (segment (start 96.266584 108.75) (end 107.485 108.75) (width 0.109) (layer "In6.Cu") (net 37))
  (segment (start 115.591657 108.293907) (end 115.629862 108.285187) (width 0.109) (layer "In6.Cu") (net 37))
  (segment (start 110.246058 108.270332) (end 110.285 108.265944) (width 0.109) (layer "In6.Cu") (net 37))
  (segment (start 94.341584 110.675) (end 96.266584 108.75) (width 0.109) (layer "In6.Cu") (net 37))
  (segment (start 110.814387 108.402003) (end 110.82733 108.365015) (width 0.109) (layer "In6.Cu") (net 37))
  (segment (start 110.498179 109.168166) (end 110.525889 109.195876) (width 0.109) (layer "In6.Cu") (net 37))
  (segment (start 110.635 109.234056) (end 110.673941 109.229668) (width 0.109) (layer "In6.Cu") (net 37))
  (segment (start 114.715214 108.593779) (end 114.754402 108.593779) (width 0.109) (layer "In6.Cu") (net 37))
  (segment (start 107.66 108.925) (end 107.66 109.059056) (width 0.109) (layer "In6.Cu") (net 37))
  (segment (start 113.62733 108.365015) (end 113.648179 108.331834) (width 0.109) (layer "In6.Cu") (net 37))
  (segment (start 109.50907 108.283275) (end 109.546058 108.270332) (width 0.109) (layer "In6.Cu") (net 37))
  (segment (start 108.885 108.265944) (end 108.923941 108.270332) (width 0.109) (layer "In6.Cu") (net 37))
  (segment (start 111.505612 109.097997) (end 111.51 109.059056) (width 0.109) (layer "In6.Cu") (net 37))
  (segment (start 113.264387 109.097997) (end 113.27733 109.134985) (width 0.109) (layer "In6.Cu") (net 37))
  (segment (start 117.825 98.78) (end 117.556492 98.511492) (width 0.109) (layer "In6.Cu") (net 37))
  (segment (start 115.631655 107.430931) (end 115.666962 107.447934) (width 0.109) (layer "In6.Cu") (net 37))
  (segment (start 115.225264 108.708087) (end 115.242266 108.672781) (width 0.109) (layer "In6.Cu") (net 37))
  (segment (start 110.092669 109.134985) (end 110.105612 109.097997) (width 0.109) (layer "In6.Cu") (net 37))
  (segment (start 107.655612 108.886058) (end 107.66 108.925) (width 0.109) (layer "In6.Cu") (net 37))
  (segment (start 110.148179 108.331834) (end 110.175889 108.304124) (width 0.109) (layer "In6.Cu") (net 37))
  (segment (start 110.875889 108.304124) (end 110.90907 108.283275) (width 0.109) (layer "In6.Cu") (net 37))
  (segment (start 110.464387 109.097997) (end 110.47733 109.134985) (width 0.109) (layer "In6.Cu") (net 37))
  (segment (start 111.164387 109.097997) (end 111.17733 109.134985) (width 0.109) (layer "In6.Cu") (net 37))
  (segment (start 109.755612 108.402003) (end 109.76 108.440944) (width 0.109) (layer "In6.Cu") (net 37))
  (segment (start 114.722324 107.872627) (end 114.739328 107.83732) (width 0.109) (layer "In6.Cu") (net 37))
  (segment (start 109.76 109.059056) (end 109.764387 109.097997) (width 0.109) (layer "In6.Cu") (net 37))
  (segment (start 111.25907 109.216725) (end 111.296058 109.229668) (width 0.109) (layer "In6.Cu") (net 37))
  (segment (start 115.745961 108.100413) (end 115.737241 108.062208) (width 0.109) (layer "In6.Cu") (net 37))
  (segment (start 113.26 109.059056) (end 113.264387 109.097997) (width 0.109) (layer "In6.Cu") (net 37))
  (segment (start 111.95907 109.216725) (end 111.996058 109.229668) (width 0.109) (layer "In6.Cu") (net 37))
  (segment (start 117.6 99.43) (end 117.825 99.205) (width 0.109) (layer "In6.Cu") (net 37))
  (segment (start 108.36 108.440944) (end 108.36 109.059056) (width 0.109) (layer "In6.Cu") (net 37))
  (segment (start 109.06 108.440944) (end 109.06 109.059056) (width 0.109) (layer "In6.Cu") (net 37))
  (segment (start 107.698179 109.168166) (end 107.725889 109.195876) (width 0.109) (layer "In6.Cu") (net 37))
  (segment (start 115.242266 108.672781) (end 115.250986 108.634576) (width 0.109) (layer "In6.Cu") (net 37))
  (segment (start 109.02182 108.331834) (end 109.042669 108.365015) (width 0.109) (layer "In6.Cu") (net 37))
  (segment (start 109.310929 109.216725) (end 109.34411 109.195876) (width 0.109) (layer "In6.Cu") (net 37))
  (segment (start 114.953343 108.738726) (end 114.983981 108.763159) (width 0.109) (layer "In6.Cu") (net 37))
  (segment (start 114.096058 108.745613) (end 114.135 108.75) (width 0.109) (layer "In6.Cu") (net 37))
  (segment (start 108.846058 108.270332) (end 108.885 108.265944) (width 0.109) (layer "In6.Cu") (net 37))
  (segment (start 115.402075 107.261551) (end 115.440279 107.270272) (width 0.109) (layer "In6.Cu") (net 37))
  (segment (start 113.35907 109.216725) (end 113.396058 109.229668) (width 0.109) (layer "In6.Cu") (net 37))
  (segment (start 109.06 109.059056) (end 109.064387 109.097997) (width 0.109) (layer "In6.Cu") (net 37))
  (segment (start 108.80907 108.283275) (end 108.846058 108.270332) (width 0.109) (layer "In6.Cu") (net 37))
  (segment (start 113.70907 108.283275) (end 113.746058 108.270332) (width 0.109) (layer "In6.Cu") (net 37))
  (segment (start 111.335 109.234056) (end 111.373941 109.229668) (width 0.109) (layer "In6.Cu") (net 37))
  (segment (start 111.82182 108.331834) (end 111.842669 108.365015) (width 0.109) (layer "In6.Cu") (net 37))
  (segment (start 115.514264 108.285187) (end 115.552469 108.293907) (width 0.109) (layer "In6.Cu") (net 37))
  (segment (start 112.214387 108.402003) (end 112.22733 108.365015) (width 0.109) (layer "In6.Cu") (net 37))
  (segment (start 113.605612 109.097997) (end 113.61 109.059056) (width 0.109) (layer "In6.Cu") (net 37))
  (segment (start 114.713605 107.910831) (end 114.722324 107.872627) (width 0.109) (layer "In6.Cu") (net 37))
  (segment (start 108.425889 109.195876) (end 108.45907 109.216725) (width 0.109) (layer "In6.Cu") (net 37))
  (segment (start 110.985 108.265944) (end 111.023941 108.270332) (width 0.109) (layer "In6.Cu") (net 37))
  (segment (start 110.285 108.265944) (end 110.323941 108.270332) (width 0.109) (layer "In6.Cu") (net 37))
  (segment (start 114.907099 107.756527) (end 114.945303 107.765248) (width 0.109) (layer "In6.Cu") (net 37))
  (segment (start 113.57182 109.168166) (end 113.592669 109.134985) (width 0.109) (layer "In6.Cu") (net 37))
  (segment (start 108.223941 108.270332) (end 108.260929 108.283275) (width 0.109) (layer "In6.Cu") (net 37))
  (segment (start 114.135 108.75) (end 114.505 108.75) (width 0.109) (layer "In6.Cu") (net 37))
  (segment (start 109.41 109.059056) (end 109.41 108.440944) (width 0.109) (layer "In6.Cu") (net 37))
  (segment (start 115.250986 108.634576) (end 115.250986 108.595388) (width 0.109) (layer "In6.Cu") (net 37))
  (segment (start 110.114387 108.402003) (end 110.12733 108.365015) (width 0.109) (layer "In6.Cu") (net 37))
  (segment (start 110.11 108.440944) (end 110.114387 108.402003) (width 0.109) (layer "In6.Cu") (net 37))
  (segment (start 107.725889 109.195876) (end 107.75907 109.216725) (width 0.109) (layer "In6.Cu") (net 37))
  (segment (start 108.014387 108.402003) (end 108.02733 108.365015) (width 0.109) (layer "In6.Cu") (net 37))
  (segment (start 115.478957 108.268184) (end 115.514264 108.285187) (width 0.109) (layer "In6.Cu") (net 37))
  (segment (start 109.07733 109.134985) (end 109.098179 109.168166) (width 0.109) (layer "In6.Cu") (net 37))
  (segment (start 109.76 108.440944) (end 109.76 109.059056) (width 0.109) (layer "In6.Cu") (net 37))
  (segment (start 113.823941 108.270332) (end 113.860929 108.283275) (width 0.109) (layer "In6.Cu") (net 37))
  (segment (start 115.258737 107.559193) (end 115.234303 107.528556) (width 0.109) (layer "In6.Cu") (net 37))
  (segment (start 109.414387 108.402003) (end 109.42733 108.365015) (width 0.109) (layer "In6.Cu") (net 37))
  (segment (start 113.473941 109.229668) (end 113.510929 109.216725) (width 0.109) (layer "In6.Cu") (net 37))
  (segment (start 89.85 111.13) (end 90.177685 110.802315) (width 0.109) (layer "In6.Cu") (net 37))
  (segment (start 111.060929 108.283275) (end 111.09411 108.304124) (width 0.109) (layer "In6.Cu") (net 37))
  (segment (start 107.523941 108.754387) (end 107.560929 108.76733) (width 0.109) (layer "In6.Cu") (net 37))
  (segment (start 108.775889 108.304124) (end 108.80907 108.283275) (width 0.109) (layer "In6.Cu") (net 37))
  (segment (start 109.37182 109.168166) (end 109.392669 109.134985) (width 0.109) (layer "In6.Cu") (net 37))
  (segment (start 115.737241 108.062208) (end 115.720239 108.026901) (width 0.109) (layer "In6.Cu") (net 37))
  (segment (start 109.896058 109.229668) (end 109.935 109.234056) (width 0.109) (layer "In6.Cu") (net 37))
  (segment (start 111.44411 109.195876) (end 111.47182 109.168166) (width 0.109) (layer "In6.Cu") (net 37))
  (segment (start 115.506224 107.311707) (end 115.601016 107.406499) (width 0.109) (layer "In6.Cu") (net 37))
  (segment (start 114.76376 107.806683) (end 114.794399 107.78225) (width 0.109) (layer "In6.Cu") (net 37))
  (segment (start 109.392669 109.134985) (end 109.405612 109.097997) (width 0.109) (layer "In6.Cu") (net 37))
  (segment (start 112.460929 108.283275) (end 112.49411 108.304124) (width 0.109) (layer "In6.Cu") (net 37))
  (segment (start 110.12733 108.365015) (end 110.148179 108.331834) (width 0.109) (layer "In6.Cu") (net 37))
  (segment (start 114.05907 108.73267) (end 114.096058 108.745613) (width 0.109) (layer "In6.Cu") (net 37))
  (segment (start 107.992669 109.134985) (end 108.005612 109.097997) (width 0.109) (layer "In6.Cu") (net 37))
  (segment (start 115.134886 108.780162) (end 115.170193 108.763159) (width 0.109) (layer "In6.Cu") (net 37))
  (segment (start 111.023941 108.270332) (end 111.060929 108.283275) (width 0.109) (layer "In6.Cu") (net 37))
  (segment (start 107.59411 108.788179) (end 107.62182 108.815889) (width 0.109) (layer "In6.Cu") (net 37))
  (segment (start 111.86 108.440944) (end 111.86 109.059056) (width 0.109) (layer "In6.Cu") (net 37))
  (segment (start 113.085 108.265944) (end 113.123941 108.270332) (width 0.109) (layer "In6.Cu") (net 37))
  (segment (start 115.737241 108.177806) (end 115.745961 108.139601) (width 0.109) (layer "In6.Cu") (net 37))
  (segment (start 109.15907 109.216725) (end 109.196058 109.229668) (width 0.109) (layer "In6.Cu") (net 37))
  (segment (start 110.710929 109.216725) (end 110.74411 109.195876) (width 0.109) (layer "In6.Cu") (net 37))
  (segment (start 108.146058 108.270332) (end 108.185 108.265944) (width 0.109) (layer "In6.Cu") (net 37))
  (segment (start 115.665168 108.268184) (end 115.695806 108.243751) (width 0.109) (layer "In6.Cu") (net 37))
  (segment (start 107.664387 109.097997) (end 107.67733 109.134985) (width 0.109) (layer "In6.Cu") (net 37))
  (segment (start 90.925 112.75) (end 90.475 112.3) (width 0.109) (layer "In6.Cu") (net 37))
  (segment (start 110.455612 108.402003) (end 110.46 108.440944) (width 0.109) (layer "In6.Cu") (net 37))
  (segment (start 112.975889 108.304124) (end 113.00907 108.283275) (width 0.109) (layer "In6.Cu") (net 37))
  (segment (start 109.125889 109.195876) (end 109.15907 109.216725) (width 0.109) (layer "In6.Cu") (net 37))
  (segment (start 108.364387 109.097997) (end 108.37733 109.134985) (width 0.109) (layer "In6.Cu") (net 37))
  (segment (start 110.07182 109.168166) (end 110.092669 109.134985) (width 0.109) (layer "In6.Cu") (net 37))
  (segment (start 114.867911 107.756527) (end 114.907099 107.756527) (width 0.109) (layer "In6.Cu") (net 37))
  (segment (start 116.9 99.805) (end 117.275 99.43) (width 0.109) (layer "In6.Cu") (net 37))
  (segment (start 114.792607 108.602499) (end 114.827914 108.619501) (width 0.109) (layer "In6.Cu") (net 37))
  (segment (start 92.164289 112.75) (end 90.925 112.75) (width 0.109) (layer "In6.Cu") (net 37))
  (segment (start 117.6 105.655) (end 117.6 101.88) (width 0.109) (layer "In6.Cu") (net 37))
  (segment (start 112.248179 108.331834) (end 112.275889 108.304124) (width 0.109) (layer "In6.Cu") (net 37))
  (segment (start 113.396058 109.229668) (end 113.435 109.234056) (width 0.109) (layer "In6.Cu") (net 37))
  (segment (start 110.77182 109.168166) (end 110.792669 109.134985) (width 0.109) (layer "In6.Cu") (net 37))
  (segment (start 111.16 109.059056) (end 111.164387 109.097997) (width 0.109) (layer "In6.Cu") (net 37))
  (segment (start 109.098179 109.168166) (end 109.125889 109.195876) (width 0.109) (layer "In6.Cu") (net 37))
  (segment (start 113.510929 109.216725) (end 113.54411 109.195876) (width 0.109) (layer "In6.Cu") (net 37))
  (segment (start 107.67733 109.134985) (end 107.698179 109.168166) (width 0.109) (layer "In6.Cu") (net 37))
  (segment (start 110.442669 108.365015) (end 110.455612 108.402003) (width 0.109) (layer "In6.Cu") (net 37))
  (segment (start 112.56 108.440944) (end 112.56 109.059056) (width 0.109) (layer "In6.Cu") (net 37))
  (segment (start 112.21 108.440944) (end 112.214387 108.402003) (width 0.109) (layer "In6.Cu") (net 37))
  (segment (start 113.942669 108.365015) (end 113.955612 108.402003) (width 0.109) (layer "In6.Cu") (net 37))
  (segment (start 114.858552 108.643935) (end 114.953343 108.738726) (width 0.109) (layer "In6.Cu") (net 37))
  (segment (start 111.373941 109.229668) (end 111.410929 109.216725) (width 0.109) (layer "In6.Cu") (net 37))
  (segment (start 109.935 109.234056) (end 109.973941 109.229668) (width 0.109) (layer "In6.Cu") (net 37))
  (segment (start 114.641703 108.619501) (end 114.677009 108.602499) (width 0.109) (layer "In6.Cu") (net 37))
  (segment (start 115.324681 107.270272) (end 115.362887 107.261551) (width 0.109) (layer "In6.Cu") (net 37))
  (segment (start 110.805612 109.097997) (end 110.81 109.059056) (width 0.109) (layer "In6.Cu") (net 37))
  (segment (start 115.817867 107.430931) (end 115.848504 107.406499) (width 0.109) (layer "In6.Cu") (net 37))
  (segment (start 112.49411 108.304124) (end 112.52182 108.331834) (width 0.109) (layer "In6.Cu") (net 37))
  (segment (start 109.34411 109.195876) (end 109.37182 109.168166) (width 0.109) (layer "In6.Cu") (net 37))
  (segment (start 112.905612 109.097997) (end 112.91 109.059056) (width 0.109) (layer "In6.Cu") (net 37))
  (segment (start 115.011248 107.806683) (end 115.229784 108.025219) (width 0.109) (layer "In6.Cu") (net 37))
  (segment (start 111.723941 108.270332) (end 111.760929 108.283275) (width 0.109) (layer "In6.Cu") (net 37))
  (segment (start 109.69411 108.304124) (end 109.72182 108.331834) (width 0.109) (layer "In6.Cu") (net 37))
  (segment (start 113.298179 109.168166) (end 113.325889 109.195876) (width 0.109) (layer "In6.Cu") (net 37))
  (segment (start 110.90907 108.283275) (end 110.946058 108.270332) (width 0.109) (layer "In6.Cu") (net 37))
  (segment (start 112.948179 108.331834) (end 112.975889 108.304124) (width 0.109) (layer "In6.Cu") (net 37))
  (segment (start 117.556492 98.511492) (end 116.713396 98.511492) (width 0.109) (layer "In6.Cu") (net 37))
  (segment (start 112.275889 108.304124) (end 112.30907 108.283275) (width 0.109) (layer "In6.Cu") (net 37))
  (segment (start 108.67182 109.168166) (end 108.692669 109.134985) (width 0.109) (layer "In6.Cu") (net 37))
  (segment (start 112.110929 109.216725) (end 112.14411 109.195876) (width 0.109) (layer "In6.Cu") (net 37))
  (segment (start 113.89411 108.304124) (end 113.92182 108.331834) (width 0.109) (layer "In6.Cu") (net 37))
  (segment (start 115.552469 108.293907) (end 115.591657 108.293907) (width 0.109) (layer "In6.Cu") (net 37))
  (segment (start 111.51 109.059056) (end 111.51 108.440944) (width 0.109) (layer "In6.Cu") (net 37))
  (segment (start 113.046058 108.270332) (end 113.085 108.265944) (width 0.109) (layer "In6.Cu") (net 37))
  (segment (start 110.04411 109.195876) (end 110.07182 109.168166) (width 0.109) (layer "In6.Cu") (net 37))
  (segment (start 114.739328 107.83732) (end 114.76376 107.806683) (width 0.109) (layer "In6.Cu") (net 37))
  (segment (start 113.785 108.265944) (end 113.823941 108.270332) (width 0.109) (layer "In6.Cu") (net 37))
  (segment (start 108.71 108.440944) (end 108.714387 108.402003) (width 0.109) (layer "In6.Cu") (net 37))
  (segment (start 113.19411 108.304124) (end 113.22182 108.331834) (width 0.109) (layer "In6.Cu") (net 37))
  (segment (start 115.744354 107.456655) (end 115.78256 107.447934) (width 0.109) (layer "In6.Cu") (net 37))
  (segment (start 112.385 108.265944) (end 112.423941 108.270332) (width 0.109) (layer "In6.Cu") (net 37))
  (segment (start 111.864387 109.097997) (end 111.87733 109.134985) (width 0.109) (layer "In6.Cu") (net 37))
  (segment (start 112.598179 109.168166) (end 112.625889 109.195876) (width 0.109) (layer "In6.Cu") (net 37))
  (segment (start 110.175889 108.304124) (end 110.20907 108.283275) (width 0.109) (layer "In6.Cu") (net 37))
  (segment (start 110.55907 109.216725) (end 110.596058 109.229668) (width 0.109) (layer "In6.Cu") (net 37))
  (segment (start 112.192669 109.134985) (end 112.205612 109.097997) (width 0.109) (layer "In6.Cu") (net 37))
  (segment (start 113.614387 108.402003) (end 113.62733 108.365015) (width 0.109) (layer "In6.Cu") (net 37))
  (segment (start 108.185 108.265944) (end 108.223941 108.270332) (width 0.109) (layer "In6.Cu") (net 37))
  (segment (start 115.208581 107.415855) (end 115.2173 107.377651) (width 0.109) (layer "In6.Cu") (net 37))
  (segment (start 110.360929 108.283275) (end 110.39411 108.304124) (width 0.109) (layer "In6.Cu") (net 37))
  (segment (start 114.794399 107.78225) (end 114.829705 107.765248) (width 0.109) (layer "In6.Cu") (net 37))
  (segment (start 110.792669 109.134985) (end 110.805612 109.097997) (width 0.109) (layer "In6.Cu") (net 37))
  (segment (start 109.973941 109.229668) (end 110.010929 109.216725) (width 0.109) (layer "In6.Cu") (net 37))
  (segment (start 108.45907 109.216725) (end 108.496058 109.229668) (width 0.109) (layer "In6.Cu") (net 37))
  (segment (start 108.573941 109.229668) (end 108.610929 109.216725) (width 0.109) (layer "In6.Cu") (net 37))
  (segment (start 109.475889 108.304124) (end 109.50907 108.283275) (width 0.109) (layer "In6.Cu") (net 37))
  (segment (start 115.258736 107.311707) (end 115.289375 107.287274) (width 0.109) (layer "In6.Cu") (net 37))
  (segment (start 113.998179 108.684111) (end 114.025889 108.711821) (width 0.109) (layer "In6.Cu") (net 37))
  (segment (start 111.52733 108.365015) (end 111.548179 108.331834) (width 0.109) (layer "In6.Cu") (net 37))
  (segment (start 111.760929 108.283275) (end 111.79411 108.304124) (width 0.109) (layer "In6.Cu") (net 37))
  (segment (start 107.66 109.059056) (end 107.664387 109.097997) (width 0.109) (layer "In6.Cu") (net 37))
  (segment (start 107.62182 108.815889) (end 107.642669 108.84907) (width 0.109) (layer "In6.Cu") (net 37))
  (segment (start 112.564387 109.097997) (end 112.57733 109.134985) (width 0.109) (layer "In6.Cu") (net 37))
  (segment (start 113.22182 108.331834) (end 113.242669 108.365015) (width 0.109) (layer "In6.Cu") (net 37))
  (segment (start 117.6 101.88) (end 116.9 101.18) (width 0.109) (layer "In6.Cu") (net 37))
  (segment (start 111.79411 108.304124) (end 111.82182 108.331834) (width 0.109) (layer "In6.Cu") (net 37))
  (segment (start 110.946058 108.270332) (end 110.985 108.265944) (width 0.109) (layer "In6.Cu") (net 37))
  (segment (start 113.242669 108.365015) (end 113.255612 108.402003) (width 0.109) (layer "In6.Cu") (net 37))
  (segment (start 115.242266 108.557183) (end 115.225264 108.521876) (width 0.109) (layer "In6.Cu") (net 37))
  (segment (start 113.61 109.059056) (end 113.61 108.440944) (width 0.109) (layer "In6.Cu") (net 37))
  (segment (start 111.685 108.265944) (end 111.723941 108.270332) (width 0.109) (layer "In6.Cu") (net 37))
  (segment (start 112.65907 109.216725) (end 112.696058 109.229668) (width 0.109) (layer "In6.Cu") (net 37))
  (segment (start 114.713605 107.950019) (end 114.713605 107.910831) (width 0.109) (layer "In6.Cu") (net 37))
  (segment (start 90.475 112.3) (end 89.95 112.3) (width 0.109) (layer "In6.Cu") (net 37))
  (segment (start 111.16 108.440944) (end 111.16 109.059056) (width 0.109) (layer "In6.Cu") (net 37))
  (segment (start 113.160929 108.283275) (end 113.19411 108.304124) (width 0.109) (layer "In6.Cu") (net 37))
  (segment (start 111.225889 109.195876) (end 111.25907 109.216725) (width 0.109) (layer "In6.Cu") (net 37))
  (segment (start 112.773941 109.229668) (end 112.810929 109.216725) (width 0.109) (layer "In6.Cu") (net 37))
  (segment (start 109.405612 109.097997) (end 109.41 109.059056) (width 0.109) (layer "In6.Cu") (net 37))
  (segment (start 111.925889 109.195876) (end 111.95907 109.216725) (width 0.109) (layer "In6.Cu") (net 37))
  (segment (start 110.323941 108.270332) (end 110.360929 108.283275) (width 0.109) (layer "In6.Cu") (net 37))
  (segment (start 109.742669 108.365015) (end 109.755612 108.402003) (width 0.109) (layer "In6.Cu") (net 37))
  (segment (start 113.592669 109.134985) (end 113.605612 109.097997) (width 0.109) (layer "In6.Cu") (net 37))
  (segment (start 115.666962 107.447934) (end 115.705166 107.456655) (width 0.109) (layer "In6.Cu") (net 37))
  (segment (start 109.798179 109.168166) (end 109.825889 109.195876) (width 0.109) (layer "In6.Cu") (net 37))
  (segment (start 107.910929 109.216725) (end 107.94411 109.195876) (width 0.109) (layer "In6.Cu") (net 37))
  (segment (start 112.035 109.234056) (end 112.073941 109.229668) (width 0.109) (layer "In6.Cu") (net 37))
  (segment (start 108.610929 109.216725) (end 108.64411 109.195876) (width 0.109) (layer "In6.Cu") (net 37))
  (segment (start 109.825889 109.195876) (end 109.85907 109.216725) (width 0.109) (layer "In6.Cu") (net 37))
  (segment (start 115.225264 108.521876) (end 115.200831 108.491238) (width 0.109) (layer "In6.Cu") (net 37))
  (segment (start 109.196058 109.229668) (end 109.235 109.234056) (width 0.109) (layer "In6.Cu") (net 37))
  (segment (start 115.475587 107.287273) (end 115.506224 107.311707) (width 0.109) (layer "In6.Cu") (net 37))
  (segment (start 108.714387 108.402003) (end 108.72733 108.365015) (width 0.109) (layer "In6.Cu") (net 37))
  (segment (start 110.46 108.440944) (end 110.46 109.059056) (width 0.109) (layer "In6.Cu") (net 37))
  (segment (start 109.042669 108.365015) (end 109.055612 108.402003) (width 0.109) (layer "In6.Cu") (net 37))
  (segment (start 117.275 99.43) (end 117.6 99.43) (width 0.109) (layer "In6.Cu") (net 37))
  (segment (start 109.448179 108.331834) (end 109.475889 108.304124) (width 0.109) (layer "In6.Cu") (net 37))
  (segment (start 111.155612 108.402003) (end 111.16 108.440944) (width 0.109) (layer "In6.Cu") (net 37))
  (segment (start 110.47733 109.134985) (end 110.498179 109.168166) (width 0.109) (layer "In6.Cu") (net 37))
  (segment (start 108.398179 109.168166) (end 108.425889 109.195876) (width 0.109) (layer "In6.Cu") (net 37))
  (segment (start 109.85907 109.216725) (end 109.896058 109.229668) (width 0.109) (layer "In6.Cu") (net 37))
  (segment (start 115.695806 108.243751) (end 115.720239 108.213112) (width 0.109) (layer "In6.Cu") (net 37))
  (segment (start 113.27733 109.134985) (end 113.298179 109.168166) (width 0.109) (layer "In6.Cu") (net 37))
  (segment (start 113.964387 108.613942) (end 113.97733 108.65093) (width 0.109) (layer "In6.Cu") (net 37))
  (segment (start 112.423941 108.270332) (end 112.460929 108.283275) (width 0.109) (layer "In6.Cu") (net 37))
  (segment (start 112.21 109.059056) (end 112.21 108.440944) (width 0.109) (layer "In6.Cu") (net 37))
  (segment (start 115.289375 107.287274) (end 115.324681 107.270272) (width 0.109) (layer "In6.Cu") (net 37))
  (segment (start 108.923941 108.270332) (end 108.960929 108.283275) (width 0.109) (layer "In6.Cu") (net 37))
  (segment (start 113.675889 108.304124) (end 113.70907 108.283275) (width 0.109) (layer "In6.Cu") (net 37))
  (segment (start 112.84411 109.195876) (end 112.87182 109.168166) (width 0.109) (layer "In6.Cu") (net 37))
  (segment (start 110.46 109.059056) (end 110.464387 109.097997) (width 0.109) (layer "In6.Cu") (net 37))
  (segment (start 108.692669 109.134985) (end 108.705612 109.097997) (width 0.109) (layer "In6.Cu") (net 37))
  (segment (start 109.546058 108.270332) (end 109.585 108.265944) (width 0.109) (layer "In6.Cu") (net 37))
  (segment (start 108.02733 108.365015) (end 108.048179 108.331834) (width 0.109) (layer "In6.Cu") (net 37))
  (segment (start 114.739327 108.023532) (end 114.722324 107.988225) (width 0.109) (layer "In6.Cu") (net 37))
  (segment (start 111.51 108.440944) (end 111.514387 108.402003) (width 0.109) (layer "In6.Cu") (net 37))
  (segment (start 108.960929 108.283275) (end 108.99411 108.304124) (width 0.109) (layer "In6.Cu") (net 37))
  (segment (start 112.30907 108.283275) (end 112.346058 108.270332) (width 0.109) (layer "In6.Cu") (net 37))
  (segment (start 109.235 109.234056) (end 109.273941 109.229668) (width 0.109) (layer "In6.Cu") (net 37))
  (segment (start 107.75907 109.216725) (end 107.796058 109.229668) (width 0.109) (layer "In6.Cu") (net 37))
  (segment (start 109.055612 108.402003) (end 109.06 108.440944) (width 0.109) (layer "In6.Cu") (net 37))
  (segment (start 116.9 101.18) (end 116.9 99.805) (width 0.109) (layer "In6.Cu") (net 37))
  (segment (start 113.746058 108.270332) (end 113.785 108.265944) (width 0.109) (layer "In6.Cu") (net 37))
  (segment (start 109.72182 108.331834) (end 109.742669 108.365015) (width 0.109) (layer "In6.Cu") (net 37))
  (segment (start 107.796058 109.229668) (end 107.835 109.234056) (width 0.109) (layer "In6.Cu") (net 37))
  (segment (start 113.955612 108.402003) (end 113.96 108.440944) (width 0.109) (layer "In6.Cu") (net 37))
  (segment (start 112.92733 108.365015) (end 112.948179 108.331834) (width 0.109) (layer "In6.Cu") (net 37))
  (segment (start 112.14411 109.195876) (end 112.17182 109.168166) (width 0.109) (layer "In6.Cu") (net 37))
  (segment (start 109.41 108.440944) (end 109.414387 108.402003) (width 0.109) (layer "In6.Cu") (net 37))
  (segment (start 111.842669 108.365015) (end 111.855612 108.402003) (width 0.109) (layer "In6.Cu") (net 37))
  (segment (start 112.87182 109.168166) (end 112.892669 109.134985) (width 0.109) (layer "In6.Cu") (net 37))
  (segment (start 107.485 108.75) (end 107.523941 108.754387) (width 0.109) (layer "In6.Cu") (net 37))
  (segment (start 112.542669 108.365015) (end 112.555612 108.402003) (width 0.109) (layer "In6.Cu") (net 37))
  (segment (start 113.435 109.234056) (end 113.473941 109.229668) (width 0.109) (layer "In6.Cu") (net 37))
  (segment (start 113.860929 108.283275) (end 113.89411 108.304124) (width 0.109) (layer "In6.Cu") (net 37))
  (segment (start 107.97182 109.168166) (end 107.992669 109.134985) (width 0.109) (layer "In6.Cu") (net 37))
  (segment (start 107.94411 109.195876) (end 107.97182 109.168166) (width 0.109) (layer "In6.Cu") (net 37))
  (segment (start 92.589289 113.175) (end 92.164289 112.75) (width 0.109) (layer "In6.Cu") (net 37))
  (segment (start 92.84 113.175) (end 92.589289 113.175) (width 0.109) (layer "In6.Cu") (net 37))
  (segment (start 108.99411 108.304124) (end 109.02182 108.331834) (width 0.109) (layer "In6.Cu") (net 37))
  (segment (start 111.17733 109.134985) (end 111.198179 109.168166) (width 0.109) (layer "In6.Cu") (net 37))
  (segment (start 114.763761 108.054169) (end 114.739327 108.023532) (width 0.109) (layer "In6.Cu") (net 37))
  (segment (start 111.410929 109.216725) (end 111.44411 109.195876) (width 0.109) (layer "In6.Cu") (net 37))
  (segment (start 109.273941 109.229668) (end 109.310929 109.216725) (width 0.109) (layer "In6.Cu") (net 37))
  (segment (start 112.625889 109.195876) (end 112.65907 109.216725) (width 0.109) (layer "In6.Cu") (net 37))
  (segment (start 110.81 109.059056) (end 110.81 108.440944) (width 0.109) (layer "In6.Cu") (net 37))
  (segment (start 115.745961 108.139601) (end 115.745961 108.100413) (width 0.109) (layer "In6.Cu") (net 37))
  (segment (start 113.26 108.440944) (end 113.26 109.059056) (width 0.109) (layer "In6.Cu") (net 37))
  (segment (start 112.56 109.059056) (end 112.564387 109.097997) (width 0.109) (layer "In6.Cu") (net 37))
  (segment (start 112.52182 108.331834) (end 112.542669 108.365015) (width 0.109) (layer "In6.Cu") (net 37))
  (segment (start 112.91 109.059056) (end 112.91 108.440944) (width 0.109) (layer "In6.Cu") (net 37))
  (segment (start 113.96 108.575) (end 113.964387 108.613942) (width 0.109) (layer "In6.Cu") (net 37))
  (segment (start 115.2173 107.493249) (end 115.208581 107.455043) (width 0.109) (layer "In6.Cu") (net 37))
  (segment (start 111.87733 109.134985) (end 111.898179 109.168166) (width 0.109) (layer "In6.Cu") (net 37))
  (segment (start 110.82733 108.365015) (end 110.848179 108.331834) (width 0.109) (layer "In6.Cu") (net 37))
  (segment (start 113.97733 108.65093) (end 113.998179 108.684111) (width 0.109) (layer "In6.Cu") (net 37))
  (segment (start 111.142669 108.365015) (end 111.155612 108.402003) (width 0.109) (layer "In6.Cu") (net 37))
  (segment (start 111.12182 108.331834) (end 111.142669 108.365015) (width 0.109) (layer "In6.Cu") (net 37))
  (segment (start 115.705166 107.456655) (end 115.744354 107.456655) (width 0.109) (layer "In6.Cu") (net 37))
  (segment (start 113.00907 108.283275) (end 113.046058 108.270332) (width 0.109) (layer "In6.Cu") (net 37))
  (segment (start 108.37733 109.134985) (end 108.398179 109.168166) (width 0.109) (layer "In6.Cu") (net 37))
  (segment (start 110.11 109.059056) (end 110.11 108.440944) (width 0.109) (layer "In6.Cu") (net 37))
  (segment (start 89.85 112.2) (end 89.85 111.13) (width 0.109) (layer "In6.Cu") (net 37))
  (segment (start 114.754402 108.593779) (end 114.792607 108.602499) (width 0.109) (layer "In6.Cu") (net 37))
  (segment (start 110.525889 109.195876) (end 110.55907 109.216725) (width 0.109) (layer "In6.Cu") (net 37))
  (segment (start 114.025889 108.711821) (end 114.05907 108.73267) (width 0.109) (layer "In6.Cu") (net 37))
  (segment (start 110.20907 108.283275) (end 110.246058 108.270332) (width 0.109) (layer "In6.Cu") (net 37))
  (segment (start 111.514387 108.402003) (end 111.52733 108.365015) (width 0.109) (layer "In6.Cu") (net 37))
  (segment (start 115.234303 107.528556) (end 115.2173 107.493249) (width 0.109) (layer "In6.Cu") (net 37))
  (segment (start 111.646058 108.270332) (end 111.685 108.265944) (width 0.109) (layer "In6.Cu") (net 37))
  (segment (start 109.585 108.265944) (end 109.623941 108.270332) (width 0.109) (layer "In6.Cu") (net 37))
  (segment (start 113.96 108.440944) (end 113.96 108.575) (width 0.109) (layer "In6.Cu") (net 37))
  (segment (start 115.362887 107.261551) (end 115.402075 107.261551) (width 0.109) (layer "In6.Cu") (net 37))
  (segment (start 108.075889 108.304124) (end 108.10907 108.283275) (width 0.109) (layer "In6.Cu") (net 37))
  (segment (start 115.448319 108.243751) (end 115.478957 108.268184) (width 0.109) (layer "In6.Cu") (net 37))
  (segment (start 111.548179 108.331834) (end 111.575889 108.304124) (width 0.109) (layer "In6.Cu") (net 37))
  (segment (start 114.827914 108.619501) (end 114.858552 108.643935) (width 0.109) (layer "In6.Cu") (net 37))
  (segment (start 108.01 108.440944) (end 108.014387 108.402003) (width 0.109) (layer "In6.Cu") (net 37))
  (segment (start 90.177685 110.802315) (end 92.317685 110.802315) (width 0.109) (layer "In6.Cu") (net 37))
  (segment (start 117.825 99.205) (end 117.825 98.78) (width 0.109) (layer "In6.Cu") (net 37))
  (segment (start 115.200831 108.738726) (end 115.225264 108.708087) (width 0.109) (layer "In6.Cu") (net 37))
  (segment (start 118.376078 97.717883) (end 118.351781 97.693586) (width 0.182) (layer "F.Cu") (net 38))
  (segment (start 118.405707 97.77941) (end 118.394359 97.746977) (width 0.182) (layer "F.Cu") (net 38))
  (segment (start 118.467328 97.933523) (end 118.443031 97.909226) (width 0.182) (layer "F.Cu") (net 38))
  (segment (start 118.199 97.66011) (end 118.164855 97.663957) (width 0.182) (layer "F.Cu") (net 38))
  (segment (start 117.387 97.967) (end 117.282713 97.862713) (width 0.182) (layer "F.Cu") (net 38))
  (segment (start 118.443031 97.909226) (end 118.42475 97.880132) (width 0.182) (layer "F.Cu") (net 38))
  (segment (start 118.528855 97.963152) (end 118.496422 97.951804) (width 0.182) (layer "F.Cu") (net 38))
  (segment (start 118.563 97.967) (end 118.528855 97.963152) (width 0.182) (layer "F.Cu") (net 38))
  (segment (start 118.049402 97.77941) (end 118.041707 97.847699) (width 0.182) (layer "F.Cu") (net 38))
  (segment (start 117.958687 97.951804) (end 117.926254 97.963152) (width 0.182) (layer "F.Cu") (net 38))
  (segment (start 117.926254 97.963152) (end 117.89211 97.967) (width 0.182) (layer "F.Cu") (net 38))
  (segment (start 117.987781 97.933523) (end 117.958687 97.951804) (width 0.182) (layer "F.Cu") (net 38))
  (segment (start 118.322687 97.675305) (end 118.290254 97.663957) (width 0.182) (layer "F.Cu") (net 38))
  (segment (start 118.164855 97.663957) (end 118.132422 97.675305) (width 0.182) (layer "F.Cu") (net 38))
  (segment (start 117.89211 97.967) (end 117.387 97.967) (width 0.182) (layer "F.Cu") (net 38))
  (segment (start 119.1829 97.967) (end 118.563 97.967) (width 0.182) (layer "F.Cu") (net 38))
  (segment (start 118.394359 97.746977) (end 118.376078 97.717883) (width 0.182) (layer "F.Cu") (net 38))
  (segment (start 117.282713 97.605) (end 117.282713 97.862713) (width 0.182) (layer "F.Cu") (net 38))
  (segment (start 118.25611 97.66011) (end 118.199 97.66011) (width 0.182) (layer "F.Cu") (net 38))
  (segment (start 118.012078 97.909226) (end 117.987781 97.933523) (width 0.182) (layer "F.Cu") (net 38))
  (segment (start 118.103328 97.693586) (end 118.079031 97.717883) (width 0.182) (layer "F.Cu") (net 38))
  (segment (start 118.413402 97.847699) (end 118.405707 97.77941) (width 0.182) (layer "F.Cu") (net 38))
  (segment (start 93.3265 112.224) (end 93.7115 111.914) (width 0.182) (layer "F.Cu") (net 38))
  (segment (start 118.132422 97.675305) (end 118.103328 97.693586) (width 0.182) (layer "F.Cu") (net 38))
  (segment (start 118.06075 97.746977) (end 118.049402 97.77941) (width 0.182) (layer "F.Cu") (net 38))
  (segment (start 118.351781 97.693586) (end 118.322687 97.675305) (width 0.182) (layer "F.Cu") (net 38))
  (segment (start 118.290254 97.663957) (end 118.25611 97.66011) (width 0.182) (layer "F.Cu") (net 38))
  (segment (start 118.496422 97.951804) (end 118.467328 97.933523) (width 0.182) (layer "F.Cu") (net 38))
  (segment (start 118.030359 97.880132) (end 118.012078 97.909226) (width 0.182) (layer "F.Cu") (net 38))
  (segment (start 118.42475 97.880132) (end 118.413402 97.847699) (width 0.182) (layer "F.Cu") (net 38))
  (segment (start 118.041707 97.847699) (end 118.030359 97.880132) (width 0.182) (layer "F.Cu") (net 38))
  (segment (start 118.079031 97.717883) (end 118.06075 97.746977) (width 0.182) (layer "F.Cu") (net 38))
  (via (at 117.282713 97.605) (size 0.45) (drill 0.1) (layers "F.Cu" "B.Cu") (net 38))
  (via (at 93.7115 111.914) (size 0.45) (drill 0.1) (layers "F.Cu" "B.Cu") (net 38))
  (segment (start 97.89411 111.709477) (end 97.92182 111.681767) (width 0.109) (layer "In6.Cu") (net 38))
  (segment (start 105.24411 110.890523) (end 105.27182 110.918233) (width 0.109) (layer "In6.Cu") (net 38))
  (segment (start 106.923941 111.743269) (end 106.960929 111.730326) (width 0.109) (layer "In6.Cu") (net 38))
  (segment (start 106.846058 111.743269) (end 106.885 111.747657) (width 0.109) (layer "In6.Cu") (net 38))
  (segment (start 97.592669 110.951414) (end 97.605612 110.988402) (width 0.109) (layer "In6.Cu") (net 38))
  (segment (start 105.835 110.852343) (end 105.873941 110.856731) (width 0.109) (layer "In6.Cu") (net 38))
  (segment (start 102.95907 110.869674) (end 102.996058 110.856731) (width 0.109) (layer "In6.Cu") (net 38))
  (segment (start 101.092669 110.951414) (end 101.105612 110.988402) (width 0.109) (layer "In6.Cu") (net 38))
  (segment (start 103.214387 111.611598) (end 103.22733 111.648586) (width 0.109) (layer "In6.Cu") (net 38))
  (segment (start 101.175889 111.709477) (end 101.20907 111.730326) (width 0.109) (layer "In6.Cu") (net 38))
  (segment (start 100.02182 111.681767) (end 100.042669 111.648586) (width 0.109) (layer "In6.Cu") (net 38))
  (segment (start 99.535 110.852343) (end 99.573941 110.856731) (width 0.109) (layer "In6.Cu") (net 38))
  (segment (start 97.955612 111.611598) (end 97.96 111.572657) (width 0.109) (layer "In6.Cu") (net 38))
  (segment (start 104.396058 110.856731) (end 104.435 110.852343) (width 0.109) (layer "In6.Cu") (net 38))
  (segment (start 97.510929 110.869674) (end 97.54411 110.890523) (width 0.109) (layer "In6.Cu") (net 38))
  (segment (start 104.605612 110.988402) (end 104.61 111.027343) (width 0.109) (layer "In6.Cu") (net 38))
  (segment (start 106.71 111.027343) (end 106.71 111.572657) (width 0.109) (layer "In6.Cu") (net 38))
  (segment (start 103.65907 110.869674) (end 103.696058 110.856731) (width 0.109) (layer "In6.Cu") (net 38))
  (segment (start 106.45907 110.869674) (end 106.496058 110.856731) (width 0.109) (layer "In6.Cu") (net 38))
  (segment (start 103.92733 111.648586) (end 103.948179 111.681767) (width 0.109) (layer "In6.Cu") (net 38))
  (segment (start 106.260929 111.730326) (end 106.29411 111.709477) (width 0.109) (layer "In6.Cu") (net 38))
  (segment (start 105.873941 110.856731) (end 105.910929 110.869674) (width 0.109) (layer "In6.Cu") (net 38))
  (segment (start 104.648179 111.681767) (end 104.675889 111.709477) (width 0.109) (layer "In6.Cu") (net 38))
  (segment (start 100.06 111.027343) (end 100.064387 110.988402) (width 0.109) (layer "In6.Cu") (net 38))
  (segment (start 106.10907 111.730326) (end 106.146058 111.743269) (width 0.109) (layer "In6.Cu") (net 38))
  (segment (start 104.92182 111.681767) (end 104.942669 111.648586) (width 0.109) (layer "In6.Cu") (net 38))
  (segment (start 98.32733 111.648586) (end 98.348179 111.681767) (width 0.109) (layer "In6.Cu") (net 38))
  (segment (start 106.64411 110.890523) (end 106.67182 110.918233) (width 0.109) (layer "In6.Cu") (net 38))
  (segment (start 104.57182 110.918233) (end 104.592669 110.951414) (width 0.109) (layer "In6.Cu") (net 38))
  (segment (start 101.82733 111.648586) (end 101.848179 111.681767) (width 0.109) (layer "In6.Cu") (net 38))
  (segment (start 107.098179 111.365889) (end 107.125889 111.338179) (width 0.109) (layer "In6.Cu") (net 38))
  (segment (start 103.625889 110.890523) (end 103.65907 110.869674) (width 0.109) (layer "In6.Cu") (net 38))
  (segment (start 102.864387 110.988402) (end 102.87733 110.951414) (width 0.109) (layer "In6.Cu") (net 38))
  (segment (start 97.62733 111.648586) (end 97.648179 111.681767) (width 0.109) (layer "In6.Cu") (net 38))
  (segment (start 105.485 111.747657) (end 105.523941 111.743269) (width 0.109) (layer "In6.Cu") (net 38))
  (segment (start 103.248179 111.681767) (end 103.275889 111.709477) (width 0.109) (layer "In6.Cu") (net 38))
  (segment (start 102.060929 111.730326) (end 102.09411 111.709477) (width 0.109) (layer "In6.Cu") (net 38))
  (segment (start 106.496058 110.856731) (end 106.535 110.852343) (width 0.109) (layer "In6.Cu") (net 38))
  (segment (start 100.273941 110.856731) (end 100.310929 110.869674) (width 0.109) (layer "In6.Cu") (net 38))
  (segment (start 104.89411 111.709477) (end 104.92182 111.681767) (width 0.109) (layer "In6.Cu") (net 38))
  (segment (start 101.946058 111.743269) (end 101.985 111.747657) (width 0.109) (layer "In6.Cu") (net 38))
  (segment (start 102.410929 110.869674) (end 102.44411 110.890523) (width 0.109) (layer "In6.Cu") (net 38))
  (segment (start 106.705612 110.988402) (end 106.71 111.027343) (width 0.109) (layer "In6.Cu") (net 38))
  (segment (start 106.223941 111.743269) (end 106.260929 111.730326) (width 0.109) (layer "In6.Cu") (net 38))
  (segment (start 97.96 111.027343) (end 97.964387 110.988402) (width 0.109) (layer "In6.Cu") (net 38))
  (segment (start 101.105612 110.988402) (end 101.11 111.027343) (width 0.109) (layer "In6.Cu") (net 38))
  (segment (start 100.34411 110.890523) (end 100.37182 110.918233) (width 0.109) (layer "In6.Cu") (net 38))
  (segment (start 97.085 111.747657) (end 97.123941 111.743269) (width 0.109) (layer "In6.Cu") (net 38))
  (segment (start 100.196058 110.856731) (end 100.235 110.852343) (width 0.109) (layer "In6.Cu") (net 38))
  (segment (start 101.848179 111.681767) (end 101.875889 111.709477) (width 0.109) (layer "In6.Cu") (net 38))
  (segment (start 105.348179 111.681767) (end 105.375889 111.709477) (width 0.109) (layer "In6.Cu") (net 38))
  (segment (start 97.998179 110.918233) (end 98.025889 110.890523) (width 0.109) (layer "In6.Cu") (net 38))
  (segment (start 119.7 107.56) (end 119.7 98.38625) (width 0.109) (layer "In6.Cu") (net 38))
  (segment (start 103.696058 110.856731) (end 103.735 110.852343) (width 0.109) (layer "In6.Cu") (net 38))
  (segment (start 102.47182 110.918233) (end 102.492669 110.951414) (width 0.109) (layer "In6.Cu") (net 38))
  (segment (start 106.36 111.027343) (end 106.364387 110.988402) (width 0.109) (layer "In6.Cu") (net 38))
  (segment (start 98.642669 111.648586) (end 98.655612 111.611598) (width 0.109) (layer "In6.Cu") (net 38))
  (segment (start 106.185 111.747657) (end 106.223941 111.743269) (width 0.109) (layer "In6.Cu") (net 38))
  (segment (start 104.96 111.027343) (end 104.964387 110.988402) (width 0.109) (layer "In6.Cu") (net 38))
  (segment (start 97.97733 110.951414) (end 97.998179 110.918233) (width 0.109) (layer "In6.Cu") (net 38))
  (segment (start 101.010929 110.869674) (end 101.04411 110.890523) (width 0.109) (layer "In6.Cu") (net 38))
  (segment (start 100.973941 110.856731) (end 101.010929 110.869674) (width 0.109) (layer "In6.Cu") (net 38))
  (segment (start 100.85907 110.869674) (end 100.896058 110.856731) (width 0.109) (layer "In6.Cu") (net 38))
  (segment (start 106.342669 111.648586) (end 106.355612 111.611598) (width 0.109) (layer "In6.Cu") (net 38))
  (segment (start 105.655612 111.611598) (end 105.66 111.572657) (width 0.109) (layer "In6.Cu") (net 38))
  (segment (start 105.59411 111.709477) (end 105.62182 111.681767) (width 0.109) (layer "In6.Cu") (net 38))
  (segment (start 98.796058 110.856731) (end 98.835 110.852343) (width 0.109) (layer "In6.Cu") (net 38))
  (segment (start 98.664387 110.988402) (end 98.67733 110.951414) (width 0.109) (layer "In6.Cu") (net 38))
  (segment (start 102.25907 110.869674) (end 102.296058 110.856731) (width 0.109) (layer "In6.Cu") (net 38))
  (segment (start 96.773941 111.304387) (end 96.810929 111.31733) (width 0.109) (layer "In6.Cu") (net 38))
  (segment (start 105.32733 111.648586) (end 105.348179 111.681767) (width 0.109) (layer "In6.Cu") (net 38))
  (segment (start 100.623941 111.743269) (end 100.660929 111.730326) (width 0.109) (layer "In6.Cu") (net 38))
  (segment (start 104.473941 110.856731) (end 104.510929 110.869674) (width 0.109) (layer "In6.Cu") (net 38))
  (segment (start 103.21 111.027343) (end 103.21 111.572657) (width 0.109) (layer "In6.Cu") (net 38))
  (segment (start 105.910929 110.869674) (end 105.94411 110.890523) (width 0.109) (layer "In6.Cu") (net 38))
  (segment (start 102.996058 110.856731) (end 103.035 110.852343) (width 0.109) (layer "In6.Cu") (net 38))
  (segment (start 102.335 110.852343) (end 102.373941 110.856731) (width 0.109) (layer "In6.Cu") (net 38))
  (segment (start 101.985 111.747657) (end 102.023941 111.743269) (width 0.109) (layer "In6.Cu") (net 38))
  (segment (start 99.185 111.747657) (end 99.223941 111.743269) (width 0.109) (layer "In6.Cu") (net 38))
  (segment (start 103.17182 110.918233) (end 103.192669 110.951414) (width 0.109) (layer "In6.Cu") (net 38))
  (segment (start 100.825889 110.890523) (end 100.85907 110.869674) (width 0.109) (layer "In6.Cu") (net 38))
  (segment (start 105.66 111.027343) (end 105.664387 110.988402) (width 0.109) (layer "In6.Cu") (net 38))
  (segment (start 98.94411 110.890523) (end 98.97182 110.918233) (width 0.109) (layer "In6.Cu") (net 38))
  (segment (start 98.485 111.747657) (end 98.523941 111.743269) (width 0.109) (layer "In6.Cu") (net 38))
  (segment (start 98.873941 110.856731) (end 98.910929 110.869674) (width 0.109) (layer "In6.Cu") (net 38))
  (segment (start 99.146058 111.743269) (end 99.185 111.747657) (width 0.109) (layer "In6.Cu") (net 38))
  (segment (start 102.09411 111.709477) (end 102.12182 111.681767) (width 0.109) (layer "In6.Cu") (net 38))
  (segment (start 103.905612 110.988402) (end 103.91 111.027343) (width 0.109) (layer "In6.Cu") (net 38))
  (segment (start 103.205612 110.988402) (end 103.21 111.027343) (width 0.109) (layer "In6.Cu") (net 38))
  (segment (start 102.82182 111.681767) (end 102.842669 111.648586) (width 0.109) (layer "In6.Cu") (net 38))
  (segment (start 102.646058 111.743269) (end 102.685 111.747657) (width 0.109) (layer "In6.Cu") (net 38))
  (segment (start 98.210929 110.869674) (end 98.24411 110.890523) (width 0.109) (layer "In6.Cu") (net 38))
  (segment (start 98.655612 111.611598) (end 98.66 111.572657) (width 0.109) (layer "In6.Cu") (net 38))
  (segment (start 104.860929 111.730326) (end 104.89411 111.709477) (width 0.109) (layer "In6.Cu") (net 38))
  (segment (start 102.60907 111.730326) (end 102.646058 111.743269) (width 0.109) (layer "In6.Cu") (net 38))
  (segment (start 100.755612 111.611598) (end 100.76 111.572657) (width 0.109) (layer "In6.Cu") (net 38))
  (segment (start 105.27182 110.918233) (end 105.292669 110.951414) (width 0.109) (layer "In6.Cu") (net 38))
  (segment (start 102.685 111.747657) (end 102.723941 111.743269) (width 0.109) (layer "In6.Cu") (net 38))
  (segment (start 99.29411 111.709477) (end 99.32182 111.681767) (width 0.109) (layer "In6.Cu") (net 38))
  (segment (start 104.61 111.027343) (end 104.61 111.572657) (width 0.109) (layer "In6.Cu") (net 38))
  (segment (start 101.455612 111.611598) (end 101.46 111.572657) (width 0.109) (layer "In6.Cu") (net 38))
  (segment (start 101.46 111.572657) (end 101.46 111.027343) (width 0.109) (layer "In6.Cu") (net 38))
  (segment (start 104.942669 111.648586) (end 104.955612 111.611598) (width 0.109) (layer "In6.Cu") (net 38))
  (segment (start 100.042669 111.648586) (end 100.055612 111.611598) (width 0.109) (layer "In6.Cu") (net 38))
  (segment (start 100.935 110.852343) (end 100.973941 110.856731) (width 0.109) (layer "In6.Cu") (net 38))
  (segment (start 98.97182 110.918233) (end 98.992669 110.951414) (width 0.109) (layer "In6.Cu") (net 38))
  (segment (start 97.435 110.852343) (end 97.473941 110.856731) (width 0.109) (layer "In6.Cu") (net 38))
  (segment (start 100.125889 110.890523) (end 100.15907 110.869674) (width 0.109) (layer "In6.Cu") (net 38))
  (segment (start 103.56 111.572657) (end 103.56 111.027343) (width 0.109) (layer "In6.Cu") (net 38))
  (segment (start 106.005612 110.988402) (end 106.01 111.027343) (width 0.109) (layer "In6.Cu") (net 38))
  (segment (start 105.97182 110.918233) (end 105.992669 110.951414) (width 0.109) (layer "In6.Cu") (net 38))
  (segment (start 105.305612 110.988402) (end 105.31 111.027343) (width 0.109) (layer "In6.Cu") (net 38))
  (segment (start 107.055612 111.611598) (end 107.06 111.572657) (width 0.109) (layer "In6.Cu") (net 38))
  (segment (start 106.99411 111.709477) (end 107.02182 111.681767) (width 0.109) (layer "In6.Cu") (net 38))
  (segment (start 98.348179 111.681767) (end 98.375889 111.709477) (width 0.109) (layer "In6.Cu") (net 38))
  (segment (start 106.146058 111.743269) (end 106.185 111.747657) (width 0.109) (layer "In6.Cu") (net 38))
  (segment (start 104.26 111.027343) (end 104.264387 110.988402) (width 0.109) (layer "In6.Cu") (net 38))
  (segment (start 97.746058 111.743269) (end 97.785 111.747657) (width 0.109) (layer "In6.Cu") (net 38))
  (segment (start 115.96 111.3) (end 119.7 107.56) (width 0.109) (layer "In6.Cu") (net 38))
  (segment (start 103.564387 110.988402) (end 103.57733 110.951414) (width 0.109) (layer "In6.Cu") (net 38))
  (segment (start 106.71 111.572657) (end 106.714387 111.611598) (width 0.109) (layer "In6.Cu") (net 38))
  (segment (start 102.198179 110.918233) (end 102.225889 110.890523) (width 0.109) (layer "In6.Cu") (net 38))
  (segment (start 98.62182 111.681767) (end 98.642669 111.648586) (width 0.109) (layer "In6.Cu") (net 38))
  (segment (start 104.614387 111.611598) (end 104.62733 111.648586) (width 0.109) (layer "In6.Cu") (net 38))
  (segment (start 104.592669 110.951414) (end 104.605612 110.988402) (width 0.109) (layer "In6.Cu") (net 38))
  (segment (start 96.87182 111.365889) (end 96.892669 111.39907) (width 0.109) (layer "In6.Cu") (net 38))
  (segment (start 98.725889 110.890523) (end 98.75907 110.869674) (width 0.109) (layer "In6.Cu") (net 38))
  (segment (start 102.51 111.572657) (end 102.514387 111.611598) (width 0.109) (layer "In6.Cu") (net 38))
  (segment (start 99.71 111.027343) (end 99.71 111.572657) (width 0.109) (layer "In6.Cu") (net 38))
  (segment (start 103.91 111.027343) (end 103.91 111.572657) (width 0.109) (layer "In6.Cu") (net 38))
  (segment (start 105.173941 110.856731) (end 105.210929 110.869674) (width 0.109) (layer "In6.Cu") (net 38))
  (segment (start 99.67182 110.918233) (end 99.692669 110.951414) (width 0.109) (layer "In6.Cu") (net 38))
  (segment (start 104.62733 111.648586) (end 104.648179 111.681767) (width 0.109) (layer "In6.Cu") (net 38))
  (segment (start 102.155612 111.611598) (end 102.16 111.572657) (width 0.109) (layer "In6.Cu") (net 38))
  (segment (start 100.896058 110.856731) (end 100.935 110.852343) (width 0.109) (layer "In6.Cu") (net 38))
  (segment (start 103.56 111.027343) (end 103.564387 110.988402) (width 0.109) (layer "In6.Cu") (net 38))
  (segment (start 99.496058 110.856731) (end 99.535 110.852343) (width 0.109) (layer "In6.Cu") (net 38))
  (segment (start 103.073941 110.856731) (end 103.110929 110.869674) (width 0.109) (layer "In6.Cu") (net 38))
  (segment (start 99.260929 111.730326) (end 99.29411 111.709477) (width 0.109) (layer "In6.Cu") (net 38))
  (segment (start 107.06 111.572657) (end 107.06 111.475) (width 0.109) (layer "In6.Cu") (net 38))
  (segment (start 97.860929 111.730326) (end 97.89411 111.709477) (width 0.109) (layer "In6.Cu") (net 38))
  (segment (start 101.11 111.572657) (end 101.114387 111.611598) (width 0.109) (layer "In6.Cu") (net 38))
  (segment (start 96.948179 111.681767) (end 96.975889 111.709477) (width 0.109) (layer "In6.Cu") (net 38))
  (segment (start 102.723941 111.743269) (end 102.760929 111.730326) (width 0.109) (layer "In6.Cu") (net 38))
  (segment (start 99.01 111.572657) (end 99.014387 111.611598) (width 0.109) (layer "In6.Cu") (net 38))
  (segment (start 96.892669 111.39907) (end 96.905612 111.436058) (width 0.109) (layer "In6.Cu") (net 38))
  (segment (start 98.135 110.852343) (end 98.173941 110.856731) (width 0.109) (layer "In6.Cu") (net 38))
  (segment (start 101.20907 111.730326) (end 101.246058 111.743269) (width 0.109) (layer "In6.Cu") (net 38))
  (segment (start 103.598179 110.918233) (end 103.625889 110.890523) (width 0.109) (layer "In6.Cu") (net 38))
  (segment (start 102.87733 110.951414) (end 102.898179 110.918233) (width 0.109) (layer "In6.Cu") (net 38))
  (segment (start 102.505612 110.988402) (end 102.51 111.027343) (width 0.109) (layer "In6.Cu") (net 38))
  (segment (start 101.596058 110.856731) (end 101.635 110.852343) (width 0.109) (layer "In6.Cu") (net 38))
  (segment (start 97.255612 111.611598) (end 97.26 111.572657) (width 0.109) (layer "In6.Cu") (net 38))
  (segment (start 100.41 111.572657) (end 100.414387 111.611598) (width 0.109) (layer "In6.Cu") (net 38))
  (segment (start 106.355612 111.611598) (end 106.36 111.572657) (width 0.109) (layer "In6.Cu") (net 38))
  (segment (start 100.37182 110.918233) (end 100.392669 110.951414) (width 0.109) (layer "In6.Cu") (net 38))
  (segment (start 105.096058 110.856731) (end 105.135 110.852343) (width 0.109) (layer "In6.Cu") (net 38))
  (segment (start 99.923941 111.743269) (end 99.960929 111.730326) (width 0.109) (layer "In6.Cu") (net 38))
  (segment (start 104.255612 111.611598) (end 104.26 111.572657) (width 0.109) (layer "In6.Cu") (net 38))
  (segment (start 102.142669 111.648586) (end 102.155612 111.611598) (width 0.109) (layer "In6.Cu") (net 38))
  (segment (start 98.305612 110.988402) (end 98.31 111.027343) (width 0.109) (layer "In6.Cu") (net 38))
  (segment (start 107.042669 111.648586) (end 107.055612 111.611598) (width 0.109) (layer "In6.Cu") (net 38))
  (segment (start 96.735 111.3) (end 96.773941 111.304387) (width 0.109) (layer "In6.Cu") (net 38))
  (segment (start 97.61 111.027343) (end 97.61 111.572657) (width 0.109) (layer "In6.Cu") (net 38))
  (segment (start 99.99411 111.709477) (end 100.02182 111.681767) (width 0.109) (layer "In6.Cu") (net 38))
  (segment (start 106.748179 111.681767) (end 106.775889 111.709477) (width 0.109) (layer "In6.Cu") (net 38))
  (segment (start 103.542669 111.648586) (end 103.555612 111.611598) (width 0.109) (layer "In6.Cu") (net 38))
  (segment (start 106.02733 111.648586) (end 106.048179 111.681767) (width 0.109) (layer "In6.Cu") (net 38))
  (segment (start 98.314387 111.611598) (end 98.32733 111.648586) (width 0.109) (layer "In6.Cu") (net 38))
  (segment (start 103.385 111.747657) (end 103.423941 111.743269) (width 0.109) (layer "In6.Cu") (net 38))
  (segment (start 98.31 111.027343) (end 98.31 111.572657) (width 0.109) (layer "In6.Cu") (net 38))
  (segment (start 102.548179 111.681767) (end 102.575889 111.709477) (width 0.109) (layer "In6.Cu") (net 38))
  (segment (start 101.39411 111.709477) (end 101.42182 111.681767) (width 0.109) (layer "In6.Cu") (net 38))
  (segment (start 104.435 110.852343) (end 104.473941 110.856731) (width 0.109) (layer "In6.Cu") (net 38))
  (segment (start 105.66 111.572657) (end 105.66 111.027343) (width 0.109) (layer "In6.Cu") (net 38))
  (segment (start 106.610929 110.869674) (end 106.64411 110.890523) (width 0.109) (layer "In6.Cu") (net 38))
  (segment (start 99.36 111.027343) (end 99.364387 110.988402) (width 0.109) (layer "In6.Cu") (net 38))
  (segment (start 96.91 111.475) (end 96.91 111.572657) (width 0.109) (layer "In6.Cu") (net 38))
  (segment (start 102.16 111.027343) (end 102.164387 110.988402) (width 0.109) (layer "In6.Cu") (net 38))
  (segment (start 103.21 111.572657) (end 103.214387 111.611598) (width 0.109) (layer "In6.Cu") (net 38))
  (segment (start 100.310929 110.869674) (end 100.34411 110.890523) (width 0.109) (layer "In6.Cu") (net 38))
  (segment (start 98.560929 111.730326) (end 98.59411 111.709477) (width 0.109) (layer "In6.Cu") (net 38))
  (segment (start 99.45907 110.869674) (end 99.496058 110.856731) (width 0.109) (layer "In6.Cu") (net 38))
  (segment (start 100.660929 111.730326) (end 100.69411 111.709477) (width 0.109) (layer "In6.Cu") (net 38))
  (segment (start 106.014387 111.611598) (end 106.02733 111.648586) (width 0.109) (layer "In6.Cu") (net 38))
  (segment (start 100.448179 111.681767) (end 100.475889 111.709477) (width 0.109) (layer "In6.Cu") (net 38))
  (segment (start 106.398179 110.918233) (end 106.425889 110.890523) (width 0.109) (layer "In6.Cu") (net 38))
  (segment (start 102.225889 110.890523) (end 102.25907 110.869674) (width 0.109) (layer "In6.Cu") (net 38))
  (segment (start 106.885 111.747657) (end 106.923941 111.743269) (width 0.109) (layer "In6.Cu") (net 38))
  (segment (start 101.74411 110.890523) (end 101.77182 110.918233) (width 0.109) (layer "In6.Cu") (net 38))
  (segment (start 97.22182 111.681767) (end 97.242669 111.648586) (width 0.109) (layer "In6.Cu") (net 38))
  (segment (start 98.67733 110.951414) (end 98.698179 110.918233) (width 0.109) (layer "In6.Cu") (net 38))
  (segment (start 102.44411 110.890523) (end 102.47182 110.918233) (width 0.109) (layer "In6.Cu") (net 38))
  (segment (start 97.19411 111.709477) (end 97.22182 111.681767) (width 0.109) (layer "In6.Cu") (net 38))
  (segment (start 102.855612 111.611598) (end 102.86 111.572657) (width 0.109) (layer "In6.Cu") (net 38))
  (segment (start 97.046058 111.743269) (end 97.085 111.747657) (width 0.109) (layer "In6.Cu") (net 38))
  (segment (start 100.764387 110.988402) (end 100.77733 110.951414) (width 0.109) (layer "In6.Cu") (net 38))
  (segment (start 104.96 111.572657) (end 104.96 111.027343) (width 0.109) (layer "In6.Cu") (net 38))
  (segment (start 104.510929 110.869674) (end 104.54411 110.890523) (width 0.109) (layer "In6.Cu") (net 38))
  (segment (start 99.72733 111.648586) (end 99.748179 111.681767) (width 0.109) (layer "In6.Cu") (net 38))
  (segment (start 103.810929 110.869674) (end 103.84411 110.890523) (width 0.109) (layer "In6.Cu") (net 38))
  (segment (start 97.61 111.572657) (end 97.614387 111.611598) (width 0.109) (layer "In6.Cu") (net 38))
  (segment (start 103.948179 111.681767) (end 103.975889 111.709477) (width 0.109) (layer "In6.Cu") (net 38))
  (segment (start 100.235 110.852343) (end 100.273941 110.856731) (width 0.109) (layer "In6.Cu") (net 38))
  (segment (start 107.06 111.475) (end 107.064387 111.436058) (width 0.109) (layer "In6.Cu") (net 38))
  (segment (start 99.398179 110.918233) (end 99.425889 110.890523) (width 0.109) (layer "In6.Cu") (net 38))
  (segment (start 102.86 111.027343) (end 102.864387 110.988402) (width 0.109) (layer "In6.Cu") (net 38))
  (segment (start 102.898179 110.918233) (end 102.925889 110.890523) (width 0.109) (layer "In6.Cu") (net 38))
  (segment (start 98.66 111.027343) (end 98.664387 110.988402) (width 0.109) (layer "In6.Cu") (net 38))
  (segment (start 99.364387 110.988402) (end 99.37733 110.951414) (width 0.109) (layer "In6.Cu") (net 38))
  (segment (start 98.025889 110.890523) (end 98.05907 110.869674) (width 0.109) (layer "In6.Cu") (net 38))
  (segment (start 104.085 111.747657) (end 104.123941 111.743269) (width 0.109) (layer "In6.Cu") (net 38))
  (segment (start 103.30907 111.730326) (end 103.346058 111.743269) (width 0.109) (layer "In6.Cu") (net 38))
  (segment (start 100.06 111.572657) (end 100.06 111.027343) (width 0.109) (layer "In6.Cu") (net 38))
  (segment (start 105.025889 110.890523) (end 105.05907 110.869674) (width 0.109) (layer "In6.Cu") (net 38))
  (segment (start 97.473941 110.856731) (end 97.510929 110.869674) (width 0.109) (layer "In6.Cu") (net 38))
  (segment (start 105.292669 110.951414) (end 105.305612 110.988402) (width 0.109) (layer "In6.Cu") (net 38))
  (segment (start 96.84411 111.338179) (end 96.87182 111.365889) (width 0.109) (layer "In6.Cu") (net 38))
  (segment (start 103.773941 110.856731) (end 103.810929 110.869674) (width 0.109) (layer "In6.Cu") (net 38))
  (segment (start 98.40907 111.730326) (end 98.446058 111.743269) (width 0.109) (layer "In6.Cu") (net 38))
  (segment (start 103.460929 111.730326) (end 103.49411 111.709477) (width 0.109) (layer "In6.Cu") (net 38))
  (segment (start 106.32182 111.681767) (end 106.342669 111.648586) (width 0.109) (layer "In6.Cu") (net 38))
  (segment (start 104.046058 111.743269) (end 104.085 111.747657) (width 0.109) (layer "In6.Cu") (net 38))
  (segment (start 104.00907 111.730326) (end 104.046058 111.743269) (width 0.109) (layer "In6.Cu") (net 38))
  (segment (start 100.098179 110.918233) (end 100.125889 110.890523) (width 0.109) (layer "In6.Cu") (net 38))
  (segment (start 104.325889 110.890523) (end 104.35907 110.869674) (width 0.109) (layer "In6.Cu") (net 38))
  (segment (start 101.792669 110.951414) (end 101.805612 110.988402) (width 0.109) (layer "In6.Cu") (net 38))
  (segment (start 100.76 111.572657) (end 100.76 111.027343) (width 0.109) (layer "In6.Cu") (net 38))
  (segment (start 101.148179 111.681767) (end 101.175889 111.709477) (width 0.109) (layer "In6.Cu") (net 38))
  (segment (start 104.264387 110.988402) (end 104.27733 110.951414) (width 0.109) (layer "In6.Cu") (net 38))
  (segment (start 105.560929 111.730326) (end 105.59411 111.709477) (width 0.109) (layer "In6.Cu") (net 38))
  (segment (start 103.57733 110.951414) (end 103.598179 110.918233) (width 0.109) (layer "In6.Cu") (net 38))
  (segment (start 98.31 111.572657) (end 98.314387 111.611598) (width 0.109) (layer "In6.Cu") (net 38))
  (segment (start 97.242669 111.648586) (end 97.255612 111.611598) (width 0.109) (layer "In6.Cu") (net 38))
  (segment (start 100.405612 110.988402) (end 100.41 111.027343) (width 0.109) (layer "In6.Cu") (net 38))
  (segment (start 99.960929 111.730326) (end 99.99411 111.709477) (width 0.109) (layer "In6.Cu") (net 38))
  (segment (start 103.49411 111.709477) (end 103.52182 111.681767) (width 0.109) (layer "In6.Cu") (net 38))
  (segment (start 99.01 111.027343) (end 99.01 111.572657) (width 0.109) (layer "In6.Cu") (net 38))
  (segment (start 98.173941 110.856731) (end 98.210929 110.869674) (width 0.109) (layer "In6.Cu") (net 38))
  (segment (start 96.175 111.3) (end 96.735 111.3) (width 0.109) (layer "In6.Cu") (net 38))
  (segment (start 99.014387 111.611598) (end 99.02733 111.648586) (width 0.109) (layer "In6.Cu") (net 38))
  (segment (start 98.446058 111.743269) (end 98.485 111.747657) (width 0.109) (layer "In6.Cu") (net 38))
  (segment (start 105.31 111.027343) (end 105.31 111.572657) (width 0.109) (layer "In6.Cu") (net 38))
  (segment (start 98.27182 110.918233) (end 98.292669 110.951414) (width 0.109) (layer "In6.Cu") (net 38))
  (segment (start 103.035 110.852343) (end 103.073941 110.856731) (width 0.109) (layer "In6.Cu") (net 38))
  (segment (start 102.925889 110.890523) (end 102.95907 110.869674) (width 0.109) (layer "In6.Cu") (net 38))
  (segment (start 97.396058 110.856731) (end 97.435 110.852343) (width 0.109) (layer "In6.Cu") (net 38))
  (segment (start 95.561 111.914) (end 96.175 111.3) (width 0.109) (layer "In6.Cu") (net 38))
  (segment (start 100.585 111.747657) (end 100.623941 111.743269) (width 0.109) (layer "In6.Cu") (net 38))
  (segment (start 101.11 111.027343) (end 101.11 111.572657) (width 0.109) (layer "In6.Cu") (net 38))
  (segment (start 105.523941 111.743269) (end 105.560929 111.730326) (width 0.109) (layer "In6.Cu") (net 38))
  (segment (start 101.635 110.852343) (end 101.673941 110.856731) (width 0.109) (layer "In6.Cu") (net 38))
  (segment (start 105.725889 110.890523) (end 105.75907 110.869674) (width 0.109) (layer "In6.Cu") (net 38))
  (segment (start 106.573941 110.856731) (end 106.610929 110.869674) (width 0.109) (layer "In6.Cu") (net 38))
  (segment (start 107.196058 111.304387) (end 107.235 111.3) (width 0.109) (layer "In6.Cu") (net 38))
  (segment (start 102.86 111.572657) (end 102.86 111.027343) (width 0.109) (layer "In6.Cu") (net 38))
  (segment (start 97.70907 111.730326) (end 97.746058 111.743269) (width 0.109) (layer "In6.Cu") (net 38))
  (segment (start 101.81 111.027343) (end 101.81 111.572657) (width 0.109) (layer "In6.Cu") (net 38))
  (segment (start 100.76 111.027343) (end 100.764387 110.988402) (width 0.109) (layer "In6.Cu") (net 38))
  (segment (start 102.514387 111.611598) (end 102.52733 111.648586) (width 0.109) (layer "In6.Cu") (net 38))
  (segment (start 97.675889 111.709477) (end 97.70907 111.730326) (width 0.109) (layer "In6.Cu") (net 38))
  (segment (start 105.75907 110.869674) (end 105.796058 110.856731) (width 0.109) (layer "In6.Cu") (net 38))
  (segment (start 93.7115 111.914) (end 95.561 111.914) (width 0.109) (layer "In6.Cu") (net 38))
  (segment (start 99.36 111.572657) (end 99.36 111.027343) (width 0.109) (layer "In6.Cu") (net 38))
  (segment (start 103.735 110.852343) (end 103.773941 110.856731) (width 0.109) (layer "In6.Cu") (net 38))
  (segment (start 97.614387 111.611598) (end 97.62733 111.648586) (width 0.109) (layer "In6.Cu") (net 38))
  (segment (start 106.714387 111.611598) (end 106.72733 111.648586) (width 0.109) (layer "In6.Cu") (net 38))
  (segment (start 102.023941 111.743269) (end 102.060929 111.730326) (width 0.109) (layer "In6.Cu") (net 38))
  (segment (start 107.235 111.3) (end 115.96 111.3) (width 0.109) (layer "In6.Cu") (net 38))
  (segment (start 103.84411 110.890523) (end 103.87182 110.918233) (width 0.109) (layer "In6.Cu") (net 38))
  (segment (start 99.425889 110.890523) (end 99.45907 110.869674) (width 0.109) (layer "In6.Cu") (net 38))
  (segment (start 100.064387 110.988402) (end 100.07733 110.951414) (width 0.109) (layer "In6.Cu") (net 38))
  (segment (start 107.02182 111.681767) (end 107.042669 111.648586) (width 0.109) (layer "In6.Cu") (net 38))
  (segment (start 101.114387 111.611598) (end 101.12733 111.648586) (width 0.109) (layer "In6.Cu") (net 38))
  (segment (start 99.342669 111.648586) (end 99.355612 111.611598) (width 0.109) (layer "In6.Cu") (net 38))
  (segment (start 99.748179 111.681767) (end 99.775889 111.709477) (width 0.109) (layer "In6.Cu") (net 38))
  (segment (start 103.555612 111.611598) (end 103.56 111.572657) (width 0.109) (layer "In6.Cu") (net 38))
  (segment (start 119.7 98.38625) (end 118.91875 97.605) (width 0.109) (layer "In6.Cu") (net 38))
  (segment (start 99.02733 111.648586) (end 99.048179 111.681767) (width 0.109) (layer "In6.Cu") (net 38))
  (segment (start 99.32182 111.681767) (end 99.342669 111.648586) (width 0.109) (layer "In6.Cu") (net 38))
  (segment (start 106.80907 111.730326) (end 106.846058 111.743269) (width 0.109) (layer "In6.Cu") (net 38))
  (segment (start 99.573941 110.856731) (end 99.610929 110.869674) (width 0.109) (layer "In6.Cu") (net 38))
  (segment (start 104.70907 111.730326) (end 104.746058 111.743269) (width 0.109) (layer "In6.Cu") (net 38))
  (segment (start 105.31 111.572657) (end 105.314387 111.611598) (width 0.109) (layer "In6.Cu") (net 38))
  (segment (start 99.355612 111.611598) (end 99.36 111.572657) (width 0.109) (layer "In6.Cu") (net 38))
  (segment (start 102.17733 110.951414) (end 102.198179 110.918233) (width 0.109) (layer "In6.Cu") (net 38))
  (segment (start 100.798179 110.918233) (end 100.825889 110.890523) (width 0.109) (layer "In6.Cu") (net 38))
  (segment (start 102.575889 111.709477) (end 102.60907 111.730326) (width 0.109) (layer "In6.Cu") (net 38))
  (segment (start 101.285 111.747657) (end 101.323941 111.743269) (width 0.109) (layer "In6.Cu") (net 38))
  (segment (start 97.785 111.747657) (end 97.823941 111.743269) (width 0.109) (layer "In6.Cu") (net 38))
  (segment (start 100.69411 111.709477) (end 100.72182 111.681767) (width 0.109) (layer "In6.Cu") (net 38))
  (segment (start 101.442669 111.648586) (end 101.455612 111.611598) (width 0.109) (layer "In6.Cu") (net 38))
  (segment (start 97.96 111.572657) (end 97.96 111.027343) (width 0.109) (layer "In6.Cu") (net 38))
  (segment (start 103.275889 111.709477) (end 103.30907 111.730326) (width 0.109) (layer "In6.Cu") (net 38))
  (segment (start 104.785 111.747657) (end 104.823941 111.743269) (width 0.109) (layer "In6.Cu") (net 38))
  (segment (start 102.373941 110.856731) (end 102.410929 110.869674) (width 0.109) (layer "In6.Cu") (net 38))
  (segment (start 101.710929 110.869674) (end 101.74411 110.890523) (width 0.109) (layer "In6.Cu") (net 38))
  (segment (start 106.67182 110.918233) (end 106.692669 110.951414) (width 0.109) (layer "In6.Cu") (net 38))
  (segment (start 103.346058 111.743269) (end 103.385 111.747657) (width 0.109) (layer "In6.Cu") (net 38))
  (segment (start 106.960929 111.730326) (end 106.99411 111.709477) (width 0.109) (layer "In6.Cu") (net 38))
  (segment (start 96.914387 111.611598) (end 96.92733 111.648586) (width 0.109) (layer "In6.Cu") (net 38))
  (segment (start 97.57182 110.918233) (end 97.592669 110.951414) (width 0.109) (layer "In6.Cu") (net 38))
  (segment (start 102.52733 111.648586) (end 102.548179 111.681767) (width 0.109) (layer "In6.Cu") (net 38))
  (segment (start 104.964387 110.988402) (end 104.97733 110.951414) (width 0.109) (layer "In6.Cu") (net 38))
  (segment (start 101.673941 110.856731) (end 101.710929 110.869674) (width 0.109) (layer "In6.Cu") (net 38))
  (segment (start 107.064387 111.436058) (end 107.07733 111.39907) (width 0.109) (layer "In6.Cu") (net 38))
  (segment (start 105.05907 110.869674) (end 105.096058 110.856731) (width 0.109) (layer "In6.Cu") (net 38))
  (segment (start 101.55907 110.869674) (end 101.596058 110.856731) (width 0.109) (layer "In6.Cu") (net 38))
  (segment (start 100.392669 110.951414) (end 100.405612 110.988402) (width 0.109) (layer "In6.Cu") (net 38))
  (segment (start 98.59411 111.709477) (end 98.62182 111.681767) (width 0.109) (layer "In6.Cu") (net 38))
  (segment (start 100.72182 111.681767) (end 100.742669 111.648586) (width 0.109) (layer "In6.Cu") (net 38))
  (segment (start 99.705612 110.988402) (end 99.71 111.027343) (width 0.109) (layer "In6.Cu") (net 38))
  (segment (start 105.40907 111.730326) (end 105.446058 111.743269) (width 0.109) (layer "In6.Cu") (net 38))
  (segment (start 107.07733 111.39907) (end 107.098179 111.365889) (width 0.109) (layer "In6.Cu") (net 38))
  (segment (start 102.164387 110.988402) (end 102.17733 110.951414) (width 0.109) (layer "In6.Cu") (net 38))
  (segment (start 106.775889 111.709477) (end 106.80907 111.730326) (width 0.109) (layer "In6.Cu") (net 38))
  (segment (start 102.296058 110.856731) (end 102.335 110.852343) (width 0.109) (layer "In6.Cu") (net 38))
  (segment (start 99.10907 111.730326) (end 99.146058 111.743269) (width 0.109) (layer "In6.Cu") (net 38))
  (segment (start 100.77733 110.951414) (end 100.798179 110.918233) (width 0.109) (layer "In6.Cu") (net 38))
  (segment (start 97.648179 111.681767) (end 97.675889 111.709477) (width 0.109) (layer "In6.Cu") (net 38))
  (segment (start 99.37733 110.951414) (end 99.398179 110.918233) (width 0.109) (layer "In6.Cu") (net 38))
  (segment (start 100.07733 110.951414) (end 100.098179 110.918233) (width 0.109) (layer "In6.Cu") (net 38))
  (segment (start 106.72733 111.648586) (end 106.748179 111.681767) (width 0.109) (layer "In6.Cu") (net 38))
  (segment (start 97.325889 110.890523) (end 97.35907 110.869674) (width 0.109) (layer "In6.Cu") (net 38))
  (segment (start 101.42182 111.681767) (end 101.442669 111.648586) (width 0.109) (layer "In6.Cu") (net 38))
  (segment (start 101.498179 110.918233) (end 101.525889 110.890523) (width 0.109) (layer "In6.Cu") (net 38))
  (segment (start 96.92733 111.648586) (end 96.948179 111.681767) (width 0.109) (layer "In6.Cu") (net 38))
  (segment (start 104.123941 111.743269) (end 104.160929 111.730326) (width 0.109) (layer "In6.Cu") (net 38))
  (segment (start 98.835 110.852343) (end 98.873941 110.856731) (width 0.109) (layer "In6.Cu") (net 38))
  (segment (start 98.523941 111.743269) (end 98.560929 111.730326) (width 0.109) (layer "In6.Cu") (net 38))
  (segment (start 99.005612 110.988402) (end 99.01 111.027343) (width 0.109) (layer "In6.Cu") (net 38))
  (segment (start 97.27733 110.951414) (end 97.298179 110.918233) (width 0.109) (layer "In6.Cu") (net 38))
  (segment (start 104.675889 111.709477) (end 104.70907 111.730326) (width 0.109) (layer "In6.Cu") (net 38))
  (segment (start 105.796058 110.856731) (end 105.835 110.852343) (width 0.109) (layer "In6.Cu") (net 38))
  (segment (start 96.975889 111.709477) (end 97.00907 111.730326) (width 0.109) (layer "In6.Cu") (net 38))
  (segment (start 104.27733 110.951414) (end 104.298179 110.918233) (width 0.109) (layer "In6.Cu") (net 38))
  (segment (start 105.67733 110.951414) (end 105.698179 110.918233) (width 0.109) (layer "In6.Cu") (net 38))
  (segment (start 99.775889 111.709477) (end 99.80907 111.730326) (width 0.109) (layer "In6.Cu") (net 38))
  (segment (start 103.22733 111.648586) (end 103.248179 111.681767) (width 0.109) (layer "In6.Cu") (net 38))
  (segment (start 102.760929 111.730326) (end 102.79411 111.709477) (width 0.109) (layer "In6.Cu") (net 38))
  (segment (start 97.298179 110.918233) (end 97.325889 110.890523) (width 0.109) (layer "In6.Cu") (net 38))
  (segment (start 101.07182 110.918233) (end 101.092669 110.951414) (width 0.109) (layer "In6.Cu") (net 38))
  (segment (start 97.942669 111.648586) (end 97.955612 111.611598) (width 0.109) (layer "In6.Cu") (net 38))
  (segment (start 100.15907 110.869674) (end 100.196058 110.856731) (width 0.109) (layer "In6.Cu") (net 38))
  (segment (start 99.048179 111.681767) (end 99.075889 111.709477) (width 0.109) (layer "In6.Cu") (net 38))
  (segment (start 97.35907 110.869674) (end 97.396058 110.856731) (width 0.109) (layer "In6.Cu") (net 38))
  (segment (start 104.35907 110.869674) (end 104.396058 110.856731) (width 0.109) (layer "In6.Cu") (net 38))
  (segment (start 98.698179 110.918233) (end 98.725889 110.890523) (width 0.109) (layer "In6.Cu") (net 38))
  (segment (start 104.298179 110.918233) (end 104.325889 110.890523) (width 0.109) (layer "In6.Cu") (net 38))
  (segment (start 101.360929 111.730326) (end 101.39411 111.709477) (width 0.109) (layer "In6.Cu") (net 38))
  (segment (start 98.66 111.572657) (end 98.66 111.027343) (width 0.109) (layer "In6.Cu") (net 38))
  (segment (start 106.36 111.572657) (end 106.36 111.027343) (width 0.109) (layer "In6.Cu") (net 38))
  (segment (start 96.91 111.572657) (end 96.914387 111.611598) (width 0.109) (layer "In6.Cu") (net 38))
  (segment (start 99.714387 111.611598) (end 99.72733 111.648586) (width 0.109) (layer "In6.Cu") (net 38))
  (segment (start 97.54411 110.890523) (end 97.57182 110.918233) (width 0.109) (layer "In6.Cu") (net 38))
  (segment (start 107.125889 111.338179) (end 107.15907 111.31733) (width 0.109) (layer "In6.Cu") (net 38))
  (segment (start 98.992669 110.951414) (end 99.005612 110.988402) (width 0.109) (layer "In6.Cu") (net 38))
  (segment (start 104.823941 111.743269) (end 104.860929 111.730326) (width 0.109) (layer "In6.Cu") (net 38))
  (segment (start 105.94411 110.890523) (end 105.97182 110.918233) (width 0.109) (layer "In6.Cu") (net 38))
  (segment (start 106.37733 110.951414) (end 106.398179 110.918233) (width 0.109) (layer "In6.Cu") (net 38))
  (segment (start 103.423941 111.743269) (end 103.460929 111.730326) (width 0.109) (layer "In6.Cu") (net 38))
  (segment (start 99.610929 110.869674) (end 99.64411 110.890523) (width 0.109) (layer "In6.Cu") (net 38))
  (segment (start 100.475889 111.709477) (end 100.50907 111.730326) (width 0.109) (layer "In6.Cu") (net 38))
  (segment (start 101.805612 110.988402) (end 101.81 111.027343) (width 0.109) (layer "In6.Cu") (net 38))
  (segment (start 99.223941 111.743269) (end 99.260929 111.730326) (width 0.109) (layer "In6.Cu") (net 38))
  (segment (start 101.47733 110.951414) (end 101.498179 110.918233) (width 0.109) (layer "In6.Cu") (net 38))
  (segment (start 105.992669 110.951414) (end 106.005612 110.988402) (width 0.109) (layer "In6.Cu") (net 38))
  (segment (start 101.246058 111.743269) (end 101.285 111.747657) (width 0.109) (layer "In6.Cu") (net 38))
  (segment (start 104.746058 111.743269) (end 104.785 111.747657) (width 0.109) (layer "In6.Cu") (net 38))
  (segment (start 104.19411 111.709477) (end 104.22182 111.681767) (width 0.109) (layer "In6.Cu") (net 38))
  (segment (start 105.698179 110.918233) (end 105.725889 110.890523) (width 0.109) (layer "In6.Cu") (net 38))
  (segment (start 103.192669 110.951414) (end 103.205612 110.988402) (width 0.109) (layer "In6.Cu") (net 38))
  (segment (start 101.875889 111.709477) (end 101.90907 111.730326) (width 0.109) (layer "In6.Cu") (net 38))
  (segment (start 98.375889 111.709477) (end 98.40907 111.730326) (width 0.109) (layer "In6.Cu") (net 38))
  (segment (start 98.910929 110.869674) (end 98.94411 110.890523) (width 0.109) (layer "In6.Cu") (net 38))
  (segment (start 105.210929 110.869674) (end 105.24411 110.890523) (width 0.109) (layer "In6.Cu") (net 38))
  (segment (start 97.605612 110.988402) (end 97.61 111.027343) (width 0.109) (layer "In6.Cu") (net 38))
  (segment (start 106.075889 111.709477) (end 106.10907 111.730326) (width 0.109) (layer "In6.Cu") (net 38))
  (segment (start 103.91 111.572657) (end 103.914387 111.611598) (width 0.109) (layer "In6.Cu") (net 38))
  (segment (start 103.52182 111.681767) (end 103.542669 111.648586) (width 0.109) (layer "In6.Cu") (net 38))
  (segment (start 98.24411 110.890523) (end 98.27182 110.918233) (width 0.109) (layer "In6.Cu") (net 38))
  (segment (start 107.15907 111.31733) (end 107.196058 111.304387) (width 0.109) (layer "In6.Cu") (net 38))
  (segment (start 101.464387 110.988402) (end 101.47733 110.951414) (width 0.109) (layer "In6.Cu") (net 38))
  (segment (start 105.375889 111.709477) (end 105.40907 111.730326) (width 0.109) (layer "In6.Cu") (net 38))
  (segment (start 102.79411 111.709477) (end 102.82182 111.681767) (width 0.109) (layer "In6.Cu") (net 38))
  (segment (start 102.492669 110.951414) (end 102.505612 110.988402) (width 0.109) (layer "In6.Cu") (net 38))
  (segment (start 103.914387 111.611598) (end 103.92733 111.648586) (width 0.109) (layer "In6.Cu") (net 38))
  (segment (start 100.546058 111.743269) (end 100.585 111.747657) (width 0.109) (layer "In6.Cu") (net 38))
  (segment (start 99.846058 111.743269) (end 99.885 111.747657) (width 0.109) (layer "In6.Cu") (net 38))
  (segment (start 102.51 111.027343) (end 102.51 111.572657) (width 0.109) (layer "In6.Cu") (net 38))
  (segment (start 104.97733 110.951414) (end 104.998179 110.918233) (width 0.109) (layer "In6.Cu") (net 38))
  (segment (start 100.50907 111.730326) (end 100.546058 111.743269) (width 0.109) (layer "In6.Cu") (net 38))
  (segment (start 106.535 110.852343) (end 106.573941 110.856731) (width 0.109) (layer "In6.Cu") (net 38))
  (segment (start 97.160929 111.730326) (end 97.19411 111.709477) (width 0.109) (layer "In6.Cu") (net 38))
  (segment (start 97.264387 110.988402) (end 97.27733 110.951414) (width 0.109) (layer "In6.Cu") (net 38))
  (segment (start 118.91875 97.605) (end 117.282713 97.605) (width 0.109) (layer "In6.Cu") (net 38))
  (segment (start 104.160929 111.730326) (end 104.19411 111.709477) (width 0.109) (layer "In6.Cu") (net 38))
  (segment (start 100.742669 111.648586) (end 100.755612 111.611598) (width 0.109) (layer "In6.Cu") (net 38))
  (segment (start 101.81 111.572657) (end 101.814387 111.611598) (width 0.109) (layer "In6.Cu") (net 38))
  (segment (start 101.77182 110.918233) (end 101.792669 110.951414) (width 0.109) (layer "In6.Cu") (net 38))
  (segment (start 101.12733 111.648586) (end 101.148179 111.681767) (width 0.109) (layer "In6.Cu") (net 38))
  (segment (start 101.525889 110.890523) (end 101.55907 110.869674) (width 0.109) (layer "In6.Cu") (net 38))
  (segment (start 102.12182 111.681767) (end 102.142669 111.648586) (width 0.109) (layer "In6.Cu") (net 38))
  (segment (start 106.364387 110.988402) (end 106.37733 110.951414) (width 0.109) (layer "In6.Cu") (net 38))
  (segment (start 99.71 111.572657) (end 99.714387 111.611598) (width 0.109) (layer "In6.Cu") (net 38))
  (segment (start 106.425889 110.890523) (end 106.45907 110.869674) (width 0.109) (layer "In6.Cu") (net 38))
  (segment (start 101.323941 111.743269) (end 101.360929 111.730326) (width 0.109) (layer "In6.Cu") (net 38))
  (segment (start 99.692669 110.951414) (end 99.705612 110.988402) (width 0.109) (layer "In6.Cu") (net 38))
  (segment (start 102.842669 111.648586) (end 102.855612 111.611598) (width 0.109) (layer "In6.Cu") (net 38))
  (segment (start 97.26 111.572657) (end 97.26 111.027343) (width 0.109) (layer "In6.Cu") (net 38))
  (segment (start 104.955612 111.611598) (end 104.96 111.572657) (width 0.109) (layer "In6.Cu") (net 38))
  (segment (start 101.04411 110.890523) (end 101.07182 110.918233) (width 0.109) (layer "In6.Cu") (net 38))
  (segment (start 96.905612 111.436058) (end 96.91 111.475) (width 0.109) (layer "In6.Cu") (net 38))
  (segment (start 105.135 110.852343) (end 105.173941 110.856731) (width 0.109) (layer "In6.Cu") (net 38))
  (segment (start 106.01 111.572657) (end 106.014387 111.611598) (width 0.109) (layer "In6.Cu") (net 38))
  (segment (start 104.26 111.572657) (end 104.26 111.027343) (width 0.109) (layer "In6.Cu") (net 38))
  (segment (start 98.05907 110.869674) (end 98.096058 110.856731) (width 0.109) (layer "In6.Cu") (net 38))
  (segment (start 97.823941 111.743269) (end 97.860929 111.730326) (width 0.109) (layer "In6.Cu") (net 38))
  (segment (start 103.975889 111.709477) (end 104.00907 111.730326) (width 0.109) (layer "In6.Cu") (net 38))
  (segment (start 103.14411 110.890523) (end 103.17182 110.918233) (width 0.109) (layer "In6.Cu") (net 38))
  (segment (start 99.075889 111.709477) (end 99.10907 111.730326) (width 0.109) (layer "In6.Cu") (net 38))
  (segment (start 104.61 111.572657) (end 104.614387 111.611598) (width 0.109) (layer "In6.Cu") (net 38))
  (segment (start 101.46 111.027343) (end 101.464387 110.988402) (width 0.109) (layer "In6.Cu") (net 38))
  (segment (start 103.892669 110.951414) (end 103.905612 110.988402) (width 0.109) (layer "In6.Cu") (net 38))
  (segment (start 97.00907 111.730326) (end 97.046058 111.743269) (width 0.109) (layer "In6.Cu") (net 38))
  (segment (start 102.16 111.572657) (end 102.16 111.027343) (width 0.109) (layer "In6.Cu") (net 38))
  (segment (start 103.87182 110.918233) (end 103.892669 110.951414) (width 0.109) (layer "In6.Cu") (net 38))
  (segment (start 100.42733 111.648586) (end 100.448179 111.681767) (width 0.109) (layer "In6.Cu") (net 38))
  (segment (start 106.29411 111.709477) (end 106.32182 111.681767) (width 0.109) (layer "In6.Cu") (net 38))
  (segment (start 104.998179 110.918233) (end 105.025889 110.890523) (width 0.109) (layer "In6.Cu") (net 38))
  (segment (start 101.814387 111.611598) (end 101.82733 111.648586) (width 0.109) (layer "In6.Cu") (net 38))
  (segment (start 96.810929 111.31733) (end 96.84411 111.338179) (width 0.109) (layer "In6.Cu") (net 38))
  (segment (start 104.54411 110.890523) (end 104.57182 110.918233) (width 0.109) (layer "In6.Cu") (net 38))
  (segment (start 100.41 111.027343) (end 100.41 111.572657) (width 0.109) (layer "In6.Cu") (net 38))
  (segment (start 98.096058 110.856731) (end 98.135 110.852343) (width 0.109) (layer "In6.Cu") (net 38))
  (segment (start 105.642669 111.648586) (end 105.655612 111.611598) (width 0.109) (layer "In6.Cu") (net 38))
  (segment (start 99.64411 110.890523) (end 99.67182 110.918233) (width 0.109) (layer "In6.Cu") (net 38))
  (segment (start 100.414387 111.611598) (end 100.42733 111.648586) (width 0.109) (layer "In6.Cu") (net 38))
  (segment (start 97.26 111.027343) (end 97.264387 110.988402) (width 0.109) (layer "In6.Cu") (net 38))
  (segment (start 97.123941 111.743269) (end 97.160929 111.730326) (width 0.109) (layer "In6.Cu") (net 38))
  (segment (start 104.242669 111.648586) (end 104.255612 111.611598) (width 0.109) (layer "In6.Cu") (net 38))
  (segment (start 98.292669 110.951414) (end 98.305612 110.988402) (width 0.109) (layer "In6.Cu") (net 38))
  (segment (start 104.22182 111.681767) (end 104.242669 111.648586) (width 0.109) (layer "In6.Cu") (net 38))
  (segment (start 106.048179 111.681767) (end 106.075889 111.709477) (width 0.109) (layer "In6.Cu") (net 38))
  (segment (start 97.92182 111.681767) (end 97.942669 111.648586) (width 0.109) (layer "In6.Cu") (net 38))
  (segment (start 106.692669 110.951414) (end 106.705612 110.988402) (width 0.109) (layer "In6.Cu") (net 38))
  (segment (start 105.446058 111.743269) (end 105.485 111.747657) (width 0.109) (layer "In6.Cu") (net 38))
  (segment (start 100.055612 111.611598) (end 100.06 111.572657) (width 0.109) (layer "In6.Cu") (net 38))
  (segment (start 99.80907 111.730326) (end 99.846058 111.743269) (width 0.109) (layer "In6.Cu") (net 38))
  (segment (start 103.110929 110.869674) (end 103.14411 110.890523) (width 0.109) (layer "In6.Cu") (net 38))
  (segment (start 105.664387 110.988402) (end 105.67733 110.951414) (width 0.109) (layer "In6.Cu") (net 38))
  (segment (start 98.75907 110.869674) (end 98.796058 110.856731) (width 0.109) (layer "In6.Cu") (net 38))
  (segment (start 105.62182 111.681767) (end 105.642669 111.648586) (width 0.109) (layer "In6.Cu") (net 38))
  (segment (start 101.90907 111.730326) (end 101.946058 111.743269) (width 0.109) (layer "In6.Cu") (net 38))
  (segment (start 97.964387 110.988402) (end 97.97733 110.951414) (width 0.109) (layer "In6.Cu") (net 38))
  (segment (start 106.01 111.027343) (end 106.01 111.572657) (width 0.109) (layer "In6.Cu") (net 38))
  (segment (start 99.885 111.747657) (end 99.923941 111.743269) (width 0.109) (layer "In6.Cu") (net 38))
  (segment (start 105.314387 111.611598) (end 105.32733 111.648586) (width 0.109) (layer "In6.Cu") (net 38))
  (segment (start 118.629 97.459) (end 118.325 97.155) (width 0.182) (layer "F.Cu") (net 39))
  (segment (start 119.1829 97.459) (end 118.629 97.459) (width 0.182) (layer "F.Cu") (net 39))
  (segment (start 93.3265 111.589) (end 93.63599 111.27951) (width 0.182) (layer "F.Cu") (net 39))
  (segment (start 118.325 97.155) (end 116.765 97.155) (width 0.182) (layer "F.Cu") (net 39))
  (segment (start 93.63599 111.27951) (end 93.7115 111.27951) (width 0.182) (layer "F.Cu") (net 39))
  (via (at 116.765 97.155) (size 0.45) (drill 0.1) (layers "F.Cu" "B.Cu") (net 39))
  (via (at 93.7115 111.27951) (size 0.45) (drill 0.1) (layers "F.Cu" "B.Cu") (net 39))
  (segment (start 117.664854 107.907253) (end 117.643909 107.880994) (width 0.109) (layer "In6.Cu") (net 39))
  (segment (start 116.795388 108.569908) (end 116.816329 108.543648) (width 0.109) (layer "In6.Cu") (net 39))
  (segment (start 113.068378 110.057762) (end 113.100082 110.068856) (width 0.109) (layer "In6.Cu") (net 39))
  (segment (start 109.341476 110.086727) (end 109.369917 110.068856) (width 0.109) (layer "In6.Cu") (net 39))
  (segment (start 114.685 110.695999) (end 114.685 110.204001) (width 0.109) (layer "In6.Cu") (net 39))
  (segment (start 111.099854 110.138919) (end 111.117725 110.110478) (width 0.109) (layer "In6.Cu") (net 39))
  (segment (start 109.870145 110.761081) (end 109.881239 110.729377) (width 0.109) (layer "In6.Cu") (net 39))
  (segment (start 116.075848 110.357899) (end 116.075848 110.32431) (width 0.109) (layer "In6.Cu") (net 39))
  (segment (start 112.899854 110.138919) (end 112.917725 110.110478) (width 0.109) (layer "In6.Cu") (net 39))
  (segment (start 117.396199 108.08387) (end 117.426463 108.098443) (width 0.109) (layer "In6.Cu") (net 39))
  (segment (start 115.664021 109.701274) (end 115.684964 109.675013) (width 0.109) (layer "In6.Cu") (net 39))
  (segment (start 110.841476 110.813273) (end 110.869917 110.831144) (width 0.109) (layer "In6.Cu") (net 39))
  (segment (start 118.012748 108.255146) (end 117.664854 107.907253) (width 0.109) (layer "In6.Cu") (net 39))
  (segment (start 114.501621 110.842238) (end 114.535 110.845999) (width 0.109) (layer "In6.Cu") (net 39))
  (segment (start 107.700082 110.464854) (end 107.728523 110.482725) (width 0.109) (layer "In6.Cu") (net 39))
  (segment (start 117.205075 108.17591) (end 117.21965 108.145646) (width 0.109) (layer "In6.Cu") (net 39))
  (segment (start 114.535 110.845999) (end 114.568378 110.842238) (width 0.109) (layer "In6.Cu") (net 39))
  (segment (start 117.787714 107.652132) (end 117.82046 107.659607) (width 0.109) (layer "In6.Cu") (net 39))
  (segment (start 114.169917 110.068856) (end 114.201621 110.057762) (width 0.109) (layer "In6.Cu") (net 39))
  (segment (start 108.985 110.204001) (end 108.985 110.695999) (width 0.109) (layer "In6.Cu") (net 39))
  (segment (start 117.588487 108.891541) (end 117.609429 108.865279) (width 0.109) (layer "In6.Cu") (net 39))
  (segment (start 113.785 110.204001) (end 113.785 110.695999) (width 0.109) (layer "In6.Cu") (net 39))
  (segment (start 109.168378 110.842238) (end 109.200082 110.831144) (width 0.109) (layer "In6.Cu") (net 39))
  (segment (start 111.928523 110.086727) (end 111.952274 110.110478) (width 0.109) (layer "In6.Cu") (net 39))
  (segment (start 109.285 110.204001) (end 109.28876 110.170623) (width 0.109) (layer "In6.Cu") (net 39))
  (segment (start 107.785 110.6) (end 107.785 110.695999) (width 0.109) (layer "In6.Cu") (net 39))
  (segment (start 108.399854 110.761081) (end 108.417725 110.789522) (width 0.109) (layer "In6.Cu") (net 39))
  (segment (start 115.807824 109.632024) (end 115.840572 109.639497) (width 0.109) (layer "In6.Cu") (net 39))
  (segment (start 117.402616 108.912484) (end 117.432879 108.927057) (width 0.109) (layer "In6.Cu") (net 39))
  (segment (start 110.217725 110.789522) (end 110.241476 110.813273) (width 0.109) (layer "In6.Cu") (net 39))
  (segment (start 112.200082 110.831144) (end 112.228523 110.813273) (width 0.109) (layer "In6.Cu") (net 39))
  (segment (start 118.224879 108.043017) (end 118.25114 108.06396) (width 0.109) (layer "In6.Cu") (net 39))
  (segment (start 113.217725 110.789522) (end 113.241476 110.813273) (width 0.109) (layer "In6.Cu") (net 39))
  (segment (start 111.699854 110.138919) (end 111.717725 110.110478) (width 0.109) (layer "In6.Cu") (net 39))
  (segment (start 109.270145 110.761081) (end 109.281239 110.729377) (width 0.109) (layer "In6.Cu") (net 39))
  (segment (start 110.301621 110.842238) (end 110.335 110.845999) (width 0.109) (layer "In6.Cu") (net 39))
  (segment (start 109.581239 110.170623) (end 109.585 110.204001) (width 0.109) (layer "In6.Cu") (net 39))
  (segment (start 118.089116 107.482991) (end 118.068171 107.456732) (width 0.109) (layer "In6.Cu") (net 39))
  (segment (start 116.389239 109.530761) (end 116.67208 109.247923) (width 0.109) (layer "In6.Cu") (net 39))
  (segment (start 117.631477 108.802269) (end 117.631477 108.76868) (width 0.109) (layer "In6.Cu") (net 39))
  (segment (start 115.820726 110.447171) (end 115.846987 110.468114) (width 0.109) (layer "In6.Cu") (net 39))
  (segment (start 117.643911 107.721383) (end 117.664852 107.695123) (width 0.109) (layer "In6.Cu") (net 39))
  (segment (start 116.698341 109.22698) (end 116.728604 109.212406) (width 0.109) (layer "In6.Cu") (net 39))
  (segment (start 116.67208 109.247923) (end 116.698341 109.22698) (width 0.109) (layer "In6.Cu") (net 39))
  (segment (start 115.470003 110.45) (end 115.540713 110.37929) (width 0.109) (layer "In6.Cu") (net 39))
  (segment (start 109.281239 110.729377) (end 109.285 110.695999) (width 0.109) (layer "In6.Cu") (net 39))
  (segment (start 116.27125 110.043851) (end 116.301513 110.058425) (width 0.109) (layer "In6.Cu") (net 39))
  (segment (start 114.381239 110.170623) (end 114.385 110.204001) (width 0.109) (layer "In6.Cu") (net 39))
  (segment (start 111.300082 110.068856) (end 111.328523 110.086727) (width 0.109) (layer "In6.Cu") (net 39))
  (segment (start 109.570145 110.138919) (end 109.581239 110.170623) (width 0.109) (layer "In6.Cu") (net 39))
  (segment (start 114.235 110.054001) (end 114.268378 110.057762) (width 0.109) (layer "In6.Cu") (net 39))
  (segment (start 118.274986 107.249918) (end 118.301247 107.27086) (width 0.109) (layer "In6.Cu") (net 39))
  (segment (start 118.281403 108.078533) (end 118.314151 108.086008) (width 0.109) (layer "In6.Cu") (net 39))
  (segment (start 109.585 110.695999) (end 109.58876 110.729377) (width 0.109) (layer "In6.Cu") (net 39))
  (segment (start 107.781239 110.566621) (end 107.785 110.6) (width 0.109) (layer "In6.Cu") (net 39))
  (segment (start 118.472527 107.887409) (end 118.457953 107.857146) (width 0.109) (layer "In6.Cu") (net 39))
  (segment (start 118.033691 108.281408) (end 118.012748 108.255146) (width 0.109) (layer "In6.Cu") (net 39))
  (segment (start 118.048265 108.311671) (end 118.033691 108.281408) (width 0.109) (layer "In6.Cu") (net 39))
  (segment (start 114.38876 110.729377) (end 114.399854 110.761081) (width 0.109) (layer "In6.Cu") (net 39))
  (segment (start 116.400597 110.058425) (end 116.43086 110.043851) (width 0.109) (layer "In6.Cu") (net 39))
  (segment (start 117.465627 108.934532) (end 117.499216 108.934532) (width 0.109) (layer "In6.Cu") (net 39))
  (segment (start 116.780813 108.600172) (end 116.795388 108.569908) (width 0.109) (layer "In6.Cu") (net 39))
  (segment (start 112.270145 110.761081) (end 112.281239 110.729377) (width 0.109) (layer "In6.Cu") (net 39))
  (segment (start 118.055739 108.378007) (end 118.055739 108.344418) (width 0.109) (layer "In6.Cu") (net 39))
  (segment (start 118.524738 107.37426) (end 118.555 107.359685) (width 0.109) (layer "In6.Cu") (net 39))
  (segment (start 117.629336 107.751647) (end 117.643911 107.721383) (width 0.109) (layer "In6.Cu") (net 39))
  (segment (start 117.621861 107.784394) (end 117.629336 107.751647) (width 0.109) (layer "In6.Cu") (net 39))
  (segment (start 108.535 110.845999) (end 108.568378 110.842238) (width 0.109) (layer "In6.Cu") (net 39))
  (segment (start 112.585 110.695999) (end 112.58876 110.729377) (width 0.109) (layer "In6.Cu") (net 39))
  (segment (start 112.135 110.845999) (end 112.168378 110.842238) (width 0.109) (layer "In6.Cu") (net 39))
  (segment (start 110.785 110.204001) (end 110.785 110.695999) (width 0.109) (layer "In6.Cu") (net 39))
  (segment (start 116.0538 110.2613) (end 116.032858 110.235038) (width 0.109) (layer "In6.Cu") (net 39))
  (segment (start 117.621862 107.817982) (end 117.621861 107.784394) (width 0.109) (layer "In6.Cu") (net 39))
  (segment (start 114.98876 110.333379) (end 114.999854 110.365083) (width 0.109) (layer "In6.Cu") (net 39))
  (segment (start 118.048265 108.410754) (end 118.055739 108.378007) (width 0.109) (layer "In6.Cu") (net 39))
  (segment (start 112.228523 110.813273) (end 112.252274 110.789522) (width 0.109) (layer "In6.Cu") (net 39))
  (segment (start 114.085 110.695999) (end 114.085 110.204001) (width 0.109) (layer "In6.Cu") (net 39))
  (segment (start 111.385 110.204001) (end 111.385 110.695999) (width 0.109) (layer "In6.Cu") (net 39))
  (segment (start 107.78876 110.729377) (end 107.799854 110.761081) (width 0.109) (layer "In6.Cu") (net 39))
  (segment (start 115.041476 110.417275) (end 115.069917 110.435146) (width 0.109) (layer "In6.Cu") (net 39))
  (segment (start 118.49199 107.381733) (end 118.524738 107.37426) (width 0.109) (layer "In6.Cu") (net 39))
  (segment (start 116.478063 109.996646) (end 116.492637 109.966383) (width 0.109) (layer "In6.Cu") (net 39))
  (segment (start 108.38876 110.729377) (end 108.399854 110.761081) (width 0.109) (layer "In6.Cu") (net 39))
  (segment (start 108.928523 110.086727) (end 108.952274 110.110478) (width 0.109) (layer "In6.Cu") (net 39))
  (segment (start 115.663573 110.336299) (end 115.69632 110.343773) (width 0.109) (layer "In6.Cu") (net 39))
  (segment (start 112.500082 110.068856) (end 112.528523 110.086727) (width 0.109) (layer "In6.Cu") (net 39))
  (segment (start 118.581261 107.338742) (end 119 106.92) (width 0.109) (layer "In6.Cu") (net 39))
  (segment (start 113.035 110.054001) (end 113.068378 110.057762) (width 0.109) (layer "In6.Cu") (net 39))
  (segment (start 113.152274 110.110478) (end 113.170145 110.138919) (width 0.109) (layer "In6.Cu") (net 39))
  (segment (start 107.635 110.45) (end 107.668378 110.45376) (width 0.109) (layer "In6.Cu") (net 39))
  (segment (start 113.635 110.054001) (end 113.668378 110.057762) (width 0.109) (layer "In6.Cu") (net 39))
  (segment (start 113.485 110.204001) (end 113.48876 110.170623) (width 0.109) (layer "In6.Cu") (net 39))
  (segment (start 111.081239 110.729377) (end 111.085 110.695999) (width 0.109) (layer "In6.Cu") (net 39))
  (segment (start 113.817725 110.789522) (end 113.841476 110.813273) (width 0.109) (layer "In6.Cu") (net 39))
  (segment (start 108.070145 110.761081) (end 108.081239 110.729377) (width 0.109) (layer "In6.Cu") (net 39))
  (segment (start 115.540713 110.37929) (end 115.566974 110.358347) (width 0.109) (layer "In6.Cu") (net 39))
  (segment (start 117.240593 108.331516) (end 117.219648 108.305257) (width 0.109) (layer "In6.Cu") (net 39))
  (segment (start 114.052274 110.789522) (end 114.070145 110.761081) (width 0.109) (layer "In6.Cu") (net 39))
  (segment (start 95.32049 111.27951) (end 96.15 110.45) (width 0.109) (layer "In6.Cu") (net 39))
  (segment (start 112.58876 110.729377) (end 112.599854 110.761081) (width 0.109) (layer "In6.Cu") (net 39))
  (segment (start 111.169917 110.068856) (end 111.201621 110.057762) (width 0.109) (layer "In6.Cu") (net 39))
  (segment (start 93.7115 111.27951) (end 95.32049 111.27951) (width 0.109) (layer "In6.Cu") (net 39))
  (segment (start 116.006597 110.468114) (end 116.032858 110.447171) (width 0.109) (layer "In6.Cu") (net 39))
  (segment (start 112.617725 110.789522) (end 112.641476 110.813273) (width 0.109) (layer "In6.Cu") (net 39))
  (segment (start 116.478063 109.837037) (end 116.457121 109.810775) (width 0.109) (layer "In6.Cu") (net 39))
  (segment (start 114.985 110.3) (end 114.98876 110.333379) (width 0.109) (layer "In6.Cu") (net 39))
  (segment (start 113.452274 110.789522) (end 113.470145 110.761081) (width 0.109) (layer "In6.Cu") (net 39))
  (segment (start 108.628523 110.813273) (end 108.652274 110.789522) (width 0.109) (layer "In6.Cu") (net 39))
  (segment (start 112.435 110.054001) (end 112.468378 110.057762) (width 0.109) (layer "In6.Cu") (net 39))
  (segment (start 108.085 110.204001) (end 108.08876 110.170623) (width 0.109) (layer "In6.Cu") (net 39))
  (segment (start 116.500111 109.933636) (end 116.500111 109.900047) (width 0.109) (layer "In6.Cu") (net 39))
  (segment (start 109.017725 110.789522) (end 109.041476 110.813273) (width 0.109) (layer "In6.Cu") (net 39))
  (segment (start 110.100082 110.068856) (end 110.128523 110.086727) (width 0.109) (layer "In6.Cu") (net 39))
  (segment (start 117.691114 107.674181) (end 117.721378 107.659606) (width 0.109) (layer "In6.Cu") (net 39))
  (segment (start 108.370145 110.138919) (end 108.381239 110.170623) (width 0.109) (layer "In6.Cu") (net 39))
  (segment (start 114.68876 110.170623) (end 114.699854 110.138919) (width 0.109) (layer "In6.Cu") (net 39))
  (segment (start 114.081239 110.729377) (end 114.085 110.695999) (width 0.109) (layer "In6.Cu") (net 39))
  (segment (start 111.38876 110.729377) (end 111.399854 110.761081) (width 0.109) (layer "In6.Cu") (net 39))
  (segment (start 111.628523 110.813273) (end 111.652274 110.789522) (width 0.109) (layer "In6.Cu") (net 39))
  (segment (start 118.41075 108.063959) (end 118.437011 108.043017) (width 0.109) (layer "In6.Cu") (net 39))
  (segment (start 117.002201 108.522705) (end 117.028462 108.543647) (width 0.109) (layer "In6.Cu") (net 39))
  (segment (start 112.768378 110.842238) (end 112.800082 110.831144) (width 0.109) (layer "In6.Cu") (net 39))
  (segment (start 115.726583 110.358347) (end 115.752845 110.37929) (width 0.109) (layer "In6.Cu") (net 39))
  (segment (start 109.617725 110.789522) (end 109.641476 110.813273) (width 0.109) (layer "In6.Cu") (net 39))
  (segment (start 111.670145 110.761081) (end 111.681239 110.729377) (width 0.109) (layer "In6.Cu") (net 39))
  (segment (start 117.609429 108.70567) (end 117.588486 108.679408) (width 0.109) (layer "In6.Cu") (net 39))
  (segment (start 108.235 110.054001) (end 108.268378 110.057762) (width 0.109) (layer "In6.Cu") (net 39))
  (segment (start 116.457121 109.810775) (end 116.389239 109.742893) (width 0.109) (layer "In6.Cu") (net 39))
  (segment (start 108.385 110.695999) (end 108.38876 110.729377) (width 0.109) (layer "In6.Cu") (net 39))
  (segment (start 113.601621 110.057762) (end 113.635 110.054001) (width 0.109) (layer "In6.Cu") (net 39))
  (segment (start 114.085 110.204001) (end 114.08876 110.170623) (width 0.109) (layer "In6.Cu") (net 39))
  (segment (start 109.285 110.695999) (end 109.285 110.204001) (width 0.109) (layer "In6.Cu") (net 39))
  (segment (start 114.685 110.204001) (end 114.68876 110.170623) (width 0.109) (layer "In6.Cu") (net 39))
  (segment (start 118.244722 107.235345) (end 118.274986 107.249918) (width 0.109) (layer "In6.Cu") (net 39))
  (segment (start 111.117725 110.110478) (end 111.141476 110.086727) (width 0.109) (layer "In6.Cu") (net 39))
  (segment (start 110.035 110.054001) (end 110.068378 110.057762) (width 0.109) (layer "In6.Cu") (net 39))
  (segment (start 118.053598 107.327385) (end 118.068173 107.297121) (width 0.109) (layer "In6.Cu") (net 39))
  (segment (start 116.346248 109.620032) (end 116.353722 109.587285) (width 0.109) (layer "In6.Cu") (net 39))
  (segment (start 117.074954 109.358794) (end 117.107701 109.351319) (width 0.109) (layer "In6.Cu") (net 39))
  (segment (start 115.629984 110.336299) (end 115.663573 110.336299) (width 0.109) (layer "In6.Cu") (net 39))
  (segment (start 117.240591 108.119386) (end 117.266853 108.098444) (width 0.109) (layer "In6.Cu") (net 39))
  (segment (start 117.624003 108.835016) (end 117.631477 108.802269) (width 0.109) (layer "In6.Cu") (net 39))
  (segment (start 114.117725 110.110478) (end 114.141476 110.086727) (width 0.109) (layer "In6.Cu") (net 39))
  (segment (start 112.369917 110.068856) (end 112.401621 110.057762) (width 0.109) (layer "In6.Cu") (net 39))
  (segment (start 113.128523 110.086727) (end 113.152274 110.110478) (width 0.109) (layer "In6.Cu") (net 39))
  (segment (start 116.975 98.105) (end 116.765 97.895) (width 0.109) (layer "In6.Cu") (net 39))
  (segment (start 111.970145 110.138919) (end 111.981239 110.170623) (width 0.109) (layer "In6.Cu") (net 39))
  (segment (start 109.899854 110.138919) (end 109.917725 110.110478) (width 0.109) (layer "In6.Cu") (net 39))
  (segment (start 112.281239 110.729377) (end 112.285 110.695999) (width 0.109) (layer "In6.Cu") (net 39))
  (segment (start 112.735 110.845999) (end 112.768378 110.842238) (width 0.109) (layer "In6.Cu") (net 39))
  (segment (start 112.041476 110.813273) (end 112.069917 110.831144) (width 0.109) (layer "In6.Cu") (net 39))
  (segment (start 113.335 110.845999) (end 113.368378 110.842238) (width 0.109) (layer "In6.Cu") (net 39))
  (segment (start 117.205075 108.274994) (end 117.197601 108.242245) (width 0.109) (layer "In6.Cu") (net 39))
  (segment (start 116.068374 110.291563) (end 116.0538 110.2613) (width 0.109) (layer "In6.Cu") (net 39))
  (segment (start 117.137964 109.336745) (end 117.164225 109.315803) (width 0.109) (layer "In6.Cu") (net 39))
  (segment (start 117.207215 109.226531) (end 117.207215 109.192942) (width 0.109) (layer "In6.Cu") (net 39))
  (segment (start 115.135 110.45) (end 115.470003 110.45) (width 0.109) (layer "In6.Cu") (net 39))
  (segment (start 114.08876 110.170623) (end 114.099854 110.138919) (width 0.109) (layer "In6.Cu") (net 39))
  (segment (start 110.541476 110.086727) (end 110.569917 110.068856) (width 0.109) (layer "In6.Cu") (net 39))
  (segment (start 111.568378 110.842238) (end 111.600082 110.831144) (width 0.109) (layer "In6.Cu") (net 39))
  (segment (start 114.201621 110.057762) (end 114.235 110.054001) (width 0.109) (layer "In6.Cu") (net 39))
  (segment (start 117.643909 107.880994) (end 117.629336 107.850731) (width 0.109) (layer "In6.Cu") (net 39))
  (segment (start 107.752274 110.506476) (end 107.770145 110.534917) (width 0.109) (layer "In6.Cu") (net 39))
  (segment (start 109.317725 110.110478) (end 109.341476 110.086727) (width 0.109) (layer "In6.Cu") (net 39))
  (segment (start 113.400082 110.831144) (end 113.428523 110.813273) (width 0.109) (layer "In6.Cu") (net 39))
  (segment (start 108.652274 110.789522) (end 108.670145 110.761081) (width 0.109) (layer "In6.Cu") (net 39))
  (segment (start 108.385 110.204001) (end 108.385 110.695999) (width 0.109) (layer "In6.Cu") (net 39))
  (segment (start 96.15 110.45) (end 107.635 110.45) (width 0.109) (layer "In6.Cu") (net 39))
  (segment (start 118.301247 107.27086) (end 118.369129 107.338742) (width 0.109) (layer "In6.Cu") (net 39))
  (segment (start 111.381239 110.170623) (end 111.385 110.204001) (width 0.109) (layer "In6.Cu") (net 39))
  (segment (start 112.917725 110.110478) (end 112.941476 110.086727) (width 0.109) (layer "In6.Cu") (net 39))
  (segment (start 111.981239 110.170623) (end 111.985 110.204001) (width 0.109) (layer "In6.Cu") (net 39))
  (segment (start 113.428523 110.813273) (end 113.452274 110.789522) (width 0.109) (layer "In6.Cu") (net 39))
  (segment (start 117.164225 109.315803) (end 117.185167 109.289541) (width 0.109) (layer "In6.Cu") (net 39))
  (segment (start 116.353722 109.587285) (end 116.368296 109.557022) (width 0.109) (layer "In6.Cu") (net 39))
  (segment (start 116.075848 110.32431) (end 116.068374 110.291563) (width 0.109) (layer "In6.Cu") (net 39))
  (segment (start 110.785 110.695999) (end 110.78876 110.729377) (width 0.109) (layer "In6.Cu") (net 39))
  (segment (start 110.700082 110.068856) (end 110.728523 110.086727) (width 0.109) (layer "In6.Cu") (net 39))
  (segment (start 116.79494 109.204932) (end 116.827687 109.212406) (width 0.109) (layer "In6.Cu") (net 39))
  (segment (start 110.817725 110.789522) (end 110.841476 110.813273) (width 0.109) (layer "In6.Cu") (net 39))
  (segment (start 116.301513 110.058425) (end 116.33426 110.065899) (width 0.109) (layer "In6.Cu") (net 39))
  (segment (start 116.872855 108.508131) (end 116.905601 108.500658) (width 0.109) (layer "In6.Cu") (net 39))
  (segment (start 119 106.92) (end 119 99.205) (width 0.109) (layer "In6.Cu") (net 39))
  (segment (start 111.769917 110.068856) (end 111.801621 110.057762) (width 0.109) (layer "In6.Cu") (net 39))
  (segment (start 112.252274 110.789522) (end 112.270145 110.761081) (width 0.109) (layer "In6.Cu") (net 39))
  (segment (start 107.728523 110.482725) (end 107.752274 110.506476) (width 0.109) (layer "In6.Cu") (net 39))
  (segment (start 117.499216 108.934532) (end 117.531963 108.927057) (width 0.109) (layer "In6.Cu") (net 39))
  (segment (start 118.033691 108.441017) (end 118.048265 108.410754) (width 0.109) (layer "In6.Cu") (net 39))
  (segment (start 114.399854 110.761081) (end 114.417725 110.789522) (width 0.109) (layer "In6.Cu") (net 39))
  (segment (start 112.885 110.695999) (end 112.885 110.204001) (width 0.109) (layer "In6.Cu") (net 39))
  (segment (start 117.363453 108.076395) (end 117.396199 108.08387) (width 0.109) (layer "In6.Cu") (net 39))
  (segment (start 117.197601 108.242245) (end 117.1976 108.208657) (width 0.109) (layer "In6.Cu") (net 39))
  (segment (start 108.300082 110.068856) (end 108.328523 110.086727) (width 0.109) (layer "In6.Cu") (net 39))
  (segment (start 117.185167 109.129932) (end 117.164224 109.10367) (width 0.109) (layer "In6.Cu") (net 39))
  (segment (start 116.032858 110.447171) (end 116.0538 110.420909) (width 0.109) (layer "In6.Cu") (net 39))
  (segment (start 110.635 110.054001) (end 110.668378 110.057762) (width 0.109) (layer "In6.Cu") (net 39))
  (segment (start 118.437011 108.043017) (end 118.457953 108.016755) (width 0.109) (layer "In6.Cu") (net 39))
  (segment (start 112.168378 110.842238) (end 112.200082 110.831144) (width 0.109) (layer "In6.Cu") (net 39))
  (segment (start 109.885 110.204001) (end 109.88876 110.170623) (width 0.109) (layer "In6.Cu") (net 39))
  (segment (start 112.870145 110.761081) (end 112.881239 110.729377) (width 0.109) (layer "In6.Cu") (net 39))
  (segment (start 118.480001 107.953745) (end 118.480001 107.920156) (width 0.109) (layer "In6.Cu") (net 39))
  (segment (start 109.641476 110.813273) (end 109.669917 110.831144) (width 0.109) (layer "In6.Cu") (net 39))
  (segment (start 108.699854 110.138919) (end 108.717725 110.110478) (width 0.109) (layer "In6.Cu") (net 39))
  (segment (start 114.652274 110.789522) (end 114.670145 110.761081) (width 0.109) (layer "In6.Cu") (net 39))
  (segment (start 117.857141 108.502795) (end 117.889889 108.51027) (width 0.109) (layer "In6.Cu") (net 39))
  (segment (start 107.817725 110.789522) (end 107.841476 110.813273) (width 0.109) (layer "In6.Cu") (net 39))
  (segment (start 109.069917 110.831144) (end 109.101621 110.842238) (width 0.109) (layer "In6.Cu") (net 39))
  (segment (start 113.700082 110.068856) (end 113.728523 110.086727) (width 0.109) (layer "In6.Cu") (net 39))
  (segment (start 113.185 110.204001) (end 113.185 110.695999) (width 0.109) (layer "In6.Cu") (net 39))
  (segment (start 115.752845 110.37929) (end 115.820726 110.447171) (width 0.109) (layer "In6.Cu") (net 39))
  (segment (start 110.001621 110.057762) (end 110.035 110.054001) (width 0.109) (layer "In6.Cu") (net 39))
  (segment (start 113.569917 110.068856) (end 113.601621 110.057762) (width 0.109) (layer "In6.Cu") (net 39))
  (segment (start 114.952274 110.110478) (end 114.970145 110.138919) (width 0.109) (layer "In6.Cu") (net 39))
  (segment (start 118.211976 107.22787) (end 118.244722 107.235345) (width 0.109) (layer "In6.Cu") (net 39))
  (segment (start 114.670145 110.761081) (end 114.681239 110.729377) (width 0.109) (layer "In6.Cu") (net 39))
  (segment (start 115.741488 109.639498) (end 115.774236 109.632023) (width 0.109) (layer "In6.Cu") (net 39))
  (segment (start 114.985 110.204001) (end 114.985 110.3) (width 0.109) (layer "In6.Cu") (net 39))
  (segment (start 118.425654 107.37426) (end 118.4584 107.381733) (width 0.109) (layer "In6.Cu") (net 39))
  (segment (start 117.376355 108.891541) (end 117.402616 108.912484) (width 0.109) (layer "In6.Cu") (net 39))
  (segment (start 110.601621 110.057762) (end 110.635 110.054001) (width 0.109) (layer "In6.Cu") (net 39))
  (segment (start 117.008617 109.351319) (end 117.041364 109.358794) (width 0.109) (layer "In6.Cu") (net 39))
  (segment (start 108.717725 110.110478) (end 108.741476 110.086727) (width 0.109) (layer "In6.Cu") (net 39))
  (segment (start 112.881239 110.729377) (end 112.885 110.695999) (width 0.109) (layer "In6.Cu") (net 39))
  (segment (start 118.068173 107.297121) (end 118.089114 107.270861) (width 0.109) (layer "In6.Cu") (net 39))
  (segment (start 117.754124 107.652133) (end 117.787714 107.652132) (width 0.109) (layer "In6.Cu") (net 39))
  (segment (start 111.235 110.054001) (end 111.268378 110.057762) (width 0.109) (layer "In6.Cu") (net 39))
  (segment (start 117.028462 108.543647) (end 117.376355 108.891541) (width 0.109) (layer "In6.Cu") (net 39))
  (segment (start 107.770145 110.534917) (end 107.781239 110.566621) (width 0.109) (layer "In6.Cu") (net 39))
  (segment (start 117.199741 109.160195) (end 117.185167 109.129932) (width 0.109) (layer "In6.Cu") (net 39))
  (segment (start 115.846987 110.468114) (end 115.87725 110.482688) (width 0.109) (layer "In6.Cu") (net 39))
  (segment (start 111.681239 110.729377) (end 111.685 110.695999) (width 0.109) (layer "In6.Cu") (net 39))
  (segment (start 110.499854 110.138919) (end 110.517725 110.110478) (width 0.109) (layer "In6.Cu") (net 39))
  (segment (start 111.08876 110.170623) (end 111.099854 110.138919) (width 0.109) (layer "In6.Cu") (net 39))
  (segment (start 108.099854 110.138919) (end 108.117725 110.110478) (width 0.109) (layer "In6.Cu") (net 39))
  (segment (start 111.741476 110.086727) (end 111.769917 110.068856) (width 0.109) (layer "In6.Cu") (net 39))
  (segment (start 118.14564 107.235344) (end 118.178386 107.227871) (width 0.109) (layer "In6.Cu") (net 39))
  (segment (start 112.585 110.204001) (end 112.585 110.695999) (width 0.109) (layer "In6.Cu") (net 39))
  (segment (start 113.841476 110.813273) (end 113.869917 110.831144) (width 0.109) (layer "In6.Cu") (net 39))
  (segment (start 111.600082 110.831144) (end 111.628523 110.813273) (width 0.109) (layer "In6.Cu") (net 39))
  (segment (start 108.081239 110.729377) (end 108.085 110.695999) (width 0.109) (layer "In6.Cu") (net 39))
  (segment (start 112.017725 110.789522) (end 112.041476 110.813273) (width 0.109) (layer "In6.Cu") (net 39))
  (segment (start 111.000082 110.831144) (end 111.028523 110.813273) (width 0.109) (layer "In6.Cu") (net 39))
  (segment (start 113.241476 110.813273) (end 113.269917 110.831144) (width 0.109) (layer "In6.Cu") (net 39))
  (segment (start 107.901621 110.842238) (end 107.935 110.845999) (width 0.109) (layer "In6.Cu") (net 39))
  (segment (start 108.141476 110.086727) (end 108.169917 110.068856) (width 0.109) (layer "In6.Cu") (net 39))
  (segment (start 116.368296 109.716632) (end 116.353722 109.686369) (width 0.109) (layer "In6.Cu") (net 39))
  (segment (start 113.48876 110.170623) (end 113.499854 110.138919) (width 0.109) (layer "In6.Cu") (net 39))
  (segment (start 116.492637 109.966383) (end 116.500111 109.933636) (width 0.109) (layer "In6.Cu") (net 39))
  (segment (start 112.552274 110.110478) (end 112.570145 110.138919) (width 0.109) (layer "In6.Cu") (net 39))
  (segment (start 109.881239 110.729377) (end 109.885 110.695999) (width 0.109) (layer "In6.Cu") (net 39))
  (segment (start 107.935 110.845999) (end 107.968378 110.842238) (width 0.109) (layer "In6.Cu") (net 39))
  (segment (start 114.328523 110.086727) (end 114.352274 110.110478) (width 0.109) (layer "In6.Cu") (net 39))
  (segment (start 108.085 110.695999) (end 108.085 110.204001) (width 0.109) (layer "In6.Cu") (net 39))
  (segment (start 110.068378 110.057762) (end 110.100082 110.068856) (width 0.109) (layer "In6.Cu") (net 39))
  (segment (start 107.841476 110.813273) (end 107.869917 110.831144) (width 0.109) (layer "In6.Cu") (net 39))
  (segment (start 112.285 110.695999) (end 112.285 110.204001) (width 0.109) (layer "In6.Cu") (net 39))
  (segment (start 109.599854 110.761081) (end 109.617725 110.789522) (width 0.109) (layer "In6.Cu") (net 39))
  (segment (start 108.381239 110.170623) (end 108.385 110.204001) (width 0.109) (layer "In6.Cu") (net 39))
  (segment (start 117.207215 109.192942) (end 117.199741 109.160195) (width 0.109) (layer "In6.Cu") (net 39))
  (segment (start 114.370145 110.138919) (end 114.381239 110.170623) (width 0.109) (layer "In6.Cu") (net 39))
  (segment (start 113.199854 110.761081) (end 113.217725 110.789522) (width 0.109) (layer "In6.Cu") (net 39))
  (segment (start 113.668378 110.057762) (end 113.700082 110.068856) (width 0.109) (layer "In6.Cu") (net 39))
  (segment (start 117.266853 108.098444) (end 117.297117 108.083869) (width 0.109) (layer "In6.Cu") (net 39))
  (segment (start 109.88876 110.170623) (end 109.899854 110.138919) (width 0.109) (layer "In6.Cu") (net 39))
  (segment (start 111.028523 110.813273) (end 111.052274 110.789522) (width 0.109) (layer "In6.Cu") (net 39))
  (segment (start 111.141476 110.086727) (end 111.169917 110.068856) (width 0.109) (layer "In6.Cu") (net 39))
  (segment (start 115.897096 109.675014) (end 116.244989 110.022908) (width 0.109) (layer "In6.Cu") (net 39))
  (segment (start 115.597237 110.343773) (end 115.629984 110.336299) (width 0.109) (layer "In6.Cu") (net 39))
  (segment (start 112.468378 110.057762) (end 112.500082 110.068856) (width 0.109) (layer "In6.Cu") (net 39))
  (segment (start 117.562226 108.912483) (end 117.588487 108.891541) (width 0.109) (layer "In6.Cu") (net 39))
  (segment (start 110.199854 110.761081) (end 110.217725 110.789522) (width 0.109) (layer "In6.Cu") (net 39))
  (segment (start 116.032858 110.235038) (end 115.684964 109.887145) (width 0.109) (layer "In6.Cu") (net 39))
  (segment (start 114.801621 110.057762) (end 114.835 110.054001) (width 0.109) (layer "In6.Cu") (net 39))
  (segment (start 116.728604 109.212406) (end 116.761351 109.204932) (width 0.109) (layer "In6.Cu") (net 39))
  (segment (start 110.481239 110.729377) (end 110.485 110.695999) (width 0.109) (layer "In6.Cu") (net 39))
  (segment (start 116.0538 110.420909) (end 116.068374 110.390646) (width 0.109) (layer "In6.Cu") (net 39))
  (segment (start 108.835 110.054001) (end 108.868378 110.057762) (width 0.109) (layer "In6.Cu") (net 39))
  (segment (start 118.046123 107.360132) (end 118.053598 107.327385) (width 0.109) (layer "In6.Cu") (net 39))
  (segment (start 113.517725 110.110478) (end 113.541476 110.086727) (width 0.109) (layer "In6.Cu") (net 39))
  (segment (start 117.588486 108.679408) (end 117.240593 108.331516) (width 0.109) (layer "In6.Cu") (net 39))
  (segment (start 108.98876 110.729377) (end 108.999854 110.761081) (width 0.109) (layer "In6.Cu") (net 39))
  (segment (start 115.641973 109.797874) (end 115.641973 109.764284) (width 0.109) (layer "In6.Cu") (net 39))
  (segment (start 118.068171 107.456732) (end 118.053598 107.426469) (width 0.109) (layer "In6.Cu") (net 39))
  (segment (start 113.269917 110.831144) (end 113.301621 110.842238) (width 0.109) (layer "In6.Cu") (net 39))
  (segment (start 108.68876 110.170623) (end 108.699854 110.138919) (width 0.109) (layer "In6.Cu") (net 39))
  (segment (start 109.669917 110.831144) (end 109.701621 110.842238) (width 0.109) (layer "In6.Cu") (net 39))
  (segment (start 110.668378 110.057762) (end 110.700082 110.068856) (width 0.109) (layer "In6.Cu") (net 39))
  (segment (start 112.701621 110.842238) (end 112.735 110.845999) (width 0.109) (layer "In6.Cu") (net 39))
  (segment (start 111.652274 110.789522) (end 111.670145 110.761081) (width 0.109) (layer "In6.Cu") (net 39))
  (segment (start 112.285 110.204001) (end 112.28876 110.170623) (width 0.109) (layer "In6.Cu") (net 39))
  (segment (start 116.33426 110.065899) (end 116.36785 110.065899) (width 0.109) (layer "In6.Cu") (net 39))
  (segment (start 109.800082 110.831144) (end 109.828523 110.813273) (width 0.109) (layer "In6.Cu") (net 39))
  (segment (start 113.100082 110.068856) (end 113.128523 110.086727) (width 0.109) (layer "In6.Cu") (net 39))
  (segment (start 118.055739 108.344418) (end 118.048265 108.311671) (width 0.109) (layer "In6.Cu") (net 39))
  (segment (start 117.923478 108.51027) (end 117.956225 108.502795) (width 0.109) (layer "In6.Cu") (net 39))
  (segment (start 115.976334 110.482688) (end 116.006597 110.468114) (width 0.109) (layer "In6.Cu") (net 39))
  (segment (start 113.781239 110.170623) (end 113.785 110.204001) (width 0.109) (layer "In6.Cu") (net 39))
  (segment (start 112.885 110.204001) (end 112.88876 110.170623) (width 0.109) (layer "In6.Cu") (net 39))
  (segment (start 111.268378 110.057762) (end 111.300082 110.068856) (width 0.109) (layer "In6.Cu") (net 39))
  (segment (start 118.457953 107.857146) (end 118.43701 107.830884) (width 0.109) (layer "In6.Cu") (net 39))
  (segment (start 117.986488 108.488221) (end 118.012749 108.467279) (width 0.109) (layer "In6.Cu") (net 39))
  (segment (start 109.552274 110.110478) (end 109.570145 110.138919) (width 0.109) (layer "In6.Cu") (net 39))
  (segment (start 114.681239 110.729377) (end 114.685 110.695999) (width 0.109) (layer "In6.Cu") (net 39))
  (segment (start 116.816331 108.755778) (end 116.795386 108.729519) (width 0.109) (layer "In6.Cu") (net 39))
  (segment (start 110.368378 110.842238) (end 110.400082 110.831144) (width 0.109) (layer "In6.Cu") (net 39))
  (segment (start 108.985 110.695999) (end 108.98876 110.729377) (width 0.109) (layer "In6.Cu") (net 39))
  (segment (start 110.170145 110.138919) (end 110.181239 110.170623) (width 0.109) (layer "In6.Cu") (net 39))
  (segment (start 115.943587 110.490162) (end 115.976334 110.482688) (width 0.109) (layer "In6.Cu") (net 39))
  (segment (start 118.115376 107.249919) (end 118.14564 107.235344) (width 0.109) (layer "In6.Cu") (net 39))
  (segment (start 108.868378 110.057762) (end 108.900082 110.068856) (width 0.109) (layer "In6.Cu") (net 39))
  (segment (start 114.717725 110.110478) (end 114.741476 110.086727) (width 0.109) (layer "In6.Cu") (net 39))
  (segment (start 111.685 110.204001) (end 111.68876 110.170623) (width 0.109) (layer "In6.Cu") (net 39))
  (segment (start 116.816329 108.543648) (end 116.842591 108.522706) (width 0.109) (layer "In6.Cu") (net 39))
  (segment (start 109.969917 110.068856) (end 110.001621 110.057762) (width 0.109) (layer "In6.Cu") (net 39))
  (segment (start 115.664021 109.860884) (end 115.649446 109.830622) (width 0.109) (layer "In6.Cu") (net 39))
  (segment (start 117.329863 108.076396) (end 117.363453 108.076395) (width 0.109) (layer "In6.Cu") (net 39))
  (segment (start 111.801621 110.057762) (end 111.835 110.054001) (width 0.109) (layer "In6.Cu") (net 39))
  (segment (start 117.609429 108.865279) (end 117.624003 108.835016) (width 0.109) (layer "In6.Cu") (net 39))
  (segment (start 109.852274 110.789522) (end 109.870145 110.761081) (width 0.109) (layer "In6.Cu") (net 39))
  (segment (start 114.417725 110.789522) (end 114.441476 110.813273) (width 0.109) (layer "In6.Cu") (net 39))
  (segment (start 111.370145 110.138919) (end 111.381239 110.170623) (width 0.109) (layer "In6.Cu") (net 39))
  (segment (start 114.385 110.695999) (end 114.38876 110.729377) (width 0.109) (layer "In6.Cu") (net 39))
  (segment (start 117.624003 108.735933) (end 117.609429 108.70567) (width 0.109) (layer "In6.Cu") (net 39))
  (segment (start 115.69632 110.343773) (end 115.726583 110.358347) (width 0.109) (layer "In6.Cu") (net 39))
  (segment (start 113.728523 110.086727) (end 113.752274 110.110478) (width 0.109) (layer "In6.Cu") (net 39))
  (segment (start 112.528523 110.086727) (end 112.552274 110.110478) (width 0.109) (layer "In6.Cu") (net 39))
  (segment (start 111.085 110.204001) (end 111.08876 110.170623) (width 0.109) (layer "In6.Cu") (net 39))
  (segment (start 115.909997 110.490162) (end 115.943587 110.490162) (width 0.109) (layer "In6.Cu") (net 39))
  (segment (start 111.98876 110.729377) (end 111.999854 110.761081) (width 0.109) (layer "In6.Cu") (net 39))
  (segment (start 116.492637 109.8673) (end 116.478063 109.837037) (width 0.109) (layer "In6.Cu") (net 39))
  (segment (start 107.869917 110.831144) (end 107.901621 110.842238) (width 0.109) (layer "In6.Cu") (net 39))
  (segment (start 117.432879 108.927057) (end 117.465627 108.934532) (width 0.109) (layer "In6.Cu") (net 39))
  (segment (start 108.469917 110.831144) (end 108.501621 110.842238) (width 0.109) (layer "In6.Cu") (net 39))
  (segment (start 117.185167 109.289541) (end 117.199741 109.259278) (width 0.109) (layer "In6.Cu") (net 39))
  (segment (start 110.901621 110.842238) (end 110.935 110.845999) (width 0.109) (layer "In6.Cu") (net 39))
  (segment (start 119 99.205) (end 117.9 98.105) (width 0.109) (layer "In6.Cu") (net 39))
  (segment (start 115.017725 110.393524) (end 115.041476 110.417275) (width 0.109) (layer "In6.Cu") (net 39))
  (segment (start 118.314151 108.086008) (end 118.34774 108.086008) (width 0.109) (layer "In6.Cu") (net 39))
  (segment (start 116.368296 109.557022) (end 116.389239 109.530761) (width 0.109) (layer "In6.Cu") (net 39))
  (segment (start 116.761351 109.204932) (end 116.79494 109.204932) (width 0.109) (layer "In6.Cu") (net 39))
  (segment (start 114.000082 110.831144) (end 114.028523 110.813273) (width 0.109) (layer "In6.Cu") (net 39))
  (segment (start 111.085 110.695999) (end 111.085 110.204001) (width 0.109) (layer "In6.Cu") (net 39))
  (segment (start 116.346248 109.653622) (end 116.346248 109.620032) (width 0.109) (layer "In6.Cu") (net 39))
  (segment (start 114.928523 110.086727) (end 114.952274 110.110478) (width 0.109) (layer "In6.Cu") (net 39))
  (segment (start 117.631477 108.76868) (end 117.624003 108.735933) (width 0.109) (layer "In6.Cu") (net 39))
  (segment (start 116.353722 109.686369) (end 116.346248 109.653622) (width 0.109) (layer "In6.Cu") (net 39))
  (segment (start 118.480001 107.920156) (end 118.472527 107.887409) (width 0.109) (layer "In6.Cu") (net 39))
  (segment (start 108.981239 110.170623) (end 108.985 110.204001) (width 0.109) (layer "In6.Cu") (net 39))
  (segment (start 118.39539 107.359685) (end 118.425654 107.37426) (width 0.109) (layer "In6.Cu") (net 39))
  (segment (start 114.600082 110.831144) (end 114.628523 110.813273) (width 0.109) (layer "In6.Cu") (net 39))
  (segment (start 116.85795 109.22698) (end 116.884212 109.247922) (width 0.109) (layer "In6.Cu") (net 39))
  (segment (start 109.58876 110.729377) (end 109.599854 110.761081) (width 0.109) (layer "In6.Cu") (net 39))
  (segment (start 117.721378 107.659606) (end 117.754124 107.652133) (width 0.109) (layer "In6.Cu") (net 39))
  (segment (start 110.935 110.845999) (end 110.968378 110.842238) (width 0.109) (layer "In6.Cu") (net 39))
  (segment (start 116.971937 108.508132) (end 117.002201 108.522705) (width 0.109) (layer "In6.Cu") (net 39))
  (segment (start 108.600082 110.831144) (end 108.628523 110.813273) (width 0.109) (layer "In6.Cu") (net 39))
  (segment (start 111.835 110.054001) (end 111.868378 110.057762) (width 0.109) (layer "In6.Cu") (net 39))
  (segment (start 111.328523 110.086727) (end 111.352274 110.110478) (width 0.109) (layer "In6.Cu") (net 39))
  (segment (start 117.452724 108.119385) (end 117.800617 108.467279) (width 0.109) (layer "In6.Cu") (net 39))
  (segment (start 118.089114 107.270861) (end 118.115376 107.249919) (width 0.109) (layer "In6.Cu") (net 39))
  (segment (start 111.985 110.204001) (end 111.985 110.695999) (width 0.109) (layer "In6.Cu") (net 39))
  (segment (start 113.499854 110.138919) (end 113.517725 110.110478) (width 0.109) (layer "In6.Cu") (net 39))
  (segment (start 110.152274 110.110478) (end 110.170145 110.138919) (width 0.109) (layer "In6.Cu") (net 39))
  (segment (start 113.18876 110.729377) (end 113.199854 110.761081) (width 0.109) (layer "In6.Cu") (net 39))
  (segment (start 110.569917 110.068856) (end 110.601621 110.057762) (width 0.109) (layer "In6.Cu") (net 39))
  (segment (start 109.369917 110.068856) (end 109.401621 110.057762) (width 0.109) (layer "In6.Cu") (net 39))
  (segment (start 117.21965 108.145646) (end 117.240591 108.119386) (width 0.109) (layer "In6.Cu") (net 39))
  (segment (start 118.053598 107.426469) (end 118.046124 107.39372) (width 0.109) (layer "In6.Cu") (net 39))
  (segment (start 112.599854 110.761081) (end 112.617725 110.789522) (width 0.109) (layer "In6.Cu") (net 39))
  (segment (start 114.835 110.054001) (end 114.868378 110.057762) (width 0.109) (layer "In6.Cu") (net 39))
  (segment (start 108.952274 110.110478) (end 108.970145 110.138919) (width 0.109) (layer "In6.Cu") (net 39))
  (segment (start 117.826878 108.488222) (end 117.857141 108.502795) (width 0.109) (layer "In6.Cu") (net 39))
  (segment (start 109.101621 110.842238) (end 109.135 110.845999) (width 0.109) (layer "In6.Cu") (net 39))
  (segment (start 110.485 110.204001) (end 110.48876 110.170623) (width 0.109) (layer "In6.Cu") (net 39))
  (segment (start 111.201621 110.057762) (end 111.235 110.054001) (width 0.109) (layer "In6.Cu") (net 39))
  (segment (start 115.840572 109.639497) (end 115.870834 109.654072) (width 0.109) (layer "In6.Cu") (net 39))
  (segment (start 110.517725 110.110478) (end 110.541476 110.086727) (width 0.109) (layer "In6.Cu") (net 39))
  (segment (start 108.501621 110.842238) (end 108.535 110.845999) (width 0.109) (layer "In6.Cu") (net 39))
  (segment (start 114.568378 110.842238) (end 114.600082 110.831144) (width 0.109) (layer "In6.Cu") (net 39))
  (segment (start 117.041364 109.358794) (end 117.074954 109.358794) (width 0.109) (layer "In6.Cu") (net 39))
  (segment (start 115.684964 109.887145) (end 115.664021 109.860884) (width 0.109) (layer "In6.Cu") (net 39))
  (segment (start 117.82046 107.659607) (end 117.850724 107.67418) (width 0.109) (layer "In6.Cu") (net 39))
  (segment (start 116.795386 108.729519) (end 116.780813 108.699256) (width 0.109) (layer "In6.Cu") (net 39))
  (segment (start 116.43086 110.043851) (end 116.457121 110.022908) (width 0.109) (layer "In6.Cu") (net 39))
  (segment (start 110.799854 110.761081) (end 110.817725 110.789522) (width 0.109) (layer "In6.Cu") (net 39))
  (segment (start 117.9 98.105) (end 116.975 98.105) (width 0.109) (layer "In6.Cu") (net 39))
  (segment (start 110.485 110.695999) (end 110.485 110.204001) (width 0.109) (layer "In6.Cu") (net 39))
  (segment (start 108.169917 110.068856) (end 108.201621 110.057762) (width 0.109) (layer "In6.Cu") (net 39))
  (segment (start 110.185 110.204001) (end 110.185 110.695999) (width 0.109) (layer "In6.Cu") (net 39))
  (segment (start 114.699854 110.138919) (end 114.717725 110.110478) (width 0.109) (layer "In6.Cu") (net 39))
  (segment (start 111.469917 110.831144) (end 111.501621 110.842238) (width 0.109) (layer "In6.Cu") (net 39))
  (segment (start 109.500082 110.068856) (end 109.528523 110.086727) (width 0.109) (layer "In6.Cu") (net 39))
  (segment (start 116.500111 109.900047) (end 116.492637 109.8673) (width 0.109) (layer "In6.Cu") (net 39))
  (segment (start 117.1976 108.208657) (end 117.205075 108.17591) (width 0.109) (layer "In6.Cu") (net 39))
  (segment (start 114.981239 110.170623) (end 114.985 110.204001) (width 0.109) (layer "In6.Cu") (net 39))
  (segment (start 112.570145 110.138919) (end 112.581239 110.170623) (width 0.109) (layer "In6.Cu") (net 39))
  (segment (start 112.969917 110.068856) (end 113.001621 110.057762) (width 0.109) (layer "In6.Cu") (net 39))
  (segment (start 112.669917 110.831144) (end 112.701621 110.842238) (width 0.109) (layer "In6.Cu") (net 39))
  (segment (start 114.141476 110.086727) (end 114.169917 110.068856) (width 0.109) (layer "In6.Cu") (net 39))
  (segment (start 118.178386 107.227871) (end 118.211976 107.22787) (width 0.109) (layer "In6.Cu") (net 39))
  (segment (start 108.268378 110.057762) (end 108.300082 110.068856) (width 0.109) (layer "In6.Cu") (net 39))
  (segment (start 107.799854 110.761081) (end 107.817725 110.789522) (width 0.109) (layer "In6.Cu") (net 39))
  (segment (start 115.870834 109.654072) (end 115.897096 109.675014) (width 0.109) (layer "In6.Cu") (net 39))
  (segment (start 113.001621 110.057762) (end 113.035 110.054001) (width 0.109) (layer "In6.Cu") (net 39))
  (segment (start 110.269917 110.831144) (end 110.301621 110.842238) (width 0.109) (layer "In6.Cu") (net 39))
  (segment (start 110.728523 110.086727) (end 110.752274 110.110478) (width 0.109) (layer "In6.Cu") (net 39))
  (segment (start 115.711226 109.654071) (end 115.741488 109.639498) (width 0.109) (layer "In6.Cu") (net 39))
  (segment (start 110.335 110.845999) (end 110.368378 110.842238) (width 0.109) (layer "In6.Cu") (net 39))
  (segment (start 110.428523 110.813273) (end 110.452274 110.789522) (width 0.109) (layer "In6.Cu") (net 39))
  (segment (start 116.068374 110.390646) (end 116.075848 110.357899) (width 0.109) (layer "In6.Cu") (net 39))
  (segment (start 116.457121 110.022908) (end 116.478063 109.996646) (width 0.109) (layer "In6.Cu") (net 39))
  (segment (start 115.101621 110.44624) (end 115.135 110.45) (width 0.109) (layer "In6.Cu") (net 39))
  (segment (start 109.917725 110.110478) (end 109.941476 110.086727) (width 0.109) (layer "In6.Cu") (net 39))
  (segment (start 115.566974 110.358347) (end 115.597237 110.343773) (width 0.109) (layer "In6.Cu") (net 39))
  (segment (start 108.769917 110.068856) (end 108.801621 110.057762) (width 0.109) (layer "In6.Cu") (net 39))
  (segment (start 110.470145 110.761081) (end 110.481239 110.729377) (width 0.109) (layer "In6.Cu") (net 39))
  (segment (start 116.773338 108.632919) (end 116.780813 108.600172) (width 0.109) (layer "In6.Cu") (net 39))
  (segment (start 108.028523 110.813273) (end 108.052274 110.789522) (width 0.109) (layer "In6.Cu") (net 39))
  (segment (start 118.380487 108.078533) (end 118.41075 108.063959) (width 0.109) (layer "In6.Cu") (net 39))
  (segment (start 117.164224 109.10367) (end 116.816331 108.755778) (width 0.109) (layer "In6.Cu") (net 39))
  (segment (start 116.978354 109.336746) (end 117.008617 109.351319) (width 0.109) (layer "In6.Cu") (net 39))
  (segment (start 114.385 110.204001) (end 114.385 110.695999) (width 0.109) (layer "In6.Cu") (net 39))
  (segment (start 111.417725 110.789522) (end 111.441476 110.813273) (width 0.109) (layer "In6.Cu") (net 39))
  (segment (start 113.368378 110.842238) (end 113.400082 110.831144) (width 0.109) (layer "In6.Cu") (net 39))
  (segment (start 111.717725 110.110478) (end 111.741476 110.086727) (width 0.109) (layer "In6.Cu") (net 39))
  (segment (start 110.181239 110.170623) (end 110.185 110.204001) (width 0.109) (layer "In6.Cu") (net 39))
  (segment (start 115.774236 109.632023) (end 115.807824 109.632024) (width 0.109) (layer "In6.Cu") (net 39))
  (segment (start 113.935 110.845999) (end 113.968378 110.842238) (width 0.109) (layer "In6.Cu") (net 39))
  (segment (start 114.999854 110.365083) (end 115.017725 110.393524) (width 0.109) (layer "In6.Cu") (net 39))
  (segment (start 111.052274 110.789522) (end 111.070145 110.761081) (width 0.109) (layer "In6.Cu") (net 39))
  (segment (start 116.827687 109.212406) (end 116.85795 109.22698) (width 0.109) (layer "In6.Cu") (net 39))
  (segment (start 111.868378 110.057762) (end 111.900082 110.068856) (width 0.109) (layer "In6.Cu") (net 39))
  (segment (start 109.585 110.204001) (end 109.585 110.695999) (width 0.109) (layer "In6.Cu") (net 39))
  (segment (start 117.426463 108.098443) (end 117.452724 108.119385) (width 0.109) (layer "In6.Cu") (net 39))
  (segment (start 109.435 110.054001) (end 109.468378 110.057762) (width 0.109) (layer "In6.Cu") (net 39))
  (segment (start 111.501621 110.842238) (end 111.535 110.845999) (width 0.109) (layer "In6.Cu") (net 39))
  (segment (start 109.228523 110.813273) (end 109.252274 110.789522) (width 0.109) (layer "In6.Cu") (net 39))
  (segment (start 111.952274 110.110478) (end 111.970145 110.138919) (width 0.109) (layer "In6.Cu") (net 39))
  (segment (start 108.685 110.695999) (end 108.685 110.204001) (width 0.109) (layer "In6.Cu") (net 39))
  (segment (start 111.399854 110.761081) (end 111.417725 110.789522) (width 0.109) (layer "In6.Cu") (net 39))
  (segment (start 112.88876 110.170623) (end 112.899854 110.138919) (width 0.109) (layer "In6.Cu") (net 39))
  (segment (start 110.185 110.695999) (end 110.18876 110.729377) (width 0.109) (layer "In6.Cu") (net 39))
  (segment (start 108.741476 110.086727) (end 108.769917 110.068856) (width 0.109) (layer "In6.Cu") (net 39))
  (segment (start 108.117725 110.110478) (end 108.141476 110.086727) (width 0.109) (layer "In6.Cu") (net 39))
  (segment (start 109.401621 110.057762) (end 109.435 110.054001) (width 0.109) (layer "In6.Cu") (net 39))
  (segment (start 117.107701 109.351319) (end 117.137964 109.336745) (width 0.109) (layer "In6.Cu") (net 39))
  (segment (start 114.300082 110.068856) (end 114.328523 110.086727) (width 0.109) (layer "In6.Cu") (net 39))
  (segment (start 113.869917 110.831144) (end 113.901621 110.842238) (width 0.109) (layer "In6.Cu") (net 39))
  (segment (start 112.641476 110.813273) (end 112.669917 110.831144) (width 0.109) (layer "In6.Cu") (net 39))
  (segment (start 118.43701 107.830884) (end 118.089116 107.482991) (width 0.109) (layer "In6.Cu") (net 39))
  (segment (start 115.649446 109.830622) (end 115.641973 109.797874) (width 0.109) (layer "In6.Cu") (net 39))
  (segment (start 109.28876 110.170623) (end 109.299854 110.138919) (width 0.109) (layer "In6.Cu") (net 39))
  (segment (start 113.181239 110.170623) (end 113.185 110.204001) (width 0.109) (layer "In6.Cu") (net 39))
  (segment (start 108.441476 110.813273) (end 108.469917 110.831144) (width 0.109) (layer "In6.Cu") (net 39))
  (segment (start 108.000082 110.831144) (end 108.028523 110.813273) (width 0.109) (layer "In6.Cu") (net 39))
  (segment (start 117.876985 107.695122) (end 118.224879 108.043017) (width 0.109) (layer "In6.Cu") (net 39))
  (segment (start 112.341476 110.086727) (end 112.369917 110.068856) (width 0.109) (layer "In6.Cu") (net 39))
  (segment (start 112.28876 110.170623) (end 112.299854 110.138919) (width 0.109) (layer "In6.Cu") (net 39))
  (segment (start 116.842591 108.522706) (end 116.872855 108.508131) (width 0.109) (layer "In6.Cu") (net 39))
  (segment (start 109.528523 110.086727) (end 109.552274 110.110478) (width 0.109) (layer "In6.Cu") (net 39))
  (segment (start 110.452274 110.789522) (end 110.470145 110.761081) (width 0.109) (layer "In6.Cu") (net 39))
  (segment (start 108.999854 110.761081) (end 109.017725 110.789522) (width 0.109) (layer "In6.Cu") (net 39))
  (segment (start 112.401621 110.057762) (end 112.435 110.054001) (width 0.109) (layer "In6.Cu") (net 39))
  (segment (start 113.470145 110.761081) (end 113.481239 110.729377) (width 0.109) (layer "In6.Cu") (net 39))
  (segment (start 110.18876 110.729377) (end 110.199854 110.761081) (width 0.109) (layer "In6.Cu") (net 39))
  (segment (start 112.581239 110.170623) (end 112.585 110.204001) (width 0.109) (layer "In6.Cu") (net 39))
  (segment (start 117.664852 107.695123) (end 117.691114 107.674181) (width 0.109) (layer "In6.Cu") (net 39))
  (segment (start 116.939191 108.500657) (end 116.971937 108.508132) (width 0.109) (layer "In6.Cu") (net 39))
  (segment (start 112.852274 110.789522) (end 112.870145 110.761081) (width 0.109) (layer "In6.Cu") (net 39))
  (segment (start 113.185 110.695999) (end 113.18876 110.729377) (width 0.109) (layer "In6.Cu") (net 39))
  (segment (start 112.101621 110.842238) (end 112.135 110.845999) (width 0.109) (layer "In6.Cu") (net 39))
  (segment (start 116.773339 108.666507) (end 116.773338 108.632919) (width 0.109) (layer "In6.Cu") (net 39))
  (segment (start 118.4584 107.381733) (end 118.49199 107.381733) (width 0.109) (layer "In6.Cu") (net 39))
  (segment (start 107.968378 110.842238) (end 108.000082 110.831144) (width 0.109) (layer "In6.Cu") (net 39))
  (segment (start 114.970145 110.138919) (end 114.981239 110.170623) (width 0.109) (layer "In6.Cu") (net 39))
  (segment (start 118.046124 107.39372) (end 118.046123 107.360132) (width 0.109) (layer "In6.Cu") (net 39))
  (segment (start 112.828523 110.813273) (end 112.852274 110.789522) (width 0.109) (layer "In6.Cu") (net 39))
  (segment (start 114.769917 110.068856) (end 114.801621 110.057762) (width 0.109) (layer "In6.Cu") (net 39))
  (segment (start 108.970145 110.138919) (end 108.981239 110.170623) (width 0.109) (layer "In6.Cu") (net 39))
  (segment (start 111.985 110.695999) (end 111.98876 110.729377) (width 0.109) (layer "In6.Cu") (net 39))
  (segment (start 109.735 110.845999) (end 109.768378 110.842238) (width 0.109) (layer "In6.Cu") (net 39))
  (segment (start 109.701621 110.842238) (end 109.735 110.845999) (width 0.109) (layer "In6.Cu") (net 39))
  (segment (start 112.299854 110.138919) (end 112.317725 110.110478) (width 0.109) (layer "In6.Cu") (net 39))
  (segment (start 113.901621 110.842238) (end 113.935 110.845999) (width 0.109) (layer "In6.Cu") (net 39))
  (segment (start 115.641973 109.764284) (end 115.649446 109.731538) (width 0.109) (layer "In6.Cu") (net 39))
  (segment (start 108.352274 110.110478) (end 108.370145 110.138919) (width 0.109) (layer "In6.Cu") (net 39))
  (segment (start 110.78876 110.729377) (end 110.799854 110.761081) (width 0.109) (layer "In6.Cu") (net 39))
  (segment (start 114.469917 110.831144) (end 114.501621 110.842238) (width 0.109) (layer "In6.Cu") (net 39))
  (segment (start 114.099854 110.138919) (end 114.117725 110.110478) (width 0.109) (layer "In6.Cu") (net 39))
  (segment (start 107.785 110.695999) (end 107.78876 110.729377) (width 0.109) (layer "In6.Cu") (net 39))
  (segment (start 116.952093 109.315803) (end 116.978354 109.336746) (width 0.109) (layer "In6.Cu") (net 39))
  (segment (start 115.684964 109.675013) (end 115.711226 109.654071) (width 0.109) (layer "In6.Cu") (net 39))
  (segment (start 108.670145 110.761081) (end 108.681239 110.729377) (width 0.109) (layer "In6.Cu") (net 39))
  (segment (start 111.441476 110.813273) (end 111.469917 110.831144) (width 0.109) (layer "In6.Cu") (net 39))
  (segment (start 113.170145 110.138919) (end 113.181239 110.170623) (width 0.109) (layer "In6.Cu") (net 39))
  (segment (start 109.885 110.695999) (end 109.885 110.204001) (width 0.109) (layer "In6.Cu") (net 39))
  (segment (start 109.252274 110.789522) (end 109.270145 110.761081) (width 0.109) (layer "In6.Cu") (net 39))
  (segment (start 115.649446 109.731538) (end 115.664021 109.701274) (width 0.109) (layer "In6.Cu") (net 39))
  (segment (start 109.468378 110.057762) (end 109.500082 110.068856) (width 0.109) (layer "In6.Cu") (net 39))
  (segment (start 111.68876 110.170623) (end 111.699854 110.138919) (width 0.109) (layer "In6.Cu") (net 39))
  (segment (start 115.87725 110.482688) (end 115.909997 110.490162) (width 0.109) (layer "In6.Cu") (net 39))
  (segment (start 117.956225 108.502795) (end 117.986488 108.488221) (width 0.109) (layer "In6.Cu") (net 39))
  (segment (start 111.999854 110.761081) (end 112.017725 110.789522) (width 0.109) (layer "In6.Cu") (net 39))
  (segment (start 109.200082 110.831144) (end 109.228523 110.813273) (width 0.109) (layer "In6.Cu") (net 39))
  (segment (start 108.201621 110.057762) (end 108.235 110.054001) (width 0.109) (layer "In6.Cu") (net 39))
  (segment (start 113.770145 110.138919) (end 113.781239 110.170623) (width 0.109) (layer "In6.Cu") (net 39))
  (segment (start 108.900082 110.068856) (end 108.928523 110.086727) (width 0.109) (layer "In6.Cu") (net 39))
  (segment (start 112.069917 110.831144) (end 112.101621 110.842238) (width 0.109) (layer "In6.Cu") (net 39))
  (segment (start 116.36785 110.065899) (end 116.400597 110.058425) (width 0.109) (layer "In6.Cu") (net 39))
  (segment (start 108.328523 110.086727) (end 108.352274 110.110478) (width 0.109) (layer "In6.Cu") (net 39))
  (segment (start 118.34774 108.086008) (end 118.380487 108.078533) (width 0.109) (layer "In6.Cu") (net 39))
  (segment (start 107.668378 110.45376) (end 107.700082 110.464854) (width 0.109) (layer "In6.Cu") (net 39))
  (segment (start 114.441476 110.813273) (end 114.469917 110.831144) (width 0.109) (layer "In6.Cu") (net 39))
  (segment (start 118.472527 107.986492) (end 118.480001 107.953745) (width 0.109) (layer "In6.Cu") (net 39))
  (segment (start 117.531963 108.927057) (end 117.562226 108.912483) (width 0.109) (layer "In6.Cu") (net 39))
  (segment (start 116.905601 108.500658) (end 116.939191 108.500657) (width 0.109) (layer "In6.Cu") (net 39))
  (segment (start 109.768378 110.842238) (end 109.800082 110.831144) (width 0.109) (layer "In6.Cu") (net 39))
  (segment (start 110.968378 110.842238) (end 111.000082 110.831144) (width 0.109) (layer "In6.Cu") (net 39))
  (segment (start 114.352274 110.110478) (end 114.370145 110.138919) (width 0.109) (layer "In6.Cu") (net 39))
  (segment (start 116.244989 110.022908) (end 116.27125 110.043851) (width 0.109) (layer "In6.Cu") (net 39))
  (segment (start 118.369129 107.338742) (end 118.39539 107.359685) (width 0.109) (layer "In6.Cu") (net 39))
  (segment (start 113.481239 110.729377) (end 113.485 110.695999) (width 0.109) (layer "In6.Cu") (net 39))
  (segment (start 110.400082 110.831144) (end 110.428523 110.813273) (width 0.109) (layer "In6.Cu") (net 39))
  (segment (start 117.889889 108.51027) (end 117.923478 108.51027) (width 0.109) (layer "In6.Cu") (net 39))
  (segment (start 109.299854 110.138919) (end 109.317725 110.110478) (width 0.109) (layer "In6.Cu") (net 39))
  (segment (start 111.352274 110.110478) (end 111.370145 110.138919) (width 0.109) (layer "In6.Cu") (net 39))
  (segment (start 118.555 107.359685) (end 118.581261 107.338742) (width 0.109) (layer "In6.Cu") (net 39))
  (segment (start 108.08876 110.170623) (end 108.099854 110.138919) (width 0.109) (layer "In6.Cu") (net 39))
  (segment (start 113.301621 110.842238) (end 113.335 110.845999) (width 0.109) (layer "In6.Cu") (net 39))
  (segment (start 110.128523 110.086727) (end 110.152274 110.110478) (width 0.109) (layer "In6.Cu") (net 39))
  (segment (start 114.868378 110.057762) (end 114.900082 110.068856) (width 0.109) (layer "In6.Cu") (net 39))
  (segment (start 109.135 110.845999) (end 109.168378 110.842238) (width 0.109) (layer "In6.Cu") (net 39))
  (segment (start 110.770145 110.138919) (end 110.781239 110.170623) (width 0.109) (layer "In6.Cu") (net 39))
  (segment (start 110.48876 110.170623) (end 110.499854 110.138919) (width 0.109) (layer "In6.Cu") (net 39))
  (segment (start 109.941476 110.086727) (end 109.969917 110.068856) (width 0.109) (layer "In6.Cu") (net 39))
  (segment (start 117.219648 108.305257) (end 117.205075 108.274994) (width 0.109) (layer "In6.Cu") (net 39))
  (segment (start 110.781239 110.170623) (end 110.785 110.204001) (width 0.109) (layer "In6.Cu") (net 39))
  (segment (start 110.241476 110.813273) (end 110.269917 110.831144) (width 0.109) (layer "In6.Cu") (net 39))
  (segment (start 108.568378 110.842238) (end 108.600082 110.831144) (width 0.109) (layer "In6.Cu") (net 39))
  (segment (start 108.417725 110.789522) (end 108.441476 110.813273) (width 0.109) (layer "In6.Cu") (net 39))
  (segment (start 116.780813 108.699256) (end 116.773339 108.666507) (width 0.109) (layer "In6.Cu") (net 39))
  (segment (start 117.800617 108.467279) (end 117.826878 108.488222) (width 0.109) (layer "In6.Cu") (net 39))
  (segment (start 113.541476 110.086727) (end 113.569917 110.068856) (width 0.109) (layer "In6.Cu") (net 39))
  (segment (start 117.199741 109.259278) (end 117.207215 109.226531) (width 0.109) (layer "In6.Cu") (net 39))
  (segment (start 116.884212 109.247922) (end 116.952093 109.315803) (width 0.109) (layer "In6.Cu") (net 39))
  (segment (start 116.765 97.895) (end 116.765 97.155) (width 0.109) (layer "In6.Cu") (net 39))
  (segment (start 118.25114 108.06396) (end 118.281403 108.078533) (width 0.109) (layer "In6.Cu") (net 39))
  (segment (start 113.785 110.695999) (end 113.78876 110.729377) (width 0.109) (layer "In6.Cu") (net 39))
  (segment (start 111.385 110.695999) (end 111.38876 110.729377) (width 0.109) (layer "In6.Cu") (net 39))
  (segment (start 117.297117 108.083869) (end 117.329863 108.076396) (width 0.109) (layer "In6.Cu") (net 39))
  (segment (start 108.052274 110.789522) (end 108.070145 110.761081) (width 0.109) (layer "In6.Cu") (net 39))
  (segment (start 108.681239 110.729377) (end 108.685 110.695999) (width 0.109) (layer "In6.Cu") (net 39))
  (segment (start 114.070145 110.761081) (end 114.081239 110.729377) (width 0.109) (layer "In6.Cu") (net 39))
  (segment (start 115.069917 110.435146) (end 115.101621 110.44624) (width 0.109) (layer "In6.Cu") (net 39))
  (segment (start 113.78876 110.729377) (end 113.799854 110.761081) (width 0.109) (layer "In6.Cu") (net 39))
  (segment (start 110.752274 110.110478) (end 110.770145 110.138919) (width 0.109) (layer "In6.Cu") (net 39))
  (segment (start 110.869917 110.831144) (end 110.901621 110.842238) (width 0.109) (layer "In6.Cu") (net 39))
  (segment (start 114.741476 110.086727) (end 114.769917 110.068856) (width 0.109) (layer "In6.Cu") (net 39))
  (segment (start 112.941476 110.086727) (end 112.969917 110.068856) (width 0.109) (layer "In6.Cu") (net 39))
  (segment (start 118.012749 108.467279) (end 118.033691 108.441017) (width 0.109) (layer "In6.Cu") (net 39))
  (segment (start 114.900082 110.068856) (end 114.928523 110.086727) (width 0.109) (layer "In6.Cu") (net 39))
  (segment (start 109.828523 110.813273) (end 109.852274 110.789522) (width 0.109) (layer "In6.Cu") (net 39))
  (segment (start 108.685 110.204001) (end 108.68876 110.170623) (width 0.109) (layer "In6.Cu") (net 39))
  (segment (start 112.800082 110.831144) (end 112.828523 110.813273) (width 0.109) (layer "In6.Cu") (net 39))
  (segment (start 118.457953 108.016755) (end 118.472527 107.986492) (width 0.109) (layer "In6.Cu") (net 39))
  (segment (start 117.850724 107.67418) (end 117.876985 107.695122) (width 0.109) (layer "In6.Cu") (net 39))
  (segment (start 114.628523 110.813273) (end 114.652274 110.789522) (width 0.109) (layer "In6.Cu") (net 39))
  (segment (start 112.317725 110.110478) (end 112.341476 110.086727) (width 0.109) (layer "In6.Cu") (net 39))
  (segment (start 113.485 110.695999) (end 113.485 110.204001) (width 0.109) (layer "In6.Cu") (net 39))
  (segment (start 111.900082 110.068856) (end 111.928523 110.086727) (width 0.109) (layer "In6.Cu") (net 39))
  (segment (start 109.041476 110.813273) (end 109.069917 110.831144) (width 0.109) (layer "In6.Cu") (net 39))
  (segment (start 117.629336 107.850731) (end 117.621862 107.817982) (width 0.109) (layer "In6.Cu") (net 39))
  (segment (start 111.535 110.845999) (end 111.568378 110.842238) (width 0.109) (layer "In6.Cu") (net 39))
  (segment (start 113.752274 110.110478) (end 113.770145 110.138919) (width 0.109) (layer "In6.Cu") (net 39))
  (segment (start 116.389239 109.742893) (end 116.368296 109.716632) (width 0.109) (layer "In6.Cu") (net 39))
  (segment (start 111.685 110.695999) (end 111.685 110.204001) (width 0.109) (layer "In6.Cu") (net 39))
  (segment (start 108.801621 110.057762) (end 108.835 110.054001) (width 0.109) (layer "In6.Cu") (net 39))
  (segment (start 113.968378 110.842238) (end 114.000082 110.831144) (width 0.109) (layer "In6.Cu") (net 39))
  (segment (start 111.070145 110.761081) (end 111.081239 110.729377) (width 0.109) (layer "In6.Cu") (net 39))
  (segment (start 114.028523 110.813273) (end 114.052274 110.789522) (width 0.109) (layer "In6.Cu") (net 39))
  (segment (start 114.268378 110.057762) (end 114.300082 110.068856) (width 0.109) (layer "In6.Cu") (net 39))
  (segment (start 113.799854 110.761081) (end 113.817725 110.789522) (width 0.109) (layer "In6.Cu") (net 39))
  (segment (start 91.9 111.940828) (end 92.3665 111.589) (width 0.182) (layer "F.Cu") (net 40))
  (segment (start 124.505 99.855) (end 124.505 99.645) (width 0.182) (layer "F.Cu") (net 40))
  (segment (start 124.295 99.925) (end 124.435 99.925) (width 0.182) (layer "F.Cu") (net 40))
  (segment (start 124.193976 100.026024) (end 124.295 99.925) (width 0.182) (layer "F.Cu") (net 40))
  (segment (start 124.435 99.925) (end 124.505 99.855) (width 0.182) (layer "F.Cu") (net 40))
  (segment (start 124.505 99.645) (end 124.351 99.491) (width 0.182) (layer "F.Cu") (net 40))
  (segment (start 124.193976 100.473976) (end 124.193976 100.026024) (width 0.182) (layer "F.Cu") (net 40))
  (segment (start 124.351 99.491) (end 123.1151 99.491) (width 0.182) (layer "F.Cu") (net 40))
  (via (at 124.193976 100.473976) (size 0.45) (drill 0.1) (layers "F.Cu" "B.Cu") (net 40))
  (via (at 91.9 111.940828) (size 0.45) (drill 0.1) (layers "F.Cu" "B.Cu") (net 40))
  (segment (start 106.16 112.675) (end 106.164387 112.636059) (width 0.109) (layer "In6.Cu") (net 40))
  (segment (start 105.105612 112.636059) (end 105.11 112.675) (width 0.109) (layer "In6.Cu") (net 40))
  (segment (start 116.321058 112.995613) (end 116.36 113) (width 0.109) (layer "In6.Cu") (net 40))
  (segment (start 110.185 113.5) (end 110.223941 113.495612) (width 0.109) (layer "In6.Cu") (net 40))
  (segment (start 115.31 113) (end 115.348941 113.004387) (width 0.109) (layer "In6.Cu") (net 40))
  (segment (start 109.40907 113.482669) (end 109.446058 113.495612) (width 0.109) (layer "In6.Cu") (net 40))
  (segment (start 103.748179 113.43411) (end 103.775889 113.46182) (width 0.109) (layer "In6.Cu") (net 40))
  (segment (start 111.06 113.175) (end 111.064387 113.136058) (width 0.109) (layer "In6.Cu") (net 40))
  (segment (start 107.542669 113.400929) (end 107.555612 113.363941) (width 0.109) (layer "In6.Cu") (net 40))
  (segment (start 115.817669 113.414207) (end 115.830612 113.377219) (width 0.109) (layer "In6.Cu") (net 40))
  (segment (start 110.36 112.675) (end 110.364387 112.636059) (width 0.109) (layer "In6.Cu") (net 40))
  (segment (start 107.21 112.675) (end 107.21 113.325) (width 0.109) (layer "In6.Cu") (net 40))
  (segment (start 105.81 112.675) (end 105.81 113.325) (width 0.109) (layer "In6.Cu") (net 40))
  (segment (start 115.76911 113.475098) (end 115.79682 113.447388) (width 0.109) (layer "In6.Cu") (net 40))
  (segment (start 111.02182 113.43411) (end 111.042669 113.400929) (width 0.109) (layer "In6.Cu") (net 40))
  (segment (start 108.19411 113.46182) (end 108.22182 113.43411) (width 0.109) (layer "In6.Cu") (net 40))
  (segment (start 116.11911 112.524902) (end 116.14682 112.552612) (width 0.109) (layer "In6.Cu") (net 40))
  (segment (start 107.214387 113.363941) (end 107.22733 113.400929) (width 0.109) (layer "In6.Cu") (net 40))
  (segment (start 103.705612 113.136058) (end 103.71 113.175) (width 0.109) (layer "In6.Cu") (net 40))
  (segment (start 110.705612 112.636059) (end 110.71 112.675) (width 0.109) (layer "In6.Cu") (net 40))
  (segment (start 106.25907 112.517331) (end 106.296058 112.504388) (width 0.109) (layer "In6.Cu") (net 40))
  (segment (start 106.760929 113.482669) (end 106.79411 113.46182) (width 0.109) (layer "In6.Cu") (net 40))
  (segment (start 110.01 113.325) (end 110.014387 113.363941) (width 0.109) (layer "In6.Cu") (net 40))
  (segment (start 116.01 112.486722) (end 116.048941 112.49111) (width 0.109) (layer "In6.Cu") (net 40))
  (segment (start 106.296058 112.504388) (end 106.335 112.5) (width 0.109) (layer "In6.Cu") (net 40))
  (segment (start 108.605612 112.636059) (end 108.61 112.675) (width 0.109) (layer "In6.Cu") (net 40))
  (segment (start 110.846058 113.495612) (end 110.885 113.5) (width 0.109) (layer "In6.Cu") (net 40))
  (segment (start 107.810929 112.517331) (end 107.84411 112.53818) (width 0.109) (layer "In6.Cu") (net 40))
  (segment (start 103.99411 113.46182) (end 104.02182 113.43411) (width 0.109) (layer "In6.Cu") (net 40))
  (segment (start 105.360929 113.482669) (end 105.39411 113.46182) (width 0.109) (layer "In6.Cu") (net 40))
  (segment (start 103.775889 113.46182) (end 103.80907 113.482669) (width 0.109) (layer "In6.Cu") (net 40))
  (segment (start 105.175889 113.46182) (end 105.20907 113.482669) (width 0.109) (layer "In6.Cu") (net 40))
  (segment (start 116.250889 112.961821) (end 116.28407 112.98267) (width 0.109) (layer "In6.Cu") (net 40))
  (segment (start 116.180612 112.622781) (end 116.185 112.661722) (width 0.109) (layer "In6.Cu") (net 40))
  (segment (start 107.91 112.675) (end 107.91 113.325) (width 0.109) (layer "In6.Cu") (net 40))
  (segment (start 109.31 113.325) (end 109.314387 113.363941) (width 0.109) (layer "In6.Cu") (net 40))
  (segment (start 108.97733 112.599071) (end 108.998179 112.56589) (width 0.109) (layer "In6.Cu") (net 40))
  (segment (start 103.71 113.325) (end 103.714387 113.363941) (width 0.109) (layer "In6.Cu") (net 40))
  (segment (start 104.475889 113.46182) (end 104.50907 113.482669) (width 0.109) (layer "In6.Cu") (net 40))
  (segment (start 110.36 113.325) (end 110.36 112.675) (width 0.109) (layer "In6.Cu") (net 40))
  (segment (start 108.242669 113.400929) (end 108.255612 113.363941) (width 0.109) (layer "In6.Cu") (net 40))
  (segment (start 115.830612 113.377219) (end 115.835 113.338278) (width 0.109) (layer "In6.Cu") (net 40))
  (segment (start 107.948179 113.43411) (end 107.975889 113.46182) (width 0.109) (layer "In6.Cu") (net 40))
  (segment (start 115.971058 112.49111) (end 116.01 112.486722) (width 0.109) (layer "In6.Cu") (net 40))
  (segment (start 121.83 104.68) (end 123.225 104.68) (width 0.109) (layer "In6.Cu") (net 40))
  (segment (start 107.14411 112.53818) (end 107.17182 112.56589) (width 0.109) (layer "In6.Cu") (net 40))
  (segment (start 110.02733 113.400929) (end 110.048179 113.43411) (width 0.109) (layer "In6.Cu") (net 40))
  (segment (start 107.385 113.5) (end 107.423941 113.495612) (width 0.109) (layer "In6.Cu") (net 40))
  (segment (start 104.098179 112.56589) (end 104.125889 112.53818) (width 0.109) (layer "In6.Cu") (net 40))
  (segment (start 110.496058 112.504388) (end 110.535 112.5) (width 0.109) (layer "In6.Cu") (net 40))
  (segment (start 108.592669 112.599071) (end 108.605612 112.636059) (width 0.109) (layer "In6.Cu") (net 40))
  (segment (start 116.189387 112.863942) (end 116.20233 112.90093) (width 0.109) (layer "In6.Cu") (net 40))
  (segment (start 94.7 113) (end 103.535 113) (width 0.109) (layer "In6.Cu") (net 40))
  (segment (start 104.896058 112.504388) (end 104.935 112.5) (width 0.109) (layer "In6.Cu") (net 40))
  (segment (start 111.06 113.325) (end 111.06 113.175) (width 0.109) (layer "In6.Cu") (net 40))
  (segment (start 110.923941 113.495612) (end 110.960929 113.482669) (width 0.109) (layer "In6.Cu") (net 40))
  (segment (start 121.1 105.41) (end 121.83 104.68) (width 0.109) (layer "In6.Cu") (net 40))
  (segment (start 103.714387 113.363941) (end 103.72733 113.400929) (width 0.109) (layer "In6.Cu") (net 40))
  (segment (start 108.27733 112.599071) (end 108.298179 112.56589) (width 0.109) (layer "In6.Cu") (net 40))
  (segment (start 115.900889 112.524902) (end 115.93407 112.504053) (width 0.109) (layer "In6.Cu") (net 40))
  (segment (start 105.805612 112.636059) (end 105.81 112.675) (width 0.109) (layer "In6.Cu") (net 40))
  (segment (start 106.855612 113.363941) (end 106.86 113.325) (width 0.109) (layer "In6.Cu") (net 40))
  (segment (start 110.398179 112.56589) (end 110.425889 112.53818) (width 0.109) (layer "In6.Cu") (net 40))
  (segment (start 103.610929 113.01733) (end 103.64411 113.038179) (width 0.109) (layer "In6.Cu") (net 40))
  (segment (start 110.99411 113.46182) (end 111.02182 113.43411) (width 0.109) (layer "In6.Cu") (net 40))
  (segment (start 106.51 113.325) (end 106.514387 113.363941) (width 0.109) (layer "In6.Cu") (net 40))
  (segment (start 105.42182 113.43411) (end 105.442669 113.400929) (width 0.109) (layer "In6.Cu") (net 40))
  (segment (start 104.76 113.325) (end 104.76 112.675) (width 0.109) (layer "In6.Cu") (net 40))
  (segment (start 116.167669 112.585793) (end 116.180612 112.622781) (width 0.109) (layer "In6.Cu") (net 40))
  (segment (start 107.275889 113.46182) (end 107.30907 113.482669) (width 0.109) (layer "In6.Cu") (net 40))
  (segment (start 106.060929 113.482669) (end 106.09411 113.46182) (width 0.109) (layer "In6.Cu") (net 40))
  (segment (start 107.598179 112.56589) (end 107.625889 112.53818) (width 0.109) (layer "In6.Cu") (net 40))
  (segment (start 109.655612 113.363941) (end 109.66 113.325) (width 0.109) (layer "In6.Cu") (net 40))
  (segment (start 105.875889 113.46182) (end 105.90907 113.482669) (width 0.109) (layer "In6.Cu") (net 40))
  (segment (start 110.014387 113.363941) (end 110.02733 113.400929) (width 0.109) (layer "In6.Cu") (net 40))
  (segment (start 115.735929 113.495947) (end 115.76911 113.475098) (width 0.109) (layer "In6.Cu") (net 40))
  (segment (start 111.064387 113.136058) (end 111.07733 113.09907) (width 0.109) (layer "In6.Cu") (net 40))
  (segment (start 108.473941 112.504388) (end 108.510929 112.517331) (width 0.109) (layer "In6.Cu") (net 40))
  (segment (start 108.160929 113.482669) (end 108.19411 113.46182) (width 0.109) (layer "In6.Cu") (net 40))
  (segment (start 115.698941 113.50889) (end 115.735929 113.495947) (width 0.109) (layer "In6.Cu") (net 40))
  (segment (start 108.26 112.675) (end 108.264387 112.636059) (width 0.109) (layer "In6.Cu") (net 40))
  (segment (start 107.57733 112.599071) (end 107.598179 112.56589) (width 0.109) (layer "In6.Cu") (net 40))
  (segment (start 110.10907 113.482669) (end 110.146058 113.495612) (width 0.109) (layer "In6.Cu") (net 40))
  (segment (start 103.573941 113.004387) (end 103.610929 113.01733) (width 0.109) (layer "In6.Cu") (net 40))
  (segment (start 105.46 113.325) (end 105.46 112.675) (width 0.109) (layer "In6.Cu") (net 40))
  (segment (start 106.155612 113.363941) (end 106.16 113.325) (width 0.109) (layer "In6.Cu") (net 40))
  (segment (start 107.564387 112.636059) (end 107.57733 112.599071) (width 0.109) (layer "In6.Cu") (net 40))
  (segment (start 106.87733 112.599071) (end 106.898179 112.56589) (width 0.109) (layer "In6.Cu") (net 40))
  (segment (start 105.010929 112.517331) (end 105.04411 112.53818) (width 0.109) (layer "In6.Cu") (net 40))
  (segment (start 107.248179 113.43411) (end 107.275889 113.46182) (width 0.109) (layer "In6.Cu") (net 40))
  (segment (start 110.223941 113.495612) (end 110.260929 113.482669) (width 0.109) (layer "In6.Cu") (net 40))
  (segment (start 108.00907 113.482669) (end 108.046058 113.495612) (width 0.109) (layer "In6.Cu") (net 40))
  (segment (start 106.925889 112.53818) (end 106.95907 112.517331) (width 0.109) (layer "In6.Cu") (net 40))
  (segment (start 107.696058 112.504388) (end 107.735 112.5) (width 0.109) (layer "In6.Cu") (net 40))
  (segment (start 105.442669 113.400929) (end 105.455612 113.363941) (width 0.109) (layer "In6.Cu") (net 40))
  (segment (start 105.46 112.675) (end 105.464387 112.636059) (width 0.109) (layer "In6.Cu") (net 40))
  (segment (start 109.873941 112.504388) (end 109.910929 112.517331) (width 0.109) (layer "In6.Cu") (net 40))
  (segment (start 108.675889 113.46182) (end 108.70907 113.482669) (width 0.109) (layer "In6.Cu") (net 40))
  (segment (start 105.946058 113.495612) (end 105.985 113.5) (width 0.109) (layer "In6.Cu") (net 40))
  (segment (start 115.621058 113.50889) (end 115.66 113.513278) (width 0.109) (layer "In6.Cu") (net 40))
  (segment (start 105.985 113.5) (end 106.023941 113.495612) (width 0.109) (layer "In6.Cu") (net 40))
  (segment (start 109.560929 113.482669) (end 109.59411 113.46182) (width 0.109) (layer "In6.Cu") (net 40))
  (segment (start 109.664387 112.636059) (end 109.67733 112.599071) (width 0.109) (layer "In6.Cu") (net 40))
  (segment (start 116.94 113) (end 121.1 108.84) (width 0.109) (layer "In6.Cu") (net 40))
  (segment (start 109.66 112.675) (end 109.664387 112.636059) (width 0.109) (layer "In6.Cu") (net 40))
  (segment (start 107.625889 112.53818) (end 107.65907 112.517331) (width 0.109) (layer "In6.Cu") (net 40))
  (segment (start 111.15907 113.01733) (end 111.196058 113.004387) (width 0.109) (layer "In6.Cu") (net 40))
  (segment (start 106.51 112.675) (end 106.51 113.325) (width 0.109) (layer "In6.Cu") (net 40))
  (segment (start 108.264387 112.636059) (end 108.27733 112.599071) (width 0.109) (layer "In6.Cu") (net 40))
  (segment (start 107.52182 113.43411) (end 107.542669 113.400929) (width 0.109) (layer "In6.Cu") (net 40))
  (segment (start 109.485 113.5) (end 109.523941 113.495612) (width 0.109) (layer "In6.Cu") (net 40))
  (segment (start 106.95907 112.517331) (end 106.996058 112.504388) (width 0.109) (layer "In6.Cu") (net 40))
  (segment (start 111.07733 113.09907) (end 111.098179 113.065889) (width 0.109) (layer "In6.Cu") (net 40))
  (segment (start 103.64411 113.038179) (end 103.67182 113.065889) (width 0.109) (layer "In6.Cu") (net 40))
  (segment (start 108.510929 112.517331) (end 108.54411 112.53818) (width 0.109) (layer "In6.Cu") (net 40))
  (segment (start 108.54411 112.53818) (end 108.57182 112.56589) (width 0.109) (layer "In6.Cu") (net 40))
  (segment (start 115.41911 113.038179) (end 115.44682 113.065889) (width 0.109) (layer "In6.Cu") (net 40))
  (segment (start 111.055612 113.363941) (end 111.06 113.325) (width 0.109) (layer "In6.Cu") (net 40))
  (segment (start 111.042669 113.400929) (end 111.055612 113.363941) (width 0.109) (layer "In6.Cu") (net 40))
  (segment (start 108.942669 113.400929) (end 108.955612 113.363941) (width 0.109) (layer "In6.Cu") (net 40))
  (segment (start 104.34411 112.53818) (end 104.37182 112.56589) (width 0.109) (layer "In6.Cu") (net 40))
  (segment (start 109.75907 112.517331) (end 109.796058 112.504388) (width 0.109) (layer "In6.Cu") (net 40))
  (segment (start 107.56 113.325) (end 107.56 112.675) (width 0.109) (layer "In6.Cu") (net 40))
  (segment (start 108.96 113.325) (end 108.96 112.675) (width 0.109) (layer "In6.Cu") (net 40))
  (segment (start 123.968977 100.698975) (end 124.193976 100.473976) (width 0.109) (layer "In6.Cu") (net 40))
  (segment (start 108.860929 113.482669) (end 108.89411 113.46182) (width 0.109) (layer "In6.Cu") (net 40))
  (segment (start 104.064387 112.636059) (end 104.07733 112.599071) (width 0.109) (layer "In6.Cu") (net 40))
  (segment (start 108.92182 113.43411) (end 108.942669 113.400929) (width 0.109) (layer "In6.Cu") (net 40))
  (segment (start 115.523179 113.447388) (end 115.550889 113.475098) (width 0.109) (layer "In6.Cu") (net 40))
  (segment (start 115.835 113.338278) (end 115.835 112.661722) (width 0.109) (layer "In6.Cu") (net 40))
  (segment (start 107.205612 112.636059) (end 107.21 112.675) (width 0.109) (layer "In6.Cu") (net 40))
  (segment (start 109.59411 113.46182) (end 109.62182 113.43411) (width 0.109) (layer "In6.Cu") (net 40))
  (segment (start 108.26 113.325) (end 108.26 112.675) (width 0.109) (layer "In6.Cu") (net 40))
  (segment (start 106.685 113.5) (end 106.723941 113.495612) (width 0.109) (layer "In6.Cu") (net 40))
  (segment (start 106.575889 113.46182) (end 106.60907 113.482669) (width 0.109) (layer "In6.Cu") (net 40))
  (segment (start 109.835 112.5) (end 109.873941 112.504388) (width 0.109) (layer "In6.Cu") (net 40))
  (segment (start 107.56 112.675) (end 107.564387 112.636059) (width 0.109) (layer "In6.Cu") (net 40))
  (segment (start 108.62733 113.400929) (end 108.648179 113.43411) (width 0.109) (layer "In6.Cu") (net 40))
  (segment (start 116.20233 112.90093) (end 116.223179 112.934111) (width 0.109) (layer "In6.Cu") (net 40))
  (segment (start 92.621449 112.549999) (end 94.249999 112.549999) (width 0.109) (layer "In6.Cu") (net 40))
  (segment (start 115.480612 113.136058) (end 115.485 113.175) (width 0.109) (layer "In6.Cu") (net 40))
  (segment (start 106.52733 113.400929) (end 106.548179 113.43411) (width 0.109) (layer "In6.Cu") (net 40))
  (segment (start 105.498179 112.56589) (end 105.525889 112.53818) (width 0.109) (layer "In6.Cu") (net 40))
  (segment (start 107.92733 113.400929) (end 107.948179 113.43411) (width 0.109) (layer "In6.Cu") (net 40))
  (segment (start 106.79411 113.46182) (end 106.82182 113.43411) (width 0.109) (layer "In6.Cu") (net 40))
  (segment (start 104.973941 112.504388) (end 105.010929 112.517331) (width 0.109) (layer "In6.Cu") (net 40))
  (segment (start 105.596058 112.504388) (end 105.635 112.5) (width 0.109) (layer "In6.Cu") (net 40))
  (segment (start 110.960929 113.482669) (end 110.99411 113.46182) (width 0.109) (layer "In6.Cu") (net 40))
  (segment (start 107.30907 113.482669) (end 107.346058 113.495612) (width 0.109) (layer "In6.Cu") (net 40))
  (segment (start 107.914387 113.363941) (end 107.92733 113.400929) (width 0.109) (layer "In6.Cu") (net 40))
  (segment (start 106.86 113.325) (end 106.86 112.675) (width 0.109) (layer "In6.Cu") (net 40))
  (segment (start 109.66 113.325) (end 109.66 112.675) (width 0.109) (layer "In6.Cu") (net 40))
  (segment (start 108.61 112.675) (end 108.61 113.325) (width 0.109) (layer "In6.Cu") (net 40))
  (segment (start 115.835 112.661722) (end 115.839387 112.622781) (width 0.109) (layer "In6.Cu") (net 40))
  (segment (start 104.85907 112.517331) (end 104.896058 112.504388) (width 0.109) (layer "In6.Cu") (net 40))
  (segment (start 106.09411 113.46182) (end 106.12182 113.43411) (width 0.109) (layer "In6.Cu") (net 40))
  (segment (start 106.410929 112.517331) (end 106.44411 112.53818) (width 0.109) (layer "In6.Cu") (net 40))
  (segment (start 109.97182 112.56589) (end 109.992669 112.599071) (width 0.109) (layer "In6.Cu") (net 40))
  (segment (start 110.535 112.5) (end 110.573941 112.504388) (width 0.109) (layer "In6.Cu") (net 40))
  (segment (start 107.87182 112.56589) (end 107.892669 112.599071) (width 0.109) (layer "In6.Cu") (net 40))
  (segment (start 109.096058 112.504388) (end 109.135 112.5) (width 0.109) (layer "In6.Cu") (net 40))
  (segment (start 105.148179 113.43411) (end 105.175889 113.46182) (width 0.109) (layer "In6.Cu") (net 40))
  (segment (start 105.792669 112.599071) (end 105.805612 112.636059) (width 0.109) (layer "In6.Cu") (net 40))
  (segment (start 105.323941 113.495612) (end 105.360929 113.482669) (width 0.109) (layer "In6.Cu") (net 40))
  (segment (start 104.06 113.325) (end 104.06 112.675) (width 0.109) (layer "In6.Cu") (net 40))
  (segment (start 108.89411 113.46182) (end 108.92182 113.43411) (width 0.109) (layer "In6.Cu") (net 40))
  (segment (start 105.11 113.325) (end 105.114387 113.363941) (width 0.109) (layer "In6.Cu") (net 40))
  (segment (start 105.710929 112.517331) (end 105.74411 112.53818) (width 0.109) (layer "In6.Cu") (net 40))
  (segment (start 108.22182 113.43411) (end 108.242669 113.400929) (width 0.109) (layer "In6.Cu") (net 40))
  (segment (start 108.648179 113.43411) (end 108.675889 113.46182) (width 0.109) (layer "In6.Cu") (net 40))
  (segment (start 105.814387 113.363941) (end 105.82733 113.400929) (width 0.109) (layer "In6.Cu") (net 40))
  (segment (start 106.12182 113.43411) (end 106.142669 113.400929) (width 0.109) (layer "In6.Cu") (net 40))
  (segment (start 110.37733 112.599071) (end 110.398179 112.56589) (width 0.109) (layer "In6.Cu") (net 40))
  (segment (start 109.67733 112.599071) (end 109.698179 112.56589) (width 0.109) (layer "In6.Cu") (net 40))
  (segment (start 103.535 113) (end 103.573941 113.004387) (width 0.109) (layer "In6.Cu") (net 40))
  (segment (start 109.375889 113.46182) (end 109.40907 113.482669) (width 0.109) (layer "In6.Cu") (net 40))
  (segment (start 105.77182 112.56589) (end 105.792669 112.599071) (width 0.109) (layer "In6.Cu") (net 40))
  (segment (start 108.255612 113.363941) (end 108.26 113.325) (width 0.109) (layer "In6.Cu") (net 40))
  (segment (start 108.955612 113.363941) (end 108.96 113.325) (width 0.109) (layer "In6.Cu") (net 40))
  (segment (start 116.048941 112.49111) (end 116.085929 112.504053) (width 0.109) (layer "In6.Cu") (net 40))
  (segment (start 107.773941 112.504388) (end 107.810929 112.517331) (width 0.109) (layer "In6.Cu") (net 40))
  (segment (start 116.185 112.825) (end 116.189387 112.863942) (width 0.109) (layer "In6.Cu") (net 40))
  (segment (start 110.425889 112.53818) (end 110.45907 112.517331) (width 0.109) (layer "In6.Cu") (net 40))
  (segment (start 115.93407 112.504053) (end 115.971058 112.49111) (width 0.109) (layer "In6.Cu") (net 40))
  (segment (start 103.846058 113.495612) (end 103.885 113.5) (width 0.109) (layer "In6.Cu") (net 40))
  (segment (start 104.405612 112.636059) (end 104.41 112.675) (width 0.109) (layer "In6.Cu") (net 40))
  (segment (start 103.923941 113.495612) (end 103.960929 113.482669) (width 0.109) (layer "In6.Cu") (net 40))
  (segment (start 109.025889 112.53818) (end 109.05907 112.517331) (width 0.109) (layer "In6.Cu") (net 40))
  (segment (start 103.71 113.175) (end 103.71 113.325) (width 0.109) (layer "In6.Cu") (net 40))
  (segment (start 116.085929 112.504053) (end 116.11911 112.524902) (width 0.109) (layer "In6.Cu") (net 40))
  (segment (start 108.61 113.325) (end 108.614387 113.363941) (width 0.109) (layer "In6.Cu") (net 40))
  (segment (start 104.798179 112.56589) (end 104.825889 112.53818) (width 0.109) (layer "In6.Cu") (net 40))
  (segment (start 115.79682 113.447388) (end 115.817669 113.414207) (width 0.109) (layer "In6.Cu") (net 40))
  (segment (start 104.414387 113.363941) (end 104.42733 113.400929) (width 0.109) (layer "In6.Cu") (net 40))
  (segment (start 109.27182 112.56589) (end 109.292669 112.599071) (width 0.109) (layer "In6.Cu") (net 40))
  (segment (start 107.073941 112.504388) (end 107.110929 112.517331) (width 0.109) (layer "In6.Cu") (net 40))
  (segment (start 104.41 112.675) (end 104.41 113.325) (width 0.109) (layer "In6.Cu") (net 40))
  (segment (start 110.32182 113.43411) (end 110.342669 113.400929) (width 0.109) (layer "In6.Cu") (net 40))
  (segment (start 108.614387 113.363941) (end 108.62733 113.400929) (width 0.109) (layer "In6.Cu") (net 40))
  (segment (start 106.996058 112.504388) (end 107.035 112.5) (width 0.109) (layer "In6.Cu") (net 40))
  (segment (start 109.910929 112.517331) (end 109.94411 112.53818) (width 0.109) (layer "In6.Cu") (net 40))
  (segment (start 103.960929 113.482669) (end 103.99411 113.46182) (width 0.109) (layer "In6.Cu") (net 40))
  (segment (start 105.74411 112.53818) (end 105.77182 112.56589) (width 0.109) (layer "In6.Cu") (net 40))
  (segment (start 107.735 112.5) (end 107.773941 112.504388) (width 0.109) (layer "In6.Cu") (net 40))
  (segment (start 104.448179 113.43411) (end 104.475889 113.46182) (width 0.109) (layer "In6.Cu") (net 40))
  (segment (start 109.24411 112.53818) (end 109.27182 112.56589) (width 0.109) (layer "In6.Cu") (net 40))
  (segment (start 108.325889 112.53818) (end 108.35907 112.517331) (width 0.109) (layer "In6.Cu") (net 40))
  (segment (start 116.28407 112.98267) (end 116.321058 112.995613) (width 0.109) (layer "In6.Cu") (net 40))
  (segment (start 105.04411 112.53818) (end 105.07182 112.56589) (width 0.109) (layer "In6.Cu") (net 40))
  (segment (start 104.41 113.325) (end 104.414387 113.363941) (width 0.109) (layer "In6.Cu") (net 40))
  (segment (start 104.935 112.5) (end 104.973941 112.504388) (width 0.109) (layer "In6.Cu") (net 40))
  (segment (start 105.246058 113.495612) (end 105.285 113.5) (width 0.109) (layer "In6.Cu") (net 40))
  (segment (start 104.660929 113.482669) (end 104.69411 113.46182) (width 0.109) (layer "In6.Cu") (net 40))
  (segment (start 109.173941 112.504388) (end 109.210929 112.517331) (width 0.109) (layer "In6.Cu") (net 40))
  (segment (start 104.742669 113.400929) (end 104.755612 113.363941) (width 0.109) (layer "In6.Cu") (net 40))
  (segment (start 106.864387 112.636059) (end 106.87733 112.599071) (width 0.109) (layer "In6.Cu") (net 40))
  (segment (start 108.396058 112.504388) (end 108.435 112.5) (width 0.109) (layer "In6.Cu") (net 40))
  (segment (start 110.342669 113.400929) (end 110.355612 113.363941) (width 0.109) (layer "In6.Cu") (net 40))
  (segment (start 104.125889 112.53818) (end 104.15907 112.517331) (width 0.109) (layer "In6.Cu") (net 40))
  (segment (start 104.273941 112.504388) (end 104.310929 112.517331) (width 0.109) (layer "In6.Cu") (net 40))
  (segment (start 115.873179 112.552612) (end 115.900889 112.524902) (width 0.109) (layer "In6.Cu") (net 40))
  (segment (start 107.192669 112.599071) (end 107.205612 112.636059) (width 0.109) (layer "In6.Cu") (net 40))
  (segment (start 107.346058 113.495612) (end 107.385 113.5) (width 0.109) (layer "In6.Cu") (net 40))
  (segment (start 105.12733 113.400929) (end 105.148179 113.43411) (width 0.109) (layer "In6.Cu") (net 40))
  (segment (start 107.84411 112.53818) (end 107.87182 112.56589) (width 0.109) (layer "In6.Cu") (net 40))
  (segment (start 110.692669 112.599071) (end 110.705612 112.636059) (width 0.109) (layer "In6.Cu") (net 40))
  (segment (start 108.046058 113.495612) (end 108.085 113.5) (width 0.109) (layer "In6.Cu") (net 40))
  (segment (start 110.748179 113.43411) (end 110.775889 113.46182) (width 0.109) (layer "In6.Cu") (net 40))
  (segment (start 94.249999 112.549999) (end 94.7 113) (width 0.109) (layer "In6.Cu") (net 40))
  (segment (start 106.335 112.5) (end 106.373941 112.504388) (width 0.109) (layer "In6.Cu") (net 40))
  (segment (start 104.72182 113.43411) (end 104.742669 113.400929) (width 0.109) (layer "In6.Cu") (net 40))
  (segment (start 109.31 112.675) (end 109.31 113.325) (width 0.109) (layer "In6.Cu") (net 40))
  (segment (start 123.225 104.68) (end 123.968977 103.936023) (width 0.109) (layer "In6.Cu") (net 40))
  (segment (start 108.96 112.675) (end 108.964387 112.636059) (width 0.109) (layer "In6.Cu") (net 40))
  (segment (start 110.67182 112.56589) (end 110.692669 112.599071) (width 0.109) (layer "In6.Cu") (net 40))
  (segment (start 105.635 112.5) (end 105.673941 112.504388) (width 0.109) (layer "In6.Cu") (net 40))
  (segment (start 110.80907 113.482669) (end 110.846058 113.495612) (width 0.109) (layer "In6.Cu") (net 40))
  (segment (start 107.975889 113.46182) (end 108.00907 113.482669) (width 0.109) (layer "In6.Cu") (net 40))
  (segment (start 106.723941 113.495612) (end 106.760929 113.482669) (width 0.109) (layer "In6.Cu") (net 40))
  (segment (start 107.22733 113.400929) (end 107.248179 113.43411) (width 0.109) (layer "In6.Cu") (net 40))
  (segment (start 104.02182 113.43411) (end 104.042669 113.400929) (width 0.109) (layer "In6.Cu") (net 40))
  (segment (start 107.17182 112.56589) (end 107.192669 112.599071) (width 0.109) (layer "In6.Cu") (net 40))
  (segment (start 92.22145 112.15) (end 92.621449 112.549999) (width 0.109) (layer "In6.Cu") (net 40))
  (segment (start 104.76 112.675) (end 104.764387 112.636059) (width 0.109) (layer "In6.Cu") (net 40))
  (segment (start 106.514387 113.363941) (end 106.52733 113.400929) (width 0.109) (layer "In6.Cu") (net 40))
  (segment (start 110.72733 113.400929) (end 110.748179 113.43411) (width 0.109) (layer "In6.Cu") (net 40))
  (segment (start 110.075889 113.46182) (end 110.10907 113.482669) (width 0.109) (layer "In6.Cu") (net 40))
  (segment (start 105.82733 113.400929) (end 105.848179 113.43411) (width 0.109) (layer "In6.Cu") (net 40))
  (segment (start 107.91 113.325) (end 107.914387 113.363941) (width 0.109) (layer "In6.Cu") (net 40))
  (segment (start 104.196058 112.504388) (end 104.235 112.5) (width 0.109) (layer "In6.Cu") (net 40))
  (segment (start 106.86 112.675) (end 106.864387 112.636059) (width 0.109) (layer "In6.Cu") (net 40))
  (segment (start 105.90907 113.482669) (end 105.946058 113.495612) (width 0.109) (layer "In6.Cu") (net 40))
  (segment (start 110.885 113.5) (end 110.923941 113.495612) (width 0.109) (layer "In6.Cu") (net 40))
  (segment (start 109.523941 113.495612) (end 109.560929 113.482669) (width 0.109) (layer "In6.Cu") (net 40))
  (segment (start 103.67182 113.065889) (end 103.692669 113.09907) (width 0.109) (layer "In6.Cu") (net 40))
  (segment (start 115.66 113.513278) (end 115.698941 113.50889) (width 0.109) (layer "In6.Cu") (net 40))
  (segment (start 115.50233 113.414207) (end 115.523179 113.447388) (width 0.109) (layer "In6.Cu") (net 40))
  (segment (start 110.364387 112.636059) (end 110.37733 112.599071) (width 0.109) (layer "In6.Cu") (net 40))
  (segment (start 110.71 113.325) (end 110.714387 113.363941) (width 0.109) (layer "In6.Cu") (net 40))
  (segment (start 110.355612 113.363941) (end 110.36 113.325) (width 0.109) (layer "In6.Cu") (net 40))
  (segment (start 105.55907 112.517331) (end 105.596058 112.504388) (width 0.109) (layer "In6.Cu") (net 40))
  (segment (start 116.223179 112.934111) (end 116.250889 112.961821) (width 0.109) (layer "In6.Cu") (net 40))
  (segment (start 106.82182 113.43411) (end 106.842669 113.400929) (width 0.109) (layer "In6.Cu") (net 40))
  (segment (start 105.07182 112.56589) (end 105.092669 112.599071) (width 0.109) (layer "In6.Cu") (net 40))
  (segment (start 115.467669 113.09907) (end 115.480612 113.136058) (width 0.109) (layer "In6.Cu") (net 40))
  (segment (start 110.64411 112.53818) (end 110.67182 112.56589) (width 0.109) (layer "In6.Cu") (net 40))
  (segment (start 108.085 113.5) (end 108.123941 113.495612) (width 0.109) (layer "In6.Cu") (net 40))
  (segment (start 109.348179 113.43411) (end 109.375889 113.46182) (width 0.109) (layer "In6.Cu") (net 40))
  (segment (start 104.37182 112.56589) (end 104.392669 112.599071) (width 0.109) (layer "In6.Cu") (net 40))
  (segment (start 106.492669 112.599071) (end 106.505612 112.636059) (width 0.109) (layer "In6.Cu") (net 40))
  (segment (start 105.81 113.325) (end 105.814387 113.363941) (width 0.109) (layer "In6.Cu") (net 40))
  (segment (start 106.225889 112.53818) (end 106.25907 112.517331) (width 0.109) (layer "In6.Cu") (net 40))
  (segment (start 104.42733 113.400929) (end 104.448179 113.43411) (width 0.109) (layer "In6.Cu") (net 40))
  (segment (start 110.71 112.675) (end 110.71 113.325) (width 0.109) (layer "In6.Cu") (net 40))
  (segment (start 110.45907 112.517331) (end 110.496058 112.504388) (width 0.109) (layer "In6.Cu") (net 40))
  (segment (start 116.14682 112.552612) (end 116.167669 112.585793) (width 0.109) (layer "In6.Cu") (net 40))
  (segment (start 103.692669 113.09907) (end 103.705612 113.136058) (width 0.109) (layer "In6.Cu") (net 40))
  (segment (start 111.098179 113.065889) (end 111.125889 113.038179) (width 0.109) (layer "In6.Cu") (net 40))
  (segment (start 105.673941 112.504388) (end 105.710929 112.517331) (width 0.109) (layer "In6.Cu") (net 40))
  (segment (start 107.110929 112.517331) (end 107.14411 112.53818) (width 0.109) (layer "In6.Cu") (net 40))
  (segment (start 106.646058 113.495612) (end 106.685 113.5) (width 0.109) (layer "In6.Cu") (net 40))
  (segment (start 104.310929 112.517331) (end 104.34411 112.53818) (width 0.109) (layer "In6.Cu") (net 40))
  (segment (start 108.35907 112.517331) (end 108.396058 112.504388) (width 0.109) (layer "In6.Cu") (net 40))
  (segment (start 106.17733 112.599071) (end 106.198179 112.56589) (width 0.109) (layer "In6.Cu") (net 40))
  (segment (start 107.555612 113.363941) (end 107.56 113.325) (width 0.109) (layer "In6.Cu") (net 40))
  (segment (start 108.964387 112.636059) (end 108.97733 112.599071) (width 0.109) (layer "In6.Cu") (net 40))
  (segment (start 115.85233 112.585793) (end 115.873179 112.552612) (width 0.109) (layer "In6.Cu") (net 40))
  (segment (start 115.44682 113.065889) (end 115.467669 113.09907) (width 0.109) (layer "In6.Cu") (net 40))
  (segment (start 107.905612 112.636059) (end 107.91 112.675) (width 0.109) (layer "In6.Cu") (net 40))
  (segment (start 111.235 113) (end 115.31 113) (width 0.109) (layer "In6.Cu") (net 40))
  (segment (start 92.109172 112.15) (end 92.22145 112.15) (width 0.109) (layer "In6.Cu") (net 40))
  (segment (start 111.125889 113.038179) (end 111.15907 113.01733) (width 0.109) (layer "In6.Cu") (net 40))
  (segment (start 111.196058 113.004387) (end 111.235 113) (width 0.109) (layer "In6.Cu") (net 40))
  (segment (start 110.005612 112.636059) (end 110.01 112.675) (width 0.109) (layer "In6.Cu") (net 40))
  (segment (start 104.50907 113.482669) (end 104.546058 113.495612) (width 0.109) (layer "In6.Cu") (net 40))
  (segment (start 106.164387 112.636059) (end 106.17733 112.599071) (width 0.109) (layer "In6.Cu") (net 40))
  (segment (start 106.44411 112.53818) (end 106.47182 112.56589) (width 0.109) (layer "In6.Cu") (net 40))
  (segment (start 106.16 113.325) (end 106.16 112.675) (width 0.109) (layer "In6.Cu") (net 40))
  (segment (start 107.892669 112.599071) (end 107.905612 112.636059) (width 0.109) (layer "In6.Cu") (net 40))
  (segment (start 104.546058 113.495612) (end 104.585 113.5) (width 0.109) (layer "In6.Cu") (net 40))
  (segment (start 104.755612 113.363941) (end 104.76 113.325) (width 0.109) (layer "In6.Cu") (net 40))
  (segment (start 106.548179 113.43411) (end 106.575889 113.46182) (width 0.109) (layer "In6.Cu") (net 40))
  (segment (start 115.839387 112.622781) (end 115.85233 112.585793) (width 0.109) (layer "In6.Cu") (net 40))
  (segment (start 109.62182 113.43411) (end 109.642669 113.400929) (width 0.109) (layer "In6.Cu") (net 40))
  (segment (start 104.77733 112.599071) (end 104.798179 112.56589) (width 0.109) (layer "In6.Cu") (net 40))
  (segment (start 104.15907 112.517331) (end 104.196058 112.504388) (width 0.109) (layer "In6.Cu") (net 40))
  (segment (start 108.823941 113.495612) (end 108.860929 113.482669) (width 0.109) (layer "In6.Cu") (net 40))
  (segment (start 104.07733 112.599071) (end 104.098179 112.56589) (width 0.109) (layer "In6.Cu") (net 40))
  (segment (start 121.1 108.84) (end 121.1 105.41) (width 0.109) (layer "In6.Cu") (net 40))
  (segment (start 109.698179 112.56589) (end 109.725889 112.53818) (width 0.109) (layer "In6.Cu") (net 40))
  (segment (start 103.80907 113.482669) (end 103.846058 113.495612) (width 0.109) (layer "In6.Cu") (net 40))
  (segment (start 105.848179 113.43411) (end 105.875889 113.46182) (width 0.109) (layer "In6.Cu") (net 40))
  (segment (start 109.94411 112.53818) (end 109.97182 112.56589) (width 0.109) (layer "In6.Cu") (net 40))
  (segment (start 104.764387 112.636059) (end 104.77733 112.599071) (width 0.109) (layer "In6.Cu") (net 40))
  (segment (start 106.198179 112.56589) (end 106.225889 112.53818) (width 0.109) (layer "In6.Cu") (net 40))
  (segment (start 115.385929 113.01733) (end 115.41911 113.038179) (width 0.109) (layer "In6.Cu") (net 40))
  (segment (start 104.825889 112.53818) (end 104.85907 112.517331) (width 0.109) (layer "In6.Cu") (net 40))
  (segment (start 110.048179 113.43411) (end 110.075889 113.46182) (width 0.109) (layer "In6.Cu") (net 40))
  (segment (start 105.11 112.675) (end 105.11 113.325) (width 0.109) (layer "In6.Cu") (net 40))
  (segment (start 104.055612 113.363941) (end 104.06 113.325) (width 0.109) (layer "In6.Cu") (net 40))
  (segment (start 109.210929 112.517331) (end 109.24411 112.53818) (width 0.109) (layer "In6.Cu") (net 40))
  (segment (start 108.70907 113.482669) (end 108.746058 113.495612) (width 0.109) (layer "In6.Cu") (net 40))
  (segment (start 116.36 113) (end 116.94 113) (width 0.109) (layer "In6.Cu") (net 40))
  (segment (start 105.39411 113.46182) (end 105.42182 113.43411) (width 0.109) (layer "In6.Cu") (net 40))
  (segment (start 109.305612 112.636059) (end 109.31 112.675) (width 0.109) (layer "In6.Cu") (net 40))
  (segment (start 110.01 112.675) (end 110.01 113.325) (width 0.109) (layer "In6.Cu") (net 40))
  (segment (start 104.235 112.5) (end 104.273941 112.504388) (width 0.109) (layer "In6.Cu") (net 40))
  (segment (start 105.285 113.5) (end 105.323941 113.495612) (width 0.109) (layer "In6.Cu") (net 40))
  (segment (start 116.185 112.661722) (end 116.185 112.825) (width 0.109) (layer "In6.Cu") (net 40))
  (segment (start 107.035 112.5) (end 107.073941 112.504388) (width 0.109) (layer "In6.Cu") (net 40))
  (segment (start 106.373941 112.504388) (end 106.410929 112.517331) (width 0.109) (layer "In6.Cu") (net 40))
  (segment (start 104.69411 113.46182) (end 104.72182 113.43411) (width 0.109) (layer "In6.Cu") (net 40))
  (segment (start 110.610929 112.517331) (end 110.64411 112.53818) (width 0.109) (layer "In6.Cu") (net 40))
  (segment (start 106.898179 112.56589) (end 106.925889 112.53818) (width 0.109) (layer "In6.Cu") (net 40))
  (segment (start 115.485 113.338278) (end 115.489387 113.377219) (width 0.109) (layer "In6.Cu") (net 40))
  (segment (start 106.60907 113.482669) (end 106.646058 113.495612) (width 0.109) (layer "In6.Cu") (net 40))
  (segment (start 108.435 112.5) (end 108.473941 112.504388) (width 0.109) (layer "In6.Cu") (net 40))
  (segment (start 106.47182 112.56589) (end 106.492669 112.599071) (width 0.109) (layer "In6.Cu") (net 40))
  (segment (start 110.146058 113.495612) (end 110.185 113.5) (width 0.109) (layer "In6.Cu") (net 40))
  (segment (start 109.05907 112.517331) (end 109.096058 112.504388) (width 0.109) (layer "In6.Cu") (net 40))
  (segment (start 107.423941 113.495612) (end 107.460929 113.482669) (width 0.109) (layer "In6.Cu") (net 40))
  (segment (start 106.023941 113.495612) (end 106.060929 113.482669) (width 0.109) (layer "In6.Cu") (net 40))
  (segment (start 123.968977 103.936023) (end 123.968977 100.698975) (width 0.109) (layer "In6.Cu") (net 40))
  (segment (start 115.489387 113.377219) (end 115.50233 113.414207) (width 0.109) (layer "In6.Cu") (net 40))
  (segment (start 110.775889 113.46182) (end 110.80907 113.482669) (width 0.109) (layer "In6.Cu") (net 40))
  (segment (start 107.65907 112.517331) (end 107.696058 112.504388) (width 0.109) (layer "In6.Cu") (net 40))
  (segment (start 108.123941 113.495612) (end 108.160929 113.482669) (width 0.109) (layer "In6.Cu") (net 40))
  (segment (start 105.114387 113.363941) (end 105.12733 113.400929) (width 0.109) (layer "In6.Cu") (net 40))
  (segment (start 115.485 113.175) (end 115.485 113.338278) (width 0.109) (layer "In6.Cu") (net 40))
  (segment (start 105.455612 113.363941) (end 105.46 113.325) (width 0.109) (layer "In6.Cu") (net 40))
  (segment (start 105.464387 112.636059) (end 105.47733 112.599071) (width 0.109) (layer "In6.Cu") (net 40))
  (segment (start 108.785 113.5) (end 108.823941 113.495612) (width 0.109) (layer "In6.Cu") (net 40))
  (segment (start 110.714387 113.363941) (end 110.72733 113.400929) (width 0.109) (layer "In6.Cu") (net 40))
  (segment (start 109.292669 112.599071) (end 109.305612 112.636059) (width 0.109) (layer "In6.Cu") (net 40))
  (segment (start 115.550889 113.475098) (end 115.58407 113.495947) (width 0.109) (layer "In6.Cu") (net 40))
  (segment (start 104.623941 113.495612) (end 104.660929 113.482669) (width 0.109) (layer "In6.Cu") (net 40))
  (segment (start 104.585 113.5) (end 104.623941 113.495612) (width 0.109) (layer "In6.Cu") (net 40))
  (segment (start 110.260929 113.482669) (end 110.29411 113.46182) (width 0.109) (layer "In6.Cu") (net 40))
  (segment (start 104.042669 113.400929) (end 104.055612 113.363941) (width 0.109) (layer "In6.Cu") (net 40))
  (segment (start 109.642669 113.400929) (end 109.655612 113.363941) (width 0.109) (layer "In6.Cu") (net 40))
  (segment (start 109.135 112.5) (end 109.173941 112.504388) (width 0.109) (layer "In6.Cu") (net 40))
  (segment (start 104.06 112.675) (end 104.064387 112.636059) (width 0.109) (layer "In6.Cu") (net 40))
  (segment (start 109.992669 112.599071) (end 110.005612 112.636059) (width 0.109) (layer "In6.Cu") (net 40))
  (segment (start 105.47733 112.599071) (end 105.498179 112.56589) (width 0.109) (layer "In6.Cu") (net 40))
  (segment (start 105.20907 113.482669) (end 105.246058 113.495612) (width 0.109) (layer "In6.Cu") (net 40))
  (segment (start 109.446058 113.495612) (end 109.485 113.5) (width 0.109) (layer "In6.Cu") (net 40))
  (segment (start 115.348941 113.004387) (end 115.385929 113.01733) (width 0.109) (layer "In6.Cu") (net 40))
  (segment (start 108.746058 113.495612) (end 108.785 113.5) (width 0.109) (layer "In6.Cu") (net 40))
  (segment (start 107.49411 113.46182) (end 107.52182 113.43411) (width 0.109) (layer "In6.Cu") (net 40))
  (segment (start 110.29411 113.46182) (end 110.32182 113.43411) (width 0.109) (layer "In6.Cu") (net 40))
  (segment (start 108.298179 112.56589) (end 108.325889 112.53818) (width 0.109) (layer "In6.Cu") (net 40))
  (segment (start 104.392669 112.599071) (end 104.405612 112.636059) (width 0.109) (layer "In6.Cu") (net 40))
  (segment (start 107.21 113.325) (end 107.214387 113.363941) (width 0.109) (layer "In6.Cu") (net 40))
  (segment (start 103.885 113.5) (end 103.923941 113.495612) (width 0.109) (layer "In6.Cu") (net 40))
  (segment (start 106.505612 112.636059) (end 106.51 112.675) (width 0.109) (layer "In6.Cu") (net 40))
  (segment (start 108.998179 112.56589) (end 109.025889 112.53818) (width 0.109) (layer "In6.Cu") (net 40))
  (segment (start 109.32733 113.400929) (end 109.348179 113.43411) (width 0.109) (layer "In6.Cu") (net 40))
  (segment (start 109.796058 112.504388) (end 109.835 112.5) (width 0.109) (layer "In6.Cu") (net 40))
  (segment (start 110.573941 112.504388) (end 110.610929 112.517331) (width 0.109) (layer "In6.Cu") (net 40))
  (segment (start 115.58407 113.495947) (end 115.621058 113.50889) (width 0.109) (layer "In6.Cu") (net 40))
  (segment (start 109.725889 112.53818) (end 109.75907 112.517331) (width 0.109) (layer "In6.Cu") (net 40))
  (segment (start 109.314387 113.363941) (end 109.32733 113.400929) (width 0.109) (layer "In6.Cu") (net 40))
  (segment (start 106.842669 113.400929) (end 106.855612 113.363941) (width 0.109) (layer "In6.Cu") (net 40))
  (segment (start 105.525889 112.53818) (end 105.55907 112.517331) (width 0.109) (layer "In6.Cu") (net 40))
  (segment (start 108.57182 112.56589) (end 108.592669 112.599071) (width 0.109) (layer "In6.Cu") (net 40))
  (segment (start 103.72733 113.400929) (end 103.748179 113.43411) (width 0.109) (layer "In6.Cu") (net 40))
  (segment (start 107.460929 113.482669) (end 107.49411 113.46182) (width 0.109) (layer "In6.Cu") (net 40))
  (segment (start 106.142669 113.400929) (end 106.155612 113.363941) (width 0.109) (layer "In6.Cu") (net 40))
  (segment (start 105.092669 112.599071) (end 105.105612 112.636059) (width 0.109) (layer "In6.Cu") (net 40))
  (segment (start 91.9 111.940828) (end 92.109172 112.15) (width 0.109) (layer "In6.Cu") (net 40))
  (segment (start 117.868 100.293196) (end 117.873189 100.339257) (width 0.182) (layer "F.Cu") (net 41))
  (segment (start 118.27681 100.339257) (end 118.282 100.293196) (width 0.182) (layer "F.Cu") (net 41))
  (segment (start 117.790062 100.04416) (end 117.822839 100.076937) (width 0.182) (layer "F.Cu") (net 41))
  (segment (start 118.287189 100.159938) (end 118.302499 100.116186) (width 0.182) (layer "F.Cu") (net 41))
  (segment (start 117.822839 100.076937) (end 117.8475 100.116186) (width 0.182) (layer "F.Cu") (net 41))
  (segment (start 118.282 100.293196) (end 118.282 100.206) (width 0.182) (layer "F.Cu") (net 41))
  (segment (start 118.302499 100.116186) (end 118.32716 100.076937) (width 0.182) (layer "F.Cu") (net 41))
  (segment (start 117.945937 100.455035) (end 117.985186 100.479696) (width 0.182) (layer "F.Cu") (net 41))
  (segment (start 117.873189 100.339257) (end 117.888499 100.383009) (width 0.182) (layer "F.Cu") (net 41))
  (segment (start 117.86281 100.159938) (end 117.868 100.206) (width 0.182) (layer "F.Cu") (net 41))
  (segment (start 118.2615 100.383009) (end 118.27681 100.339257) (width 0.182) (layer "F.Cu") (net 41))
  (segment (start 118.204062 100.455035) (end 118.236839 100.422258) (width 0.182) (layer "F.Cu") (net 41))
  (segment (start 118.121061 100.495006) (end 118.164813 100.479696) (width 0.182) (layer "F.Cu") (net 41))
  (segment (start 118.075 100.500196) (end 118.121061 100.495006) (width 0.182) (layer "F.Cu") (net 41))
  (segment (start 118.359937 100.04416) (end 118.399186 100.019499) (width 0.182) (layer "F.Cu") (net 41))
  (segment (start 117.888499 100.383009) (end 117.91316 100.422258) (width 0.182) (layer "F.Cu") (net 41))
  (segment (start 118.399186 100.019499) (end 118.442938 100.004189) (width 0.182) (layer "F.Cu") (net 41))
  (segment (start 117.318608 99.923102) (end 117.394506 99.999) (width 0.182) (layer "F.Cu") (net 41))
  (segment (start 118.32716 100.076937) (end 118.359937 100.04416) (width 0.182) (layer "F.Cu") (net 41))
  (segment (start 118.164813 100.479696) (end 118.204062 100.455035) (width 0.182) (layer "F.Cu") (net 41))
  (segment (start 118.028938 100.495006) (end 118.075 100.500196) (width 0.182) (layer "F.Cu") (net 41))
  (segment (start 117.8475 100.116186) (end 117.86281 100.159938) (width 0.182) (layer "F.Cu") (net 41))
  (segment (start 117.661 99.999) (end 117.707061 100.004189) (width 0.182) (layer "F.Cu") (net 41))
  (segment (start 117.750813 100.019499) (end 117.790062 100.04416) (width 0.182) (layer "F.Cu") (net 41))
  (segment (start 117.707061 100.004189) (end 117.750813 100.019499) (width 0.182) (layer "F.Cu") (net 41))
  (segment (start 118.489 99.999) (end 119.1829 99.999) (width 0.182) (layer "F.Cu") (net 41))
  (segment (start 117.868 100.206) (end 117.868 100.293196) (width 0.182) (layer "F.Cu") (net 41))
  (segment (start 117.91316 100.422258) (end 117.945937 100.455035) (width 0.182) (layer "F.Cu") (net 41))
  (segment (start 118.282 100.206) (end 118.287189 100.159938) (width 0.182) (layer "F.Cu") (net 41))
  (segment (start 91.9 111.181817) (end 92.3665 110.954) (width 0.182) (layer "F.Cu") (net 41))
  (segment (start 118.236839 100.422258) (end 118.2615 100.383009) (width 0.182) (layer "F.Cu") (net 41))
  (segment (start 118.442938 100.004189) (end 118.489 99.999) (width 0.182) (layer "F.Cu") (net 41))
  (segment (start 117.985186 100.479696) (end 118.028938 100.495006) (width 0.182) (layer "F.Cu") (net 41))
  (segment (start 117.394506 99.999) (end 117.661 99.999) (width 0.182) (layer "F.Cu") (net 41))
  (via (at 117.318608 99.923102) (size 0.45) (drill 0.1) (layers "F.Cu" "B.Cu") (net 41))
  (via (at 91.9 111.181817) (size 0.45) (drill 0.1) (layers "F.Cu" "B.Cu") (net 41))
  (segment (start 106.246058 110.095612) (end 106.285 110.1) (width 0.109) (layer "In6.Cu") (net 41))
  (segment (start 117.750915 100.349204) (end 117.720278 100.324772) (width 0.109) (layer "In6.Cu") (net 41))
  (segment (start 106.848179 110.03411) (end 106.875889 110.06182) (width 0.109) (layer "In6.Cu") (net 41))
  (segment (start 97.775889 110.06182) (end 97.80907 110.082669) (width 0.109) (layer "In6.Cu") (net 41))
  (segment (start 106.323941 110.095612) (end 106.360929 110.082669) (width 0.109) (layer "In6.Cu") (net 41))
  (segment (start 99.596058 109.104388) (end 99.635 109.1) (width 0.109) (layer "In6.Cu") (net 41))
  (segment (start 98.15907 109.117331) (end 98.196058 109.104388) (width 0.109) (layer "In6.Cu") (net 41))
  (segment (start 104.342669 110.000929) (end 104.355612 109.963941) (width 0.109) (layer "In6.Cu") (net 41))
  (segment (start 106.74411 109.13818) (end 106.77182 109.16589) (width 0.109) (layer "In6.Cu") (net 41))
  (segment (start 104.425889 109.13818) (end 104.45907 109.117331) (width 0.109) (layer "In6.Cu") (net 41))
  (segment (start 117.786222 100.366207) (end 117.750915 100.349204) (width 0.109) (layer "In6.Cu") (net 41))
  (segment (start 100.12182 110.03411) (end 100.142669 110.000929) (width 0.109) (layer "In6.Cu") (net 41))
  (segment (start 105.392669 109.199071) (end 105.405612 109.236059) (width 0.109) (layer "In6.Cu") (net 41))
  (segment (start 105.34411 109.13818) (end 105.37182 109.16589) (width 0.109) (layer "In6.Cu") (net 41))
  (segment (start 104.923941 110.095612) (end 104.960929 110.082669) (width 0.109) (layer "In6.Cu") (net 41))
  (segment (start 103.97182 109.16589) (end 103.992669 109.199071) (width 0.109) (layer "In6.Cu") (net 41))
  (segment (start 118.438857 99.907673) (end 118.400652 99.916393) (width 0.109) (layer "In6.Cu") (net 41))
  (segment (start 104.71 109.275) (end 104.71 109.925) (width 0.109) (layer "In6.Cu") (net 41))
  (segment (start 100.864387 109.236059) (end 100.87733 109.199071) (width 0.109) (layer "In6.Cu") (net 41))
  (segment (start 104.01 109.275) (end 104.01 109.925) (width 0.109) (layer "In6.Cu") (net 41))
  (segment (start 96.94411 109.638179) (end 96.97182 109.665889) (width 0.109) (layer "In6.Cu") (net 41))
  (segment (start 100.373941 109.104388) (end 100.410929 109.117331) (width 0.109) (layer "In6.Cu") (net 41))
  (segment (start 100.760929 110.082669) (end 100.79411 110.06182) (width 0.109) (layer "In6.Cu") (net 41))
  (segment (start 105.41 109.925) (end 105.414387 109.963941) (width 0.109) (layer "In6.Cu") (net 41))
  (segment (start 100.17733 109.199071) (end 100.198179 109.16589) (width 0.109) (layer "In6.Cu") (net 41))
  (segment (start 102.435 109.1) (end 102.473941 109.104388) (width 0.109) (layer "In6.Cu") (net 41))
  (segment (start 118.3 100.904494) (end 118.215253 100.819747) (width 0.109) (layer "In6.Cu") (net 41))
  (segment (start 103.40907 110.082669) (end 103.446058 110.095612) (width 0.109) (layer "In6.Cu") (net 41))
  (segment (start 101.49411 110.06182) (end 101.52182 110.03411) (width 0.109) (layer "In6.Cu") (net 41))
  (segment (start 103.725889 109.13818) (end 103.75907 109.117331) (width 0.109) (layer "In6.Cu") (net 41))
  (segment (start 99.985 110.1) (end 100.023941 110.095612) (width 0.109) (layer "In6.Cu") (net 41))
  (segment (start 97.885 110.1) (end 97.923941 110.095612) (width 0.109) (layer "In6.Cu") (net 41))
  (segment (start 101.17182 109.16589) (end 101.192669 109.199071) (width 0.109) (layer "In6.Cu") (net 41))
  (segment (start 99.20907 110.082669) (end 99.246058 110.095612) (width 0.109) (layer "In6.Cu") (net 41))
  (segment (start 103.31 109.925) (end 103.314387 109.963941) (width 0.109) (layer "In6.Cu") (net 41))
  (segment (start 100.51 109.925) (end 100.514387 109.963941) (width 0.109) (layer "In6.Cu") (net 41))
  (segment (start 97.573941 109.104388) (end 97.610929 109.117331) (width 0.109) (layer "In6.Cu") (net 41))
  (segment (start 118.623631 100.023774) (end 118.606628 99.988467) (width 0.109) (layer "In6.Cu") (net 41))
  (segment (start 102.35907 109.117331) (end 102.396058 109.104388) (width 0.109) (layer "In6.Cu") (net 41))
  (segment (start 106.47733 109.199071) (end 106.498179 109.16589) (width 0.109) (layer "In6.Cu") (net 41))
  (segment (start 102.325889 109.13818) (end 102.35907 109.117331) (width 0.109) (layer "In6.Cu") (net 41))
  (segment (start 118.582195 100.205316) (end 118.606628 100.174678) (width 0.109) (layer "In6.Cu") (net 41))
  (segment (start 97.36 109.275) (end 97.364387 109.236059) (width 0.109) (layer "In6.Cu") (net 41))
  (segment (start 106.596058 109.104388) (end 106.635 109.1) (width 0.109) (layer "In6.Cu") (net 41))
  (segment (start 96.2 109.6) (end 96.835 109.6) (width 0.109) (layer "In6.Cu") (net 41))
  (segment (start 97.748179 110.03411) (end 97.775889 110.06182) (width 0.109) (layer "In6.Cu") (net 41))
  (segment (start 105.098179 109.16589) (end 105.125889 109.13818) (width 0.109) (layer "In6.Cu") (net 41))
  (segment (start 104.846058 110.095612) (end 104.885 110.1) (width 0.109) (layer "In6.Cu") (net 41))
  (segment (start 98.798179 109.16589) (end 98.825889 109.13818) (width 0.109) (layer "In6.Cu") (net 41))
  (segment (start 102.61 109.275) (end 102.61 109.925) (width 0.109) (layer "In6.Cu") (net 41))
  (segment (start 104.692669 109.199071) (end 104.705612 109.236059) (width 0.109) (layer "In6.Cu") (net 41))
  (segment (start 92.330907 111.181817) (end 92.612724 110.9) (width 0.109) (layer "In6.Cu") (net 41))
  (segment (start 98.585 110.1) (end 98.623941 110.095612) (width 0.109) (layer "In6.Cu") (net 41))
  (segment (start 101.57733 109.199071) (end 101.598179 109.16589) (width 0.109) (layer "In6.Cu") (net 41))
  (segment (start 107.09411 110.06182) (end 107.12182 110.03411) (width 0.109) (layer "In6.Cu") (net 41))
  (segment (start 100.95907 109.117331) (end 100.996058 109.104388) (width 0.109) (layer "In6.Cu") (net 41))
  (segment (start 106.875889 110.06182) (end 106.90907 110.082669) (width 0.109) (layer "In6.Cu") (net 41))
  (segment (start 104.075889 110.06182) (end 104.10907 110.082669) (width 0.109) (layer "In6.Cu") (net 41))
  (segment (start 105.935 109.1) (end 105.973941 109.104388) (width 0.109) (layer "In6.Cu") (net 41))
  (segment (start 100.060929 110.082669) (end 100.09411 110.06182) (width 0.109) (layer "In6.Cu") (net 41))
  (segment (start 103.446058 110.095612) (end 103.485 110.1) (width 0.109) (layer "In6.Cu") (net 41))
  (segment (start 104.67182 109.16589) (end 104.692669 109.199071) (width 0.109) (layer "In6.Cu") (net 41))
  (segment (start 99.42182 110.03411) (end 99.442669 110.000929) (width 0.109) (layer "In6.Cu") (net 41))
  (segment (start 99.010929 109.117331) (end 99.04411 109.13818) (width 0.109) (layer "In6.Cu") (net 41))
  (segment (start 103.523941 110.095612) (end 103.560929 110.082669) (width 0.109) (layer "In6.Cu") (net 41))
  (segment (start 106.985 110.1) (end 107.023941 110.095612) (width 0.109) (layer "In6.Cu") (net 41))
  (segment (start 101.192669 109.199071) (end 101.205612 109.236059) (width 0.109) (layer "In6.Cu") (net 41))
  (segment (start 107.164387 109.736058) (end 107.17733 109.69907) (width 0.109) (layer "In6.Cu") (net 41))
  (segment (start 103.348179 110.03411) (end 103.375889 110.06182) (width 0.109) (layer "In6.Cu") (net 41))
  (segment (start 97.37733 109.199071) (end 97.398179 109.16589) (width 0.109) (layer "In6.Cu") (net 41))
  (segment (start 102.19411 110.06182) (end 102.22182 110.03411) (width 0.109) (layer "In6.Cu") (net 41))
  (segment (start 97.45907 109.117331) (end 97.496058 109.104388) (width 0.109) (layer "In6.Cu") (net 41))
  (segment (start 106.81 109.925) (end 106.814387 109.963941) (width 0.109) (layer "In6.Cu") (net 41))
  (segment (start 106.673941 109.104388) (end 106.710929 109.117331) (width 0.109) (layer "In6.Cu") (net 41))
  (segment (start 106.114387 109.963941) (end 106.12733 110.000929) (width 0.109) (layer "In6.Cu") (net 41))
  (segment (start 100.723941 110.095612) (end 100.760929 110.082669) (width 0.109) (layer "In6.Cu") (net 41))
  (segment (start 100.87733 109.199071) (end 100.898179 109.16589) (width 0.109) (layer "In6.Cu") (net 41))
  (segment (start 97.01 109.925) (end 97.014387 109.963941) (width 0.109) (layer "In6.Cu") (net 41))
  (segment (start 101.735 109.1) (end 101.773941 109.104388) (width 0.109) (layer "In6.Cu") (net 41))
  (segment (start 99.39411 110.06182) (end 99.42182 110.03411) (width 0.109) (layer "In6.Cu") (net 41))
  (segment (start 107.12182 110.03411) (end 107.142669 110.000929) (width 0.109) (layer "In6.Cu") (net 41))
  (segment (start 98.825889 109.13818) (end 98.85907 109.117331) (width 0.109) (layer "In6.Cu") (net 41))
  (segment (start 100.225889 109.13818) (end 100.25907 109.117331) (width 0.109) (layer "In6.Cu") (net 41))
  (segment (start 102.998179 109.16589) (end 103.025889 109.13818) (width 0.109) (layer "In6.Cu") (net 41))
  (segment (start 115.025 109.6) (end 118.3 106.325) (width 0.109) (layer "In6.Cu") (net 41))
  (segment (start 101.975889 110.06182) (end 102.00907 110.082669) (width 0.109) (layer "In6.Cu") (net 41))
  (segment (start 102.62733 110.000929) (end 102.648179 110.03411) (width 0.109) (layer "In6.Cu") (net 41))
  (segment (start 102.785 110.1) (end 102.823941 110.095612) (width 0.109) (layer "In6.Cu") (net 41))
  (segment (start 97.02733 110.000929) (end 97.048179 110.03411) (width 0.109) (layer "In6.Cu") (net 41))
  (segment (start 99.81 109.925) (end 99.814387 109.963941) (width 0.109) (layer "In6.Cu") (net 41))
  (segment (start 98.196058 109.104388) (end 98.235 109.1) (width 0.109) (layer "In6.Cu") (net 41))
  (segment (start 98.973941 109.104388) (end 99.010929 109.117331) (width 0.109) (layer "In6.Cu") (net 41))
  (segment (start 105.77733 109.199071) (end 105.798179 109.16589) (width 0.109) (layer "In6.Cu") (net 41))
  (segment (start 98.042669 110.000929) (end 98.055612 109.963941) (width 0.109) (layer "In6.Cu") (net 41))
  (segment (start 101.52182 110.03411) (end 101.542669 110.000929) (width 0.109) (layer "In6.Cu") (net 41))
  (segment (start 118.51625 99.916393) (end 118.478045 99.907673) (width 0.109) (layer "In6.Cu") (net 41))
  (segment (start 97.71 109.275) (end 97.71 109.925) (width 0.109) (layer "In6.Cu") (net 41))
  (segment (start 98.623941 110.095612) (end 98.660929 110.082669) (width 0.109) (layer "In6.Cu") (net 41))
  (segment (start 100.25907 109.117331) (end 100.296058 109.104388) (width 0.109) (layer "In6.Cu") (net 41))
  (segment (start 104.960929 110.082669) (end 104.99411 110.06182) (width 0.109) (layer "In6.Cu") (net 41))
  (segment (start 107.023941 110.095612) (end 107.060929 110.082669) (width 0.109) (layer "In6.Cu") (net 41))
  (segment (start 100.86 109.275) (end 100.864387 109.236059) (width 0.109) (layer "In6.Cu") (net 41))
  (segment (start 99.47733 109.199071) (end 99.498179 109.16589) (width 0.109) (layer "In6.Cu") (net 41))
  (segment (start 100.548179 110.03411) (end 100.575889 110.06182) (width 0.109) (layer "In6.Cu") (net 41))
  (segment (start 99.848179 110.03411) (end 99.875889 110.06182) (width 0.109) (layer "In6.Cu") (net 41))
  (segment (start 100.16 109.275) (end 100.164387 109.236059) (width 0.109) (layer "In6.Cu") (net 41))
  (segment (start 104.748179 110.03411) (end 104.775889 110.06182) (width 0.109) (layer "In6.Cu") (net 41))
  (segment (start 118.173817 100.753802) (end 118.165097 100.715597) (width 0.109) (layer "In6.Cu") (net 41))
  (segment (start 106.792669 109.199071) (end 106.805612 109.236059) (width 0.109) (layer "In6.Cu") (net 41))
  (segment (start 98.85907 109.117331) (end 98.896058 109.104388) (width 0.109) (layer "In6.Cu") (net 41))
  (segment (start 118.632351 100.101166) (end 118.632351 100.061979) (width 0.109) (layer "In6.Cu") (net 41))
  (segment (start 104.705612 109.236059) (end 104.71 109.275) (width 0.109) (layer "In6.Cu") (net 41))
  (segment (start 106.42182 110.03411) (end 106.442669 110.000929) (width 0.109) (layer "In6.Cu") (net 41))
  (segment (start 100.142669 110.000929) (end 100.155612 109.963941) (width 0.109) (layer "In6.Cu") (net 41))
  (segment (start 104.775889 110.06182) (end 104.80907 110.082669) (width 0.109) (layer "In6.Cu") (net 41))
  (segment (start 105.660929 110.082669) (end 105.69411 110.06182) (width 0.109) (layer "In6.Cu") (net 41))
  (segment (start 104.36 109.275) (end 104.364387 109.236059) (width 0.109) (layer "In6.Cu") (net 41))
  (segment (start 106.710929 109.117331) (end 106.74411 109.13818) (width 0.109) (layer "In6.Cu") (net 41))
  (segment (start 102.264387 109.236059) (end 102.27733 109.199071) (width 0.109) (layer "In6.Cu") (net 41))
  (segment (start 104.885 110.1) (end 104.923941 110.095612) (width 0.109) (layer "In6.Cu") (net 41))
  (segment (start 106.39411 110.06182) (end 106.42182 110.03411) (width 0.109) (layer "In6.Cu") (net 41))
  (segment (start 99.07182 109.16589) (end 99.092669 109.199071) (width 0.109) (layer "In6.Cu") (net 41))
  (segment (start 101.84411 109.13818) (end 101.87182 109.16589) (width 0.109) (layer "In6.Cu") (net 41))
  (segment (start 101.87182 109.16589) (end 101.892669 109.199071) (width 0.109) (layer "In6.Cu") (net 41))
  (segment (start 102.22182 110.03411) (end 102.242669 110.000929) (width 0.109) (layer "In6.Cu") (net 41))
  (segment (start 102.396058 109.104388) (end 102.435 109.1) (width 0.109) (layer "In6.Cu") (net 41))
  (segment (start 98.72182 110.03411) (end 98.742669 110.000929) (width 0.109) (layer "In6.Cu") (net 41))
  (segment (start 100.47182 109.16589) (end 100.492669 109.199071) (width 0.109) (layer "In6.Cu") (net 41))
  (segment (start 101.14411 109.13818) (end 101.17182 109.16589) (width 0.109) (layer "In6.Cu") (net 41))
  (segment (start 101.385 110.1) (end 101.423941 110.095612) (width 0.109) (layer "In6.Cu") (net 41))
  (segment (start 102.255612 109.963941) (end 102.26 109.925) (width 0.109) (layer "In6.Cu") (net 41))
  (segment (start 106.092669 109.199071) (end 106.105612 109.236059) (width 0.109) (layer "In6.Cu") (net 41))
  (segment (start 97.260929 110.082669) (end 97.29411 110.06182) (width 0.109) (layer "In6.Cu") (net 41))
  (segment (start 96.97182 109.665889) (end 96.992669 109.69907) (width 0.109) (layer "In6.Cu") (net 41))
  (segment (start 103.664387 109.236059) (end 103.67733 109.199071) (width 0.109) (layer "In6.Cu") (net 41))
  (segment (start 99.11 109.925) (end 99.114387 109.963941) (width 0.109) (layer "In6.Cu") (net 41))
  (segment (start 103.31 109.275) (end 103.31 109.925) (width 0.109) (layer "In6.Cu") (net 41))
  (segment (start 118.334707 99.957829) (end 117.967764 100.324771) (width 0.109) (layer "In6.Cu") (net 41))
  (segment (start 104.71 109.925) (end 104.714387 109.963941) (width 0.109) (layer "In6.Cu") (net 41))
  (segment (start 98.273941 109.104388) (end 98.310929 109.117331) (width 0.109) (layer "In6.Cu") (net 41))
  (segment (start 100.51 109.275) (end 100.51 109.925) (width 0.109) (layer "In6.Cu") (net 41))
  (segment (start 100.198179 109.16589) (end 100.225889 109.13818) (width 0.109) (layer "In6.Cu") (net 41))
  (segment (start 103.66 109.925) (end 103.66 109.275) (width 0.109) (layer "In6.Cu") (net 41))
  (segment (start 98.660929 110.082669) (end 98.69411 110.06182) (width 0.109) (layer "In6.Cu") (net 41))
  (segment (start 106.82733 110.000929) (end 106.848179 110.03411) (width 0.109) (layer "In6.Cu") (net 41))
  (segment (start 97.223941 110.095612) (end 97.260929 110.082669) (width 0.109) (layer "In6.Cu") (net 41))
  (segment (start 99.092669 109.199071) (end 99.105612 109.236059) (width 0.109) (layer "In6.Cu") (net 41))
  (segment (start 107.16 109.775) (end 107.164387 109.736058) (width 0.109) (layer "In6.Cu") (net 41))
  (segment (start 102.046058 110.095612) (end 102.085 110.1) (width 0.109) (layer "In6.Cu") (net 41))
  (segment (start 102.160929 110.082669) (end 102.19411 110.06182) (width 0.109) (layer "In6.Cu") (net 41))
  (segment (start 105.448179 110.03411) (end 105.475889 110.06182) (width 0.109) (layer "In6.Cu") (net 41))
  (segment (start 99.805612 109.236059) (end 99.81 109.275) (width 0.109) (layer "In6.Cu") (net 41))
  (segment (start 98.064387 109.236059) (end 98.07733 109.199071) (width 0.109) (layer "In6.Cu") (net 41))
  (segment (start 104.45907 109.117331) (end 104.496058 109.104388) (width 0.109) (layer "In6.Cu") (net 41))
  (segment (start 104.714387 109.963941) (end 104.72733 110.000929) (width 0.109) (layer "In6.Cu") (net 41))
  (segment (start 100.155612 109.963941) (end 100.16 109.925) (width 0.109) (layer "In6.Cu") (net 41))
  (segment (start 101.22733 110.000929) (end 101.248179 110.03411) (width 0.109) (layer "In6.Cu") (net 41))
  (segment (start 99.46 109.925) (end 99.46 109.275) (width 0.109) (layer "In6.Cu") (net 41))
  (segment (start 102.823941 110.095612) (end 102.860929 110.082669) (width 0.109) (layer "In6.Cu") (net 41))
  (segment (start 100.82182 110.03411) (end 100.842669 110.000929) (width 0.109) (layer "In6.Cu") (net 41))
  (segment (start 103.992669 109.199071) (end 104.005612 109.236059) (width 0.109) (layer "In6.Cu") (net 41))
  (segment (start 105.475889 110.06182) (end 105.50907 110.082669) (width 0.109) (layer "In6.Cu") (net 41))
  (segment (start 97.425889 109.13818) (end 97.45907 109.117331) (width 0.109) (layer "In6.Cu") (net 41))
  (segment (start 104.260929 110.082669) (end 104.29411 110.06182) (width 0.109) (layer "In6.Cu") (net 41))
  (segment (start 103.59411 110.06182) (end 103.62182 110.03411) (width 0.109) (layer "In6.Cu") (net 41))
  (segment (start 104.72733 110.000929) (end 104.748179 110.03411) (width 0.109) (layer "In6.Cu") (net 41))
  (segment (start 104.355612 109.963941) (end 104.36 109.925) (width 0.109) (layer "In6.Cu") (net 41))
  (segment (start 102.54411 109.13818) (end 102.57182 109.16589) (width 0.109) (layer "In6.Cu") (net 41))
  (segment (start 99.285 110.1) (end 99.323941 110.095612) (width 0.109) (layer "In6.Cu") (net 41))
  (segment (start 103.796058 109.104388) (end 103.835 109.1) (width 0.109) (layer "In6.Cu") (net 41))
  (segment (start 99.814387 109.963941) (end 99.82733 110.000929) (width 0.109) (layer "In6.Cu") (net 41))
  (segment (start 106.12733 110.000929) (end 106.148179 110.03411) (width 0.109) (layer "In6.Cu") (net 41))
  (segment (start 101.423941 110.095612) (end 101.460929 110.082669) (width 0.109) (layer "In6.Cu") (net 41))
  (segment (start 103.655612 109.963941) (end 103.66 109.925) (width 0.109) (layer "In6.Cu") (net 41))
  (segment (start 97.398179 109.16589) (end 97.425889 109.13818) (width 0.109) (layer "In6.Cu") (net 41))
  (segment (start 106.498179 109.16589) (end 106.525889 109.13818) (width 0.109) (layer "In6.Cu") (net 41))
  (segment (start 103.66 109.275) (end 103.664387 109.236059) (width 0.109) (layer "In6.Cu") (net 41))
  (segment (start 107.225889 109.638179) (end 107.25907 109.61733) (width 0.109) (layer "In6.Cu") (net 41))
  (segment (start 97.923941 110.095612) (end 97.960929 110.082669) (width 0.109) (layer "In6.Cu") (net 41))
  (segment (start 98.37182 109.16589) (end 98.392669 109.199071) (width 0.109) (layer "In6.Cu") (net 41))
  (segment (start 104.64411 109.13818) (end 104.67182 109.16589) (width 0.109) (layer "In6.Cu") (net 41))
  (segment (start 101.56 109.925) (end 101.56 109.275) (width 0.109) (layer "In6.Cu") (net 41))
  (segment (start 99.525889 109.13818) (end 99.55907 109.117331) (width 0.109) (layer "In6.Cu") (net 41))
  (segment (start 118.3 106.325) (end 118.3 100.904494) (width 0.109) (layer "In6.Cu") (net 41))
  (segment (start 97.535 109.1) (end 97.573941 109.104388) (width 0.109) (layer "In6.Cu") (net 41))
  (segment (start 98.896058 109.104388) (end 98.935 109.1) (width 0.109) (layer "In6.Cu") (net 41))
  (segment (start 102.92182 110.03411) (end 102.942669 110.000929) (width 0.109) (layer "In6.Cu") (net 41))
  (segment (start 106.360929 110.082669) (end 106.39411 110.06182) (width 0.109) (layer "In6.Cu") (net 41))
  (segment (start 97.146058 110.095612) (end 97.185 110.1) (width 0.109) (layer "In6.Cu") (net 41))
  (segment (start 97.72733 110.000929) (end 97.748179 110.03411) (width 0.109) (layer "In6.Cu") (net 41))
  (segment (start 101.346058 110.095612) (end 101.385 110.1) (width 0.109) (layer "In6.Cu") (net 41))
  (segment (start 104.496058 109.104388) (end 104.535 109.1) (width 0.109) (layer "In6.Cu") (net 41))
  (segment (start 105.764387 109.236059) (end 105.77733 109.199071) (width 0.109) (layer "In6.Cu") (net 41))
  (segment (start 100.855612 109.963941) (end 100.86 109.925) (width 0.109) (layer "In6.Cu") (net 41))
  (segment (start 99.360929 110.082669) (end 99.39411 110.06182) (width 0.109) (layer "In6.Cu") (net 41))
  (segment (start 102.97733 109.199071) (end 102.998179 109.16589) (width 0.109) (layer "In6.Cu") (net 41))
  (segment (start 118.215253 100.572259) (end 118.582195 100.205316) (width 0.109) (layer "In6.Cu") (net 41))
  (segment (start 103.67733 109.199071) (end 103.698179 109.16589) (width 0.109) (layer "In6.Cu") (net 41))
  (segment (start 102.592669 109.199071) (end 102.605612 109.236059) (width 0.109) (layer "In6.Cu") (net 41))
  (segment (start 97.075889 110.06182) (end 97.10907 110.082669) (width 0.109) (layer "In6.Cu") (net 41))
  (segment (start 101.542669 110.000929) (end 101.555612 109.963941) (width 0.109) (layer "In6.Cu") (net 41))
  (segment (start 98.546058 110.095612) (end 98.585 110.1) (width 0.109) (layer "In6.Cu") (net 41))
  (segment (start 100.60907 110.082669) (end 100.646058 110.095612) (width 0.109) (layer "In6.Cu") (net 41))
  (segment (start 98.755612 109.963941) (end 98.76 109.925) (width 0.109) (layer "In6.Cu") (net 41))
  (segment (start 102.61 109.925) (end 102.614387 109.963941) (width 0.109) (layer "In6.Cu") (net 41))
  (segment (start 105.235 109.1) (end 105.273941 109.104388) (width 0.109) (layer "In6.Cu") (net 41))
  (segment (start 104.10907 110.082669) (end 104.146058 110.095612) (width 0.109) (layer "In6.Cu") (net 41))
  (segment (start 104.01 109.925) (end 104.014387 109.963941) (width 0.109) (layer "In6.Cu") (net 41))
  (segment (start 101.30907 110.082669) (end 101.346058 110.095612) (width 0.109) (layer "In6.Cu") (net 41))
  (segment (start 96.910929 109.61733) (end 96.94411 109.638179) (width 0.109) (layer "In6.Cu") (net 41))
  (segment (start 101.460929 110.082669) (end 101.49411 110.06182) (width 0.109) (layer "In6.Cu") (net 41))
  (segment (start 101.275889 110.06182) (end 101.30907 110.082669) (width 0.109) (layer "In6.Cu") (net 41))
  (segment (start 103.173941 109.104388) (end 103.210929 109.117331) (width 0.109) (layer "In6.Cu") (net 41))
  (segment (start 105.06 109.925) (end 105.06 109.275) (width 0.109) (layer "In6.Cu") (net 41))
  (segment (start 117.863614 100.374927) (end 117.824427 100.374927) (width 0.109) (layer "In6.Cu") (net 41))
  (segment (start 100.646058 110.095612) (end 100.685 110.1) (width 0.109) (layer "In6.Cu") (net 41))
  (segment (start 98.07733 109.199071) (end 98.098179 109.16589) (width 0.109) (layer "In6.Cu") (net 41))
  (segment (start 104.29411 110.06182) (end 104.32182 110.03411) (width 0.109) (layer "In6.Cu") (net 41))
  (segment (start 118.190819 100.602897) (end 118.215253 100.572259) (width 0.109) (layer "In6.Cu") (net 41))
  (segment (start 103.375889 110.06182) (end 103.40907 110.082669) (width 0.109) (layer "In6.Cu") (net 41))
  (segment (start 97.29411 110.06182) (end 97.32182 110.03411) (width 0.109) (layer "In6.Cu") (net 41))
  (segment (start 97.67182 109.16589) (end 97.692669 109.199071) (width 0.109) (layer "In6.Cu") (net 41))
  (segment (start 105.37182 109.16589) (end 105.392669 109.199071) (width 0.109) (layer "In6.Cu") (net 41))
  (segment (start 101.948179 110.03411) (end 101.975889 110.06182) (width 0.109) (layer "In6.Cu") (net 41))
  (segment (start 100.996058 109.104388) (end 101.035 109.1) (width 0.109) (layer "In6.Cu") (net 41))
  (segment (start 99.81 109.275) (end 99.81 109.925) (width 0.109) (layer "In6.Cu") (net 41))
  (segment (start 104.36 109.925) (end 104.36 109.275) (width 0.109) (layer "In6.Cu") (net 41))
  (segment (start 100.505612 109.236059) (end 100.51 109.275) (width 0.109) (layer "In6.Cu") (net 41))
  (segment (start 105.310929 109.117331) (end 105.34411 109.13818) (width 0.109) (layer "In6.Cu") (net 41))
  (segment (start 106.635 109.1) (end 106.673941 109.104388) (width 0.109) (layer "In6.Cu") (net 41))
  (segment (start 100.023941 110.095612) (end 100.060929 110.082669) (width 0.109) (layer "In6.Cu") (net 41))
  (segment (start 106.464387 109.236059) (end 106.47733 109.199071) (width 0.109) (layer "In6.Cu") (net 41))
  (segment (start 101.598179 109.16589) (end 101.625889 109.13818) (width 0.109) (layer "In6.Cu") (net 41))
  (segment (start 101.205612 109.236059) (end 101.21 109.275) (width 0.109) (layer "In6.Cu") (net 41))
  (segment (start 104.32182 110.03411) (end 104.342669 110.000929) (width 0.109) (layer "In6.Cu") (net 41))
  (segment (start 100.296058 109.104388) (end 100.335 109.1) (width 0.109) (layer "In6.Cu") (net 41))
  (segment (start 106.442669 110.000929) (end 106.455612 109.963941) (width 0.109) (layer "In6.Cu") (net 41))
  (segment (start 105.41 109.275) (end 105.41 109.925) (width 0.109) (layer "In6.Cu") (net 41))
  (segment (start 104.223941 110.095612) (end 104.260929 110.082669) (width 0.109) (layer "In6.Cu") (net 41))
  (segment (start 101.696058 109.104388) (end 101.735 109.1) (width 0.109) (layer "In6.Cu") (net 41))
  (segment (start 97.714387 109.963941) (end 97.72733 110.000929) (width 0.109) (layer "In6.Cu") (net 41))
  (segment (start 103.305612 109.236059) (end 103.31 109.275) (width 0.109) (layer "In6.Cu") (net 41))
  (segment (start 105.196058 109.104388) (end 105.235 109.1) (width 0.109) (layer "In6.Cu") (net 41))
  (segment (start 99.74411 109.13818) (end 99.77182 109.16589) (width 0.109) (layer "In6.Cu") (net 41))
  (segment (start 98.935 109.1) (end 98.973941 109.104388) (width 0.109) (layer "In6.Cu") (net 41))
  (segment (start 99.148179 110.03411) (end 99.175889 110.06182) (width 0.109) (layer "In6.Cu") (net 41))
  (segment (start 105.825889 109.13818) (end 105.85907 109.117331) (width 0.109) (layer "In6.Cu") (net 41))
  (segment (start 105.06 109.275) (end 105.064387 109.236059) (width 0.109) (layer "In6.Cu") (net 41))
  (segment (start 91.9 111.181817) (end 92.330907 111.181817) (width 0.109) (layer "In6.Cu") (net 41))
  (segment (start 101.248179 110.03411) (end 101.275889 110.06182) (width 0.109) (layer "In6.Cu") (net 41))
  (segment (start 103.873941 109.104388) (end 103.910929 109.117331) (width 0.109) (layer "In6.Cu") (net 41))
  (segment (start 96.835 109.6) (end 96.873941 109.604387) (width 0.109) (layer "In6.Cu") (net 41))
  (segment (start 101.810929 109.117331) (end 101.84411 109.13818) (width 0.109) (layer "In6.Cu") (net 41))
  (segment (start 103.24411 109.13818) (end 103.27182 109.16589) (width 0.109) (layer "In6.Cu") (net 41))
  (segment (start 104.573941 109.104388) (end 104.610929 109.117331) (width 0.109) (layer "In6.Cu") (net 41))
  (segment (start 99.710929 109.117331) (end 99.74411 109.13818) (width 0.109) (layer "In6.Cu") (net 41))
  (segment (start 101.892669 109.199071) (end 101.905612 109.236059) (width 0.109) (layer "In6.Cu") (net 41))
  (segment (start 101.073941 109.104388) (end 101.110929 109.117331) (width 0.109) (layer "In6.Cu") (net 41))
  (segment (start 105.742669 110.000929) (end 105.755612 109.963941) (width 0.109) (layer "In6.Cu") (net 41))
  (segment (start 105.76 109.925) (end 105.76 109.275) (width 0.109) (layer "In6.Cu") (net 41))
  (segment (start 107.25907 109.61733) (end 107.296058 109.604387) (width 0.109) (layer "In6.Cu") (net 41))
  (segment (start 98.392669 109.199071) (end 98.405612 109.236059) (width 0.109) (layer "In6.Cu") (net 41))
  (segment (start 104.398179 109.16589) (end 104.425889 109.13818) (width 0.109) (layer "In6.Cu") (net 41))
  (segment (start 104.37733 109.199071) (end 104.398179 109.16589) (width 0.109) (layer "In6.Cu") (net 41))
  (segment (start 118.582195 99.957829) (end 118.551556 99.933395) (width 0.109) (layer "In6.Cu") (net 41))
  (segment (start 100.44411 109.13818) (end 100.47182 109.16589) (width 0.109) (layer "In6.Cu") (net 41))
  (segment (start 118.551556 99.933395) (end 118.51625 99.916393) (width 0.109) (layer "In6.Cu") (net 41))
  (segment (start 97.342669 110.000929) (end 97.355612 109.963941) (width 0.109) (layer "In6.Cu") (net 41))
  (segment (start 118.400652 99.916393) (end 118.365345 99.933395) (width 0.109) (layer "In6.Cu") (net 41))
  (segment (start 118.173817 100.638204) (end 118.190819 100.602897) (width 0.109) (layer "In6.Cu") (net 41))
  (segment (start 106.55907 109.117331) (end 106.596058 109.104388) (width 0.109) (layer "In6.Cu") (net 41))
  (segment (start 102.89411 110.06182) (end 102.92182 110.03411) (width 0.109) (layer "In6.Cu") (net 41))
  (segment (start 101.914387 109.963941) (end 101.92733 110.000929) (width 0.109) (layer "In6.Cu") (net 41))
  (segment (start 105.85907 109.117331) (end 105.896058 109.104388) (width 0.109) (layer "In6.Cu") (net 41))
  (segment (start 117.418711 100.023205) (end 117.318608 99.923102) (width 0.109) (layer "In6.Cu") (net 41))
  (segment (start 107.16 109.925) (end 107.16 109.775) (width 0.109) (layer "In6.Cu") (net 41))
  (segment (start 118.190819 100.789108) (end 118.173817 100.753802) (width 0.109) (layer "In6.Cu") (net 41))
  (segment (start 105.585 110.1) (end 105.623941 110.095612) (width 0.109) (layer "In6.Cu") (net 41))
  (segment (start 118.623631 100.139371) (end 118.632351 100.101166) (width 0.109) (layer "In6.Cu") (net 41))
  (segment (start 99.498179 109.16589) (end 99.525889 109.13818) (width 0.109) (layer "In6.Cu") (net 41))
  (segment (start 97.36 109.925) (end 97.36 109.275) (width 0.109) (layer "In6.Cu") (net 41))
  (segment (start 104.535 109.1) (end 104.573941 109.104388) (width 0.109) (layer "In6.Cu") (net 41))
  (segment (start 117.720278 100.324772) (end 117.418711 100.023205) (width 0.109) (layer "In6.Cu") (net 41))
  (segment (start 100.575889 110.06182) (end 100.60907 110.082669) (width 0.109) (layer "In6.Cu") (net 41))
  (segment (start 98.414387 109.963941) (end 98.42733 110.000929) (width 0.109) (layer "In6.Cu") (net 41))
  (segment (start 105.125889 109.13818) (end 105.15907 109.117331) (width 0.109) (layer "In6.Cu") (net 41))
  (segment (start 100.86 109.925) (end 100.86 109.275) (width 0.109) (layer "In6.Cu") (net 41))
  (segment (start 106.010929 109.117331) (end 106.04411 109.13818) (width 0.109) (layer "In6.Cu") (net 41))
  (segment (start 103.27182 109.16589) (end 103.292669 109.199071) (width 0.109) (layer "In6.Cu") (net 41))
  (segment (start 105.405612 109.236059) (end 105.41 109.275) (width 0.109) (layer "In6.Cu") (net 41))
  (segment (start 101.773941 109.104388) (end 101.810929 109.117331) (width 0.109) (layer "In6.Cu") (net 41))
  (segment (start 97.80907 110.082669) (end 97.846058 110.095612) (width 0.109) (layer "In6.Cu") (net 41))
  (segment (start 101.035 109.1) (end 101.073941 109.104388) (width 0.109) (layer "In6.Cu") (net 41))
  (segment (start 118.606628 100.174678) (end 118.623631 100.139371) (width 0.109) (layer "In6.Cu") (net 41))
  (segment (start 97.99411 110.06182) (end 98.02182 110.03411) (width 0.109) (layer "In6.Cu") (net 41))
  (segment (start 104.80907 110.082669) (end 104.846058 110.095612) (width 0.109) (layer "In6.Cu") (net 41))
  (segment (start 117.901819 100.366207) (end 117.863614 100.374927) (width 0.109) (layer "In6.Cu") (net 41))
  (segment (start 103.292669 109.199071) (end 103.305612 109.236059) (width 0.109) (layer "In6.Cu") (net 41))
  (segment (start 99.246058 110.095612) (end 99.285 110.1) (width 0.109) (layer "In6.Cu") (net 41))
  (segment (start 98.310929 109.117331) (end 98.34411 109.13818) (width 0.109) (layer "In6.Cu") (net 41))
  (segment (start 105.76 109.275) (end 105.764387 109.236059) (width 0.109) (layer "In6.Cu") (net 41))
  (segment (start 102.70907 110.082669) (end 102.746058 110.095612) (width 0.109) (layer "In6.Cu") (net 41))
  (segment (start 103.210929 109.117331) (end 103.24411 109.13818) (width 0.109) (layer "In6.Cu") (net 41))
  (segment (start 105.414387 109.963941) (end 105.42733 110.000929) (width 0.109) (layer "In6.Cu") (net 41))
  (segment (start 98.475889 110.06182) (end 98.50907 110.082669) (width 0.109) (layer "In6.Cu") (net 41))
  (segment (start 107.060929 110.082669) (end 107.09411 110.06182) (width 0.109) (layer "In6.Cu") (net 41))
  (segment (start 97.692669 109.199071) (end 97.705612 109.236059) (width 0.109) (layer "In6.Cu") (net 41))
  (segment (start 104.185 110.1) (end 104.223941 110.095612) (width 0.109) (layer "In6.Cu") (net 41))
  (segment (start 100.685 110.1) (end 100.723941 110.095612) (width 0.109) (layer "In6.Cu") (net 41))
  (segment (start 101.905612 109.236059) (end 101.91 109.275) (width 0.109) (layer "In6.Cu") (net 41))
  (segment (start 103.698179 109.16589) (end 103.725889 109.13818) (width 0.109) (layer "In6.Cu") (net 41))
  (segment (start 101.91 109.925) (end 101.914387 109.963941) (width 0.109) (layer "In6.Cu") (net 41))
  (segment (start 98.41 109.925) (end 98.414387 109.963941) (width 0.109) (layer "In6.Cu") (net 41))
  (segment (start 97.364387 109.236059) (end 97.37733 109.199071) (width 0.109) (layer "In6.Cu") (net 41))
  (segment (start 104.02733 110.000929) (end 104.048179 110.03411) (width 0.109) (layer "In6.Cu") (net 41))
  (segment (start 102.942669 110.000929) (end 102.955612 109.963941) (width 0.109) (layer "In6.Cu") (net 41))
  (segment (start 98.405612 109.236059) (end 98.41 109.275) (width 0.109) (layer "In6.Cu") (net 41))
  (segment (start 97.846058 110.095612) (end 97.885 110.1) (width 0.109) (layer "In6.Cu") (net 41))
  (segment (start 104.99411 110.06182) (end 105.02182 110.03411) (width 0.109) (layer "In6.Cu") (net 41))
  (segment (start 106.20907 110.082669) (end 106.246058 110.095612) (width 0.109) (layer "In6.Cu") (net 41))
  (segment (start 106.46 109.925) (end 106.46 109.275) (width 0.109) (layer "In6.Cu") (net 41))
  (segment (start 106.805612 109.236059) (end 106.81 109.275) (width 0.109) (layer "In6.Cu") (net 41))
  (segment (start 107.142669 110.000929) (end 107.155612 109.963941) (width 0.109) (layer "In6.Cu") (net 41))
  (segment (start 103.560929 110.082669) (end 103.59411 110.06182) (width 0.109) (layer "In6.Cu") (net 41))
  (segment (start 99.114387 109.963941) (end 99.12733 110.000929) (width 0.109) (layer "In6.Cu") (net 41))
  (segment (start 97.10907 110.082669) (end 97.146058 110.095612) (width 0.109) (layer "In6.Cu") (net 41))
  (segment (start 100.52733 110.000929) (end 100.548179 110.03411) (width 0.109) (layer "In6.Cu") (net 41))
  (segment (start 97.185 110.1) (end 97.223941 110.095612) (width 0.109) (layer "In6.Cu") (net 41))
  (segment (start 107.296058 109.604387) (end 107.335 109.6) (width 0.109) (layer "In6.Cu") (net 41))
  (segment (start 102.298179 109.16589) (end 102.325889 109.13818) (width 0.109) (layer "In6.Cu") (net 41))
  (segment (start 118.606628 99.988467) (end 118.582195 99.957829) (width 0.109) (layer "In6.Cu") (net 41))
  (segment (start 99.90907 110.082669) (end 99.946058 110.095612) (width 0.109) (layer "In6.Cu") (net 41))
  (segment (start 104.005612 109.236059) (end 104.01 109.275) (width 0.109) (layer "In6.Cu") (net 41))
  (segment (start 103.94411 109.13818) (end 103.97182 109.16589) (width 0.109) (layer "In6.Cu") (net 41))
  (segment (start 103.314387 109.963941) (end 103.32733 110.000929) (width 0.109) (layer "In6.Cu") (net 41))
  (segment (start 99.792669 109.199071) (end 99.805612 109.236059) (width 0.109) (layer "In6.Cu") (net 41))
  (segment (start 98.69411 110.06182) (end 98.72182 110.03411) (width 0.109) (layer "In6.Cu") (net 41))
  (segment (start 102.96 109.925) (end 102.96 109.275) (width 0.109) (layer "In6.Cu") (net 41))
  (segment (start 99.464387 109.236059) (end 99.47733 109.199071) (width 0.109) (layer "In6.Cu") (net 41))
  (segment (start 107.17733 109.69907) (end 107.198179 109.665889) (width 0.109) (layer "In6.Cu") (net 41))
  (segment (start 103.32733 110.000929) (end 103.348179 110.03411) (width 0.109) (layer "In6.Cu") (net 41))
  (segment (start 98.76 109.925) (end 98.76 109.275) (width 0.109) (layer "In6.Cu") (net 41))
  (segment (start 103.05907 109.117331) (end 103.096058 109.104388) (width 0.109) (layer "In6.Cu") (net 41))
  (segment (start 106.525889 109.13818) (end 106.55907 109.117331) (width 0.109) (layer "In6.Cu") (net 41))
  (segment (start 97.960929 110.082669) (end 97.99411 110.06182) (width 0.109) (layer "In6.Cu") (net 41))
  (segment (start 98.02182 110.03411) (end 98.042669 110.000929) (width 0.109) (layer "In6.Cu") (net 41))
  (segment (start 100.492669 109.199071) (end 100.505612 109.236059) (width 0.109) (layer "In6.Cu") (net 41))
  (segment (start 105.755612 109.963941) (end 105.76 109.925) (width 0.109) (layer "In6.Cu") (net 41))
  (segment (start 100.16 109.925) (end 100.16 109.275) (width 0.109) (layer "In6.Cu") (net 41))
  (segment (start 106.455612 109.963941) (end 106.46 109.925) (width 0.109) (layer "In6.Cu") (net 41))
  (segment (start 106.105612 109.236059) (end 106.11 109.275) (width 0.109) (layer "In6.Cu") (net 41))
  (segment (start 100.925889 109.13818) (end 100.95907 109.117331) (width 0.109) (layer "In6.Cu") (net 41))
  (segment (start 117.824427 100.374927) (end 117.786222 100.366207) (width 0.109) (layer "In6.Cu") (net 41))
  (segment (start 106.81 109.275) (end 106.81 109.925) (width 0.109) (layer "In6.Cu") (net 41))
  (segment (start 102.242669 110.000929) (end 102.255612 109.963941) (width 0.109) (layer "In6.Cu") (net 41))
  (segment (start 105.72182 110.03411) (end 105.742669 110.000929) (width 0.109) (layer "In6.Cu") (net 41))
  (segment (start 101.110929 109.117331) (end 101.14411 109.13818) (width 0.109) (layer "In6.Cu") (net 41))
  (segment (start 96.873941 109.604387) (end 96.910929 109.61733) (width 0.109) (layer "In6.Cu") (net 41))
  (segment (start 105.055612 109.963941) (end 105.06 109.925) (width 0.109) (layer "In6.Cu") (net 41))
  (segment (start 101.21 109.275) (end 101.21 109.925) (width 0.109) (layer "In6.Cu") (net 41))
  (segment (start 105.064387 109.236059) (end 105.07733 109.199071) (width 0.109) (layer "In6.Cu") (net 41))
  (segment (start 98.448179 110.03411) (end 98.475889 110.06182) (width 0.109) (layer "In6.Cu") (net 41))
  (segment (start 103.485 110.1) (end 103.523941 110.095612) (width 0.109) (layer "In6.Cu") (net 41))
  (segment (start 107.155612 109.963941) (end 107.16 109.925) (width 0.109) (layer "In6.Cu") (net 41))
  (segment (start 106.11 109.925) (end 106.114387 109.963941) (width 0.109) (layer "In6.Cu") (net 41))
  (segment (start 101.214387 109.963941) (end 101.22733 110.000929) (width 0.109) (layer "In6.Cu") (net 41))
  (segment (start 106.04411 109.13818) (end 106.07182 109.16589) (width 0.109) (layer "In6.Cu") (net 41))
  (segment (start 99.635 109.1) (end 99.673941 109.104388) (width 0.109) (layer "In6.Cu") (net 41))
  (segment (start 105.546058 110.095612) (end 105.585 110.1) (width 0.109) (layer "In6.Cu") (net 41))
  (segment (start 92.612724 110.9) (end 94.9 110.9) (width 0.109) (layer "In6.Cu") (net 41))
  (segment (start 101.21 109.925) (end 101.214387 109.963941) (width 0.109) (layer "In6.Cu") (net 41))
  (segment (start 99.875889 110.06182) (end 99.90907 110.082669) (width 0.109) (layer "In6.Cu") (net 41))
  (segment (start 99.46 109.275) (end 99.464387 109.236059) (width 0.109) (layer "In6.Cu") (net 41))
  (segment (start 106.148179 110.03411) (end 106.175889 110.06182) (width 0.109) (layer "In6.Cu") (net 41))
  (segment (start 105.896058 109.104388) (end 105.935 109.1) (width 0.109) (layer "In6.Cu") (net 41))
  (segment (start 101.65907 109.117331) (end 101.696058 109.104388) (width 0.109) (layer "In6.Cu") (net 41))
  (segment (start 106.946058 110.095612) (end 106.985 110.1) (width 0.109) (layer "In6.Cu") (net 41))
  (segment (start 106.90907 110.082669) (end 106.946058 110.095612) (width 0.109) (layer "In6.Cu") (net 41))
  (segment (start 99.04411 109.13818) (end 99.07182 109.16589) (width 0.109) (layer "In6.Cu") (net 41))
  (segment (start 103.910929 109.117331) (end 103.94411 109.13818) (width 0.109) (layer "In6.Cu") (net 41))
  (segment (start 101.555612 109.963941) (end 101.56 109.925) (width 0.109) (layer "In6.Cu") (net 41))
  (segment (start 102.964387 109.236059) (end 102.97733 109.199071) (width 0.109) (layer "In6.Cu") (net 41))
  (segment (start 104.364387 109.236059) (end 104.37733 109.199071) (width 0.109) (layer "In6.Cu") (net 41))
  (segment (start 100.335 109.1) (end 100.373941 109.104388) (width 0.109) (layer "In6.Cu") (net 41))
  (segment (start 106.77182 109.16589) (end 106.792669 109.199071) (width 0.109) (layer "In6.Cu") (net 41))
  (segment (start 98.76 109.275) (end 98.764387 109.236059) (width 0.109) (layer "In6.Cu") (net 41))
  (segment (start 100.164387 109.236059) (end 100.17733 109.199071) (width 0.109) (layer "In6.Cu") (net 41))
  (segment (start 117.967764 100.324771) (end 117.937126 100.349204) (width 0.109) (layer "In6.Cu") (net 41))
  (segment (start 99.442669 110.000929) (end 99.455612 109.963941) (width 0.109) (layer "In6.Cu") (net 41))
  (segment (start 97.64411 109.13818) (end 97.67182 109.16589) (width 0.109) (layer "In6.Cu") (net 41))
  (segment (start 102.605612 109.236059) (end 102.61 109.275) (width 0.109) (layer "In6.Cu") (net 41))
  (segment (start 97.496058 109.104388) (end 97.535 109.1) (width 0.109) (layer "In6.Cu") (net 41))
  (segment (start 102.27733 109.199071) (end 102.298179 109.16589) (width 0.109) (layer "In6.Cu") (net 41))
  (segment (start 102.26 109.925) (end 102.26 109.275) (width 0.109) (layer "In6.Cu") (net 41))
  (segment (start 101.625889 109.13818) (end 101.65907 109.117331) (width 0.109) (layer "In6.Cu") (net 41))
  (segment (start 97.71 109.925) (end 97.714387 109.963941) (width 0.109) (layer "In6.Cu") (net 41))
  (segment (start 97.610929 109.117331) (end 97.64411 109.13818) (width 0.109) (layer "In6.Cu") (net 41))
  (segment (start 118.165097 100.676409) (end 118.173817 100.638204) (width 0.109) (layer "In6.Cu") (net 41))
  (segment (start 99.77182 109.16589) (end 99.792669 109.199071) (width 0.109) (layer "In6.Cu") (net 41))
  (segment (start 99.946058 110.095612) (end 99.985 110.1) (width 0.109) (layer "In6.Cu") (net 41))
  (segment (start 100.842669 110.000929) (end 100.855612 109.963941) (width 0.109) (layer "In6.Cu") (net 41))
  (segment (start 98.42733 110.000929) (end 98.448179 110.03411) (width 0.109) (layer "In6.Cu") (net 41))
  (segment (start 97.005612 109.736058) (end 97.01 109.775) (width 0.109) (layer "In6.Cu") (net 41))
  (segment (start 106.285 110.1) (end 106.323941 110.095612) (width 0.109) (layer "In6.Cu") (net 41))
  (segment (start 102.57182 109.16589) (end 102.592669 109.199071) (width 0.109) (layer "In6.Cu") (net 41))
  (segment (start 105.69411 110.06182) (end 105.72182 110.03411) (width 0.109) (layer "In6.Cu") (net 41))
  (segment (start 98.41 109.275) (end 98.41 109.925) (width 0.109) (layer "In6.Cu") (net 41))
  (segment (start 106.175889 110.06182) (end 106.20907 110.082669) (width 0.109) (layer "In6.Cu") (net 41))
  (segment (start 100.09411 110.06182) (end 100.12182 110.03411) (width 0.109) (layer "In6.Cu") (net 41))
  (segment (start 102.648179 110.03411) (end 102.675889 110.06182) (width 0.109) (layer "In6.Cu") (net 41))
  (segment (start 118.478045 99.907673) (end 118.438857 99.907673) (width 0.109) (layer "In6.Cu") (net 41))
  (segment (start 101.56 109.275) (end 101.564387 109.236059) (width 0.109) (layer "In6.Cu") (net 41))
  (segment (start 104.610929 109.117331) (end 104.64411 109.13818) (width 0.109) (layer "In6.Cu") (net 41))
  (segment (start 100.898179 109.16589) (end 100.925889 109.13818) (width 0.109) (layer "In6.Cu") (net 41))
  (segment (start 106.11 109.275) (end 106.11 109.925) (width 0.109) (layer "In6.Cu") (net 41))
  (segment (start 103.025889 109.13818) (end 103.05907 109.117331) (width 0.109) (layer "In6.Cu") (net 41))
  (segment (start 102.510929 109.117331) (end 102.54411 109.13818) (width 0.109) (layer "In6.Cu") (net 41))
  (segment (start 97.355612 109.963941) (end 97.36 109.925) (width 0.109) (layer "In6.Cu") (net 41))
  (segment (start 97.32182 110.03411) (end 97.342669 110.000929) (width 0.109) (layer "In6.Cu") (net 41))
  (segment (start 102.26 109.275) (end 102.264387 109.236059) (width 0.109) (layer "In6.Cu") (net 41))
  (segment (start 100.410929 109.117331) (end 100.44411 109.13818) (width 0.109) (layer "In6.Cu") (net 41))
  (segment (start 98.06 109.925) (end 98.06 109.275) (width 0.109) (layer "In6.Cu") (net 41))
  (segment (start 102.746058 110.095612) (end 102.785 110.1) (width 0.109) (layer "In6.Cu") (net 41))
  (segment (start 107.198179 109.665889) (end 107.225889 109.638179) (width 0.109) (layer "In6.Cu") (net 41))
  (segment (start 101.564387 109.236059) (end 101.57733 109.199071) (width 0.109) (layer "In6.Cu") (net 41))
  (segment (start 102.614387 109.963941) (end 102.62733 110.000929) (width 0.109) (layer "In6.Cu") (net 41))
  (segment (start 97.048179 110.03411) (end 97.075889 110.06182) (width 0.109) (layer "In6.Cu") (net 41))
  (segment (start 98.34411 109.13818) (end 98.37182 109.16589) (width 0.109) (layer "In6.Cu") (net 41))
  (segment (start 101.92733 110.000929) (end 101.948179 110.03411) (width 0.109) (layer "In6.Cu") (net 41))
  (segment (start 99.323941 110.095612) (end 99.360929 110.082669) (width 0.109) (layer "In6.Cu") (net 41))
  (segment (start 104.014387 109.963941) (end 104.02733 110.000929) (width 0.109) (layer "In6.Cu") (net 41))
  (segment (start 99.82733 110.000929) (end 99.848179 110.03411) (width 0.109) (layer "In6.Cu") (net 41))
  (segment (start 98.235 109.1) (end 98.273941 109.104388) (width 0.109) (layer "In6.Cu") (net 41))
  (segment (start 118.215253 100.819747) (end 118.190819 100.789108) (width 0.109) (layer "In6.Cu") (net 41))
  (segment (start 103.62182 110.03411) (end 103.642669 110.000929) (width 0.109) (layer "In6.Cu") (net 41))
  (segment (start 102.96 109.275) (end 102.964387 109.236059) (width 0.109) (layer "In6.Cu") (net 41))
  (segment (start 99.105612 109.236059) (end 99.11 109.275) (width 0.109) (layer "In6.Cu") (net 41))
  (segment (start 97.014387 109.963941) (end 97.02733 110.000929) (width 0.109) (layer "In6.Cu") (net 41))
  (segment (start 107.335 109.6) (end 115.025 109.6) (width 0.109) (layer "In6.Cu") (net 41))
  (segment (start 117.937126 100.349204) (end 117.901819 100.366207) (width 0.109) (layer "In6.Cu") (net 41))
  (segment (start 99.673941 109.104388) (end 99.710929 109.117331) (width 0.109) (layer "In6.Cu") (net 41))
  (segment (start 103.75907 109.117331) (end 103.796058 109.104388) (width 0.109) (layer "In6.Cu") (net 41))
  (segment (start 102.123941 110.095612) (end 102.160929 110.082669) (width 0.109) (layer "In6.Cu") (net 41))
  (segment (start 94.9 110.9) (end 96.2 109.6) (width 0.109) (layer "In6.Cu") (net 41))
  (segment (start 106.07182 109.16589) (end 106.092669 109.199071) (width 0.109) (layer "In6.Cu") (net 41))
  (segment (start 103.835 109.1) (end 103.873941 109.104388) (width 0.109) (layer "In6.Cu") (net 41))
  (segment (start 102.00907 110.082669) (end 102.046058 110.095612) (width 0.109) (layer "In6.Cu") (net 41))
  (segment (start 105.623941 110.095612) (end 105.660929 110.082669) (width 0.109) (layer "In6.Cu") (net 41))
  (segment (start 105.07733 109.199071) (end 105.098179 109.16589) (width 0.109) (layer "In6.Cu") (net 41))
  (segment (start 105.973941 109.104388) (end 106.010929 109.117331) (width 0.109) (layer "In6.Cu") (net 41))
  (segment (start 99.12733 110.000929) (end 99.148179 110.03411) (width 0.109) (layer "In6.Cu") (net 41))
  (segment (start 103.642669 110.000929) (end 103.655612 109.963941) (width 0.109) (layer "In6.Cu") (net 41))
  (segment (start 118.632351 100.061979) (end 118.623631 100.023774) (width 0.109) (layer "In6.Cu") (net 41))
  (segment (start 104.048179 110.03411) (end 104.075889 110.06182) (width 0.109) (layer "In6.Cu") (net 41))
  (segment (start 96.992669 109.69907) (end 97.005612 109.736058) (width 0.109) (layer "In6.Cu") (net 41))
  (segment (start 101.91 109.275) (end 101.91 109.925) (width 0.109) (layer "In6.Cu") (net 41))
  (segment (start 98.764387 109.236059) (end 98.77733 109.199071) (width 0.109) (layer "In6.Cu") (net 41))
  (segment (start 98.77733 109.199071) (end 98.798179 109.16589) (width 0.109) (layer "In6.Cu") (net 41))
  (segment (start 105.15907 109.117331) (end 105.196058 109.104388) (width 0.109) (layer "In6.Cu") (net 41))
  (segment (start 97.705612 109.236059) (end 97.71 109.275) (width 0.109) (layer "In6.Cu") (net 41))
  (segment (start 99.175889 110.06182) (end 99.20907 110.082669) (width 0.109) (layer "In6.Cu") (net 41))
  (segment (start 99.55907 109.117331) (end 99.596058 109.104388) (width 0.109) (layer "In6.Cu") (net 41))
  (segment (start 105.042669 110.000929) (end 105.055612 109.963941) (width 0.109) (layer "In6.Cu") (net 41))
  (segment (start 103.135 109.1) (end 103.173941 109.104388) (width 0.109) (layer "In6.Cu") (net 41))
  (segment (start 98.50907 110.082669) (end 98.546058 110.095612) (width 0.109) (layer "In6.Cu") (net 41))
  (segment (start 100.79411 110.06182) (end 100.82182 110.03411) (width 0.109) (layer "In6.Cu") (net 41))
  (segment (start 102.085 110.1) (end 102.123941 110.095612) (width 0.109) (layer "In6.Cu") (net 41))
  (segment (start 102.675889 110.06182) (end 102.70907 110.082669) (width 0.109) (layer "In6.Cu") (net 41))
  (segment (start 102.860929 110.082669) (end 102.89411 110.06182) (width 0.109) (layer "In6.Cu") (net 41))
  (segment (start 104.146058 110.095612) (end 104.185 110.1) (width 0.109) (layer "In6.Cu") (net 41))
  (segment (start 98.055612 109.963941) (end 98.06 109.925) (width 0.109) (layer "In6.Cu") (net 41))
  (segment (start 99.455612 109.963941) (end 99.46 109.925) (width 0.109) (layer "In6.Cu") (net 41))
  (segment (start 99.11 109.275) (end 99.11 109.925) (width 0.109) (layer "In6.Cu") (net 41))
  (segment (start 105.798179 109.16589) (end 105.825889 109.13818) (width 0.109) (layer "In6.Cu") (net 41))
  (segment (start 98.125889 109.13818) (end 98.15907 109.117331) (width 0.109) (layer "In6.Cu") (net 41))
  (segment (start 100.514387 109.963941) (end 100.52733 110.000929) (width 0.109) (layer "In6.Cu") (net 41))
  (segment (start 97.01 109.775) (end 97.01 109.925) (width 0.109) (layer "In6.Cu") (net 41))
  (segment (start 118.365345 99.933395) (end 118.334707 99.957829) (width 0.109) (layer "In6.Cu") (net 41))
  (segment (start 105.273941 109.104388) (end 105.310929 109.117331) (width 0.109) (layer "In6.Cu") (net 41))
  (segment (start 106.814387 109.963941) (end 106.82733 110.000929) (width 0.109) (layer "In6.Cu") (net 41))
  (segment (start 106.46 109.275) (end 106.464387 109.236059) (width 0.109) (layer "In6.Cu") (net 41))
  (segment (start 105.42733 110.000929) (end 105.448179 110.03411) (width 0.109) (layer "In6.Cu") (net 41))
  (segment (start 105.50907 110.082669) (end 105.546058 110.095612) (width 0.109) (layer "In6.Cu") (net 41))
  (segment (start 118.165097 100.715597) (end 118.165097 100.676409) (width 0.109) (layer "In6.Cu") (net 41))
  (segment (start 98.742669 110.000929) (end 98.755612 109.963941) (width 0.109) (layer "In6.Cu") (net 41))
  (segment (start 102.955612 109.963941) (end 102.96 109.925) (width 0.109) (layer "In6.Cu") (net 41))
  (segment (start 98.06 109.275) (end 98.064387 109.236059) (width 0.109) (layer "In6.Cu") (net 41))
  (segment (start 98.098179 109.16589) (end 98.125889 109.13818) (width 0.109) (layer "In6.Cu") (net 41))
  (segment (start 103.096058 109.104388) (end 103.135 109.1) (width 0.109) (layer "In6.Cu") (net 41))
  (segment (start 105.02182 110.03411) (end 105.042669 110.000929) (width 0.109) (layer "In6.Cu") (net 41))
  (segment (start 102.473941 109.104388) (end 102.510929 109.117331) (width 0.109) (layer "In6.Cu") (net 41))
  (segment (start 118.538183 98.817651) (end 118.522348 98.801816) (width 0.182) (layer "F.Cu") (net 42))
  (segment (start 118.167816 98.817651) (end 118.155903 98.836611) (width 0.182) (layer "F.Cu") (net 42))
  (segment (start 118.136096 99.123389) (end 118.124183 99.142349) (width 0.182) (layer "F.Cu") (net 42))
  (segment (start 118.557492 98.857747) (end 118.550096 98.836611) (width 0.182) (layer "F.Cu") (net 42))
  (segment (start 118.46 98.78) (end 118.246 98.78) (width 0.182) (layer "F.Cu") (net 42))
  (segment (start 118.562507 98.902252) (end 118.557492 98.857747) (width 0.182) (layer "F.Cu") (net 42))
  (segment (start 118.581816 98.942348) (end 118.569903 98.923388) (width 0.182) (layer "F.Cu") (net 42))
  (segment (start 118.550096 98.836611) (end 118.538183 98.817651) (width 0.182) (layer "F.Cu") (net 42))
  (segment (start 117.675388 98.989904) (end 117.654252 98.982508) (width 0.182) (layer "F.Cu") (net 42))
  (segment (start 118.124183 99.142349) (end 118.108348 99.158184) (width 0.182) (layer "F.Cu") (net 42))
  (segment (start 117.832 99.18) (end 117.809747 99.177493) (width 0.182) (layer "F.Cu") (net 42))
  (segment (start 117.710183 99.017652) (end 117.694348 99.001817) (width 0.182) (layer "F.Cu") (net 42))
  (segment (start 118.522348 98.801816) (end 118.503388 98.789903) (width 0.182) (layer "F.Cu") (net 42))
  (segment (start 118.155903 98.836611) (end 118.148507 98.857747) (width 0.182) (layer "F.Cu") (net 42))
  (segment (start 117.286277 98.944645) (end 117.279975 98.938343) (width 0.182) (layer "F.Cu") (net 42))
  (segment (start 118.143492 99.102253) (end 118.136096 99.123389) (width 0.182) (layer "F.Cu") (net 42))
  (segment (start 117.741903 99.123389) (end 117.734507 99.102253) (width 0.182) (layer "F.Cu") (net 42))
  (segment (start 118.068252 99.177493) (end 118.046 99.18) (width 0.182) (layer "F.Cu") (net 42))
  (segment (start 118.046 99.18) (end 117.832 99.18) (width 0.182) (layer "F.Cu") (net 42))
  (segment (start 117.654252 98.982508) (end 117.632 98.98) (width 0.182) (layer "F.Cu") (net 42))
  (segment (start 118.762545 98.983) (end 118.759545 98.98) (width 0.182) (layer "F.Cu") (net 42))
  (segment (start 118.637747 98.977492) (end 118.616611 98.970096) (width 0.182) (layer "F.Cu") (net 42))
  (segment (start 117.769651 99.158184) (end 117.753816 99.142349) (width 0.182) (layer "F.Cu") (net 42))
  (segment (start 117.632 98.98) (end 117.321632 98.98) (width 0.182) (layer "F.Cu") (net 42))
  (segment (start 118.503388 98.789903) (end 118.482252 98.782507) (width 0.182) (layer "F.Cu") (net 42))
  (segment (start 118.108348 99.158184) (end 118.089388 99.170097) (width 0.182) (layer "F.Cu") (net 42))
  (segment (start 118.089388 99.170097) (end 118.068252 99.177493) (width 0.182) (layer "F.Cu") (net 42))
  (segment (start 118.246 98.78) (end 118.223747 98.782507) (width 0.182) (layer "F.Cu") (net 42))
  (segment (start 117.809747 99.177493) (end 117.788611 99.170097) (width 0.182) (layer "F.Cu") (net 42))
  (segment (start 119.1829 98.983) (end 118.762545 98.983) (width 0.182) (layer "F.Cu") (net 42))
  (segment (start 118.616611 98.970096) (end 118.597651 98.958183) (width 0.182) (layer "F.Cu") (net 42))
  (segment (start 117.734507 99.102253) (end 117.729492 99.057748) (width 0.182) (layer "F.Cu") (net 42))
  (segment (start 117.321632 98.98) (end 117.286277 98.944645) (width 0.182) (layer "F.Cu") (net 42))
  (segment (start 118.183651 98.801816) (end 118.167816 98.817651) (width 0.182) (layer "F.Cu") (net 42))
  (segment (start 118.202611 98.789903) (end 118.183651 98.801816) (width 0.182) (layer "F.Cu") (net 42))
  (segment (start 118.148507 98.857747) (end 118.146 98.88) (width 0.182) (layer "F.Cu") (net 42))
  (segment (start 118.223747 98.782507) (end 118.202611 98.789903) (width 0.182) (layer "F.Cu") (net 42))
  (segment (start 118.482252 98.782507) (end 118.46 98.78) (width 0.182) (layer "F.Cu") (net 42))
  (segment (start 118.569903 98.923388) (end 118.562507 98.902252) (width 0.182) (layer "F.Cu") (net 42))
  (segment (start 118.66 98.98) (end 118.637747 98.977492) (width 0.182) (layer "F.Cu") (net 42))
  (segment (start 118.597651 98.958183) (end 118.581816 98.942348) (width 0.182) (layer "F.Cu") (net 42))
  (segment (start 117.753816 99.142349) (end 117.741903 99.123389) (width 0.182) (layer "F.Cu") (net 42))
  (segment (start 117.788611 99.170097) (end 117.769651 99.158184) (width 0.182) (layer "F.Cu") (net 42))
  (segment (start 118.146 99.08) (end 118.143492 99.102253) (width 0.182) (layer "F.Cu") (net 42))
  (segment (start 118.146 98.88) (end 118.146 99.08) (width 0.182) (layer "F.Cu") (net 42))
  (segment (start 92.3665 110.319) (end 92.84 110.005) (width 0.182) (layer "F.Cu") (net 42))
  (segment (start 117.722096 99.036612) (end 117.710183 99.017652) (width 0.182) (layer "F.Cu") (net 42))
  (segment (start 117.694348 99.001817) (end 117.675388 98.989904) (width 0.182) (layer "F.Cu") (net 42))
  (segment (start 118.759545 98.98) (end 118.66 98.98) (width 0.182) (layer "F.Cu") (net 42))
  (segment (start 117.729492 99.057748) (end 117.722096 99.036612) (width 0.182) (layer "F.Cu") (net 42))
  (via (at 117.279975 98.938343) (size 0.45) (drill 0.1) (layers "F.Cu" "B.Cu") (net 42))
  (via (at 92.84 110.005) (size 0.45) (drill 0.1) (layers "F.Cu" "B.Cu") (net 42))
  (segment (start 115.538917 103.961058) (end 115.55186 103.92407) (width 0.109) (layer "In6.Cu") (net 42))
  (segment (start 115.234529 100.974998) (end 115.78547 100.975) (width 0.109) (layer "In6.Cu") (net 42))
  (segment (start 115.589387 102.511058) (end 115.60233 102.47407) (width 0.109) (layer "In6.Cu") (net 42))
  (segment (start 109.980612 107.513941) (end 109.985 107.475) (width 0.109) (layer "In6.Cu") (net 42))
  (segment (start 108.33407 107.632669) (end 108.371058 107.645612) (width 0.109) (layer "In6.Cu") (net 42))
  (segment (start 112.610929 107.06733) (end 112.64411 107.088179) (width 0.109) (layer "In6.Cu") (net 42))
  (segment (start 109.38407 106.067331) (end 109.421058 106.054388) (width 0.109) (layer "In6.Cu") (net 42))
  (segment (start 112.64411 107.088179) (end 112.67182 107.115889) (width 0.109) (layer "In6.Cu") (net 42))
  (segment (start 107.167669 107.550929) (end 107.180612 107.513941) (width 0.109) (layer "In6.Cu") (net 42))
  (segment (start 110.86 107.05) (end 112.535 107.05) (width 0.109) (layer "In6.Cu") (net 42))
  (segment (start 112.923941 107.645612) (end 112.960929 107.632669) (width 0.109) (layer "In6.Cu") (net 42))
  (segment (start 115.572709 103.890889) (end 115.600419 103.863179) (width 0.109) (layer "In6.Cu") (net 42))
  (segment (start 107.185 107.475) (end 107.185 106.225) (width 0.109) (layer "In6.Cu") (net 42))
  (segment (start 115.60233 100.525928) (end 115.589387 100.48894) (width 0.109) (layer "In6.Cu") (net 42))
  (segment (start 107.950889 106.08818) (end 107.98407 106.067331) (width 0.109) (layer "In6.Cu") (net 42))
  (segment (start 109.59682 106.11589) (end 109.617669 106.149071) (width 0.109) (layer "In6.Cu") (net 42))
  (segment (start 107.048941 107.645612) (end 107.085929 107.632669) (width 0.109) (layer "In6.Cu") (net 42))
  (segment (start 107.085929 107.632669) (end 107.11911 107.61182) (width 0.109) (layer "In6.Cu") (net 42))
  (segment (start 93.195 110.005) (end 93.3125 109.8875) (width 0.109) (layer "In6.Cu") (net 42))
  (segment (start 114.982787 105.777211) (end 116.06 104.7) (width 0.109) (layer "In6.Cu") (net 42))
  (segment (start 115.68407 100.607668) (end 115.650889 100.586819) (width 0.109) (layer "In6.Cu") (net 42))
  (segment (start 109.11 107.65) (end 109.148941 107.645612) (width 0.109) (layer "In6.Cu") (net 42))
  (segment (start 116.581083 103.688941) (end 116.585471 103.65) (width 0.109) (layer "In6.Cu") (net 42))
  (segment (start 110.400889 107.61182) (end 110.43407 107.632669) (width 0.109) (layer "In6.Cu") (net 42))
  (segment (start 113.405612 106.186059) (end 113.41 106.225) (width 0.109) (layer "In6.Cu") (net 42))
  (segment (start 109.24682 107.58411) (end 109.267669 107.550929) (width 0.109) (layer "In6.Cu") (net 42))
  (segment (start 107.36 106.05) (end 107.398941 106.054388) (width 0.109) (layer "In6.Cu") (net 42))
  (segment (start 114.876722 106.413608) (end 114.90736 106.438041) (width 0.109) (layer "In6.Cu") (net 42))
  (segment (start 108.371058 107.645612) (end 108.41 107.65) (width 0.109) (layer "In6.Cu") (net 42))
  (segment (start 114.67939 106.765243) (end 114.67067 106.727038) (width 0.109) (layer "In6.Cu") (net 42))
  (segment (start 108.68407 106.067331) (end 108.721058 106.054388) (width 0.109) (layer "In6.Cu") (net 42))
  (segment (start 110.821058 107.054387) (end 110.86 107.05) (width 0.109) (layer "In6.Cu") (net 42))
  (segment (start 115.585 102.55) (end 115.589387 102.511058) (width 0.109) (layer "In6.Cu") (net 42))
  (segment (start 114.932631 105.920548) (end 114.932631 105.881361) (width 0.109) (layer "In6.Cu") (net 42))
  (segment (start 108.41 107.65) (end 108.448941 107.645612) (width 0.109) (layer "In6.Cu") (net 42))
  (segment (start 114.174382 106.725724) (end 114.209689 106.742726) (width 0.109) (layer "In6.Cu") (net 42))
  (segment (start 107.435929 106.067331) (end 107.46911 106.08818) (width 0.109) (layer "In6.Cu") (net 42))
  (segment (start 113.448179 106.984111) (end 113.475889 107.011821) (width 0.109) (layer "In6.Cu") (net 42))
  (segment (start 115.922291 101.60911) (end 115.94314 101.575929) (width 0.109) (layer "In6.Cu") (net 42))
  (segment (start 115.063917 101.18894) (end 115.059529 101.149999) (width 0.109) (layer "In6.Cu") (net 42))
  (segment (start 115.8614 101.34233) (end 115.824412 101.329387) (width 0.109) (layer "In6.Cu") (net 42))
  (segment (start 115.709529 103.825) (end 116.410471 103.825) (width 0.109) (layer "In6.Cu") (net 42))
  (segment (start 116.196058 104.529387) (end 116.235 104.525) (width 0.109) (layer "In6.Cu") (net 42))
  (segment (start 116.547291 104.45911) (end 116.56814 104.425929) (width 0.109) (layer "In6.Cu") (net 42))
  (segment (start 95.505837 107.05) (end 106.66 107.05) (width 0.109) (layer "In6.Cu") (net 42))
  (segment (start 113.125889 106.08818) (end 113.15907 106.067331) (width 0.109) (layer "In6.Cu") (net 42))
  (segment (start 108.935 106.225) (end 108.935 107.475) (width 0.109) (layer "In6.Cu") (net 42))
  (segment (start 110.317669 106.149071) (end 110.330612 106.186059) (width 0.109) (layer "In6.Cu") (net 42))
  (segment (start 116.410471 103.825) (end 116.449412 103.820612) (width 0.109) (layer "In6.Cu") (net 42))
  (segment (start 115.23453 102.024999) (end 115.195588 102.020611) (width 0.109) (layer "In6.Cu") (net 42))
  (segment (start 109.639387 107.513941) (end 109.65233 107.550929) (width 0.109) (layer "In6.Cu") (net 42))
  (segment (start 109.323179 106.11589) (end 109.350889 106.08818) (width 0.109) (layer "In6.Cu") (net 42))
  (segment (start 93.790419 108.765419) (end 95.505837 107.05) (width 0.109) (layer "In6.Cu") (net 42))
  (segment (start 115.585 100.449998) (end 115.585001 99.694999) (width 0.109) (layer "In6.Cu") (net 42))
  (segment (start 113.098179 106.11589) (end 113.125889 106.08818) (width 0.109) (layer "In6.Cu") (net 42))
  (segment (start 110.16 106.05) (end 110.198941 106.054388) (width 0.109) (layer "In6.Cu") (net 42))
  (segment (start 115.063917 101.88894) (end 115.059529 101.849999) (width 0.109) (layer "In6.Cu") (net 42))
  (segment (start 108.098941 106.054388) (end 108.135929 106.067331) (width 0.109) (layer "In6.Cu") (net 42))
  (segment (start 114.447693 106.950017) (end 114.485898 106.958737) (width 0.109) (layer "In6.Cu") (net 42))
  (segment (start 106.971058 107.645612) (end 107.01 107.65) (width 0.109) (layer "In6.Cu") (net 42))
  (segment (start 113.846652 105.523645) (end 113.884858 105.514924) (width 0.109) (layer "In6.Cu") (net 42))
  (segment (start 115.93547 102.375) (end 115.974412 102.370612) (width 0.109) (layer "In6.Cu") (net 42))
  (segment (start 115.94314 101.42407) (end 115.922291 101.390889) (width 0.109) (layer "In6.Cu") (net 42))
  (segment (start 113.235 106.05) (end 113.273941 106.054388) (width 0.109) (layer "In6.Cu") (net 42))
  (segment (start 112.573941 107.054387) (end 112.610929 107.06733) (width 0.109) (layer "In6.Cu") (net 42))
  (segment (start 114.629235 106.661093) (end 113.780708 105.812566) (width 0.109) (layer "In6.Cu") (net 42))
  (segment (start 115.097709 101.740888) (end 115.125419 101.713178) (width 0.109) (layer "In6.Cu") (net 42))
  (segment (start 115.07686 101.774069) (end 115.097709 101.740888) (width 0.109) (layer "In6.Cu") (net 42))
  (segment (start 108.239387 107.513941) (end 108.25233 107.550929) (width 0.109) (layer "In6.Cu") (net 42))
  (segment (start 110.51 107.65) (end 110.548941 107.645612) (width 0.109) (layer "In6.Cu") (net 42))
  (segment (start 114.525085 106.958737) (end 114.56329 106.950017) (width 0.109) (layer "In6.Cu") (net 42))
  (segment (start 113.06 107.475) (end 113.06 106.225) (width 0.109) (layer "In6.Cu") (net 42))
  (segment (start 110.050889 106.08818) (end 110.08407 106.067331) (width 0.109) (layer "In6.Cu") (net 42))
  (segment (start 116.110471 102.2) (end 116.106083 102.161058) (width 0.109) (layer "In6.Cu") (net 42))
  (segment (start 108.448941 107.645612) (end 108.485929 107.632669) (width 0.109) (layer "In6.Cu") (net 42))
  (segment (start 115.148642 106.196758) (end 115.124209 106.16612) (width 0.109) (layer "In6.Cu") (net 42))
  (segment (start 115.174364 106.27027) (end 115.165644 106.232065) (width 0.109) (layer "In6.Cu") (net 42))
  (segment (start 110.023179 106.11589) (end 110.050889 106.08818) (width 0.109) (layer "In6.Cu") (net 42))
  (segment (start 107.14682 107.58411) (end 107.167669 107.550929) (width 0.109) (layer "In6.Cu") (net 42))
  (segment (start 116.449412 104.179387) (end 116.410471 104.175) (width 0.109) (layer "In6.Cu") (net 42))
  (segment (start 114.653668 106.877942) (end 114.67067 106.842636) (width 0.109) (layer "In6.Cu") (net 42))
  (segment (start 116.449412 103.479387) (end 116.410471 103.475) (width 0.109) (layer "In6.Cu") (net 42))
  (segment (start 116.547291 104.240889) (end 116.519581 104.213179) (width 0.109) (layer "In6.Cu") (net 42))
  (segment (start 115.55186 103.92407) (end 115.572709 103.890889) (width 0.109) (layer "In6.Cu") (net 42))
  (segment (start 106.817669 107.14907) (end 106.830612 107.186058) (width 0.109) (layer "In6.Cu") (net 42))
  (segment (start 106.93407 107.632669) (end 106.971058 107.645612) (width 0.109) (layer "In6.Cu") (net 42))
  (segment (start 115.94314 100.72407) (end 115.922291 100.690889) (width 0.109) (layer "In6.Cu") (net 42))
  (segment (start 110.585929 107.632669) (end 110.61911 107.61182) (width 0.109) (layer "In6.Cu") (net 42))
  (segment (start 109.03407 107.632669) (end 109.071058 107.645612) (width 0.109) (layer "In6.Cu") (net 42))
  (segment (start 106.85233 107.550929) (end 106.873179 107.58411) (width 0.109) (layer "In6.Cu") (net 42))
  (segment (start 115.623179 100.559109) (end 115.60233 100.525928) (width 0.109) (layer "In6.Cu") (net 42))
  (segment (start 114.932631 105.881361) (end 114.941351 105.843156) (width 0.109) (layer "In6.Cu") (net 42))
  (segment (start 116.585471 104.35) (end 116.581083 104.311058) (width 0.109) (layer "In6.Cu") (net 42))
  (segment (start 114.058784 106.725724) (end 114.096989 106.717004) (width 0.109) (layer "In6.Cu") (net 42))
  (segment (start 114.67067 106.727038) (end 114.653668 106.691731) (width 0.109) (layer "In6.Cu") (net 42))
  (segment (start 115.68407 102.39233) (end 115.721058 102.379387) (width 0.109) (layer "In6.Cu") (net 42))
  (segment (start 112.960929 107.632669) (end 112.99411 107.61182) (width 0.109) (layer "In6.Cu") (net 42))
  (segment (start 116.519581 104.48682) (end 116.547291 104.45911) (width 0.109) (layer "In6.Cu") (net 42))
  (segment (start 107.671058 107.645612) (end 107.71 107.65) (width 0.109) (layer "In6.Cu") (net 42))
  (segment (start 115.8614 100.957669) (end 115.894581 100.93682) (width 0.109) (layer "In6.Cu") (net 42))
  (segment (start 115.195588 100.979386) (end 115.234529 100.974998) (width 0.109) (layer "In6.Cu") (net 42))
  (segment (start 116.15907 103.457669) (end 116.125889 103.43682) (width 0.109) (layer "In6.Cu") (net 42))
  (segment (start 116.581083 104.388941) (end 116.585471 104.35) (width 0.109) (layer "In6.Cu") (net 42))
  (segment (start 115.650889 100.586819) (end 115.623179 100.559109) (width 0.109) (layer "In6.Cu") (net 42))
  (segment (start 116.235 103.475) (end 116.196058 103.470612) (width 0.109) (layer "In6.Cu") (net 42))
  (segment (start 115.125419 101.286819) (end 115.097709 101.259109) (width 0.109) (layer "In6.Cu") (net 42))
  (segment (start 115.55186 104.075929) (end 115.538917 104.038941) (width 0.109) (layer "In6.Cu") (net 42))
  (segment (start 113.756275 105.595717) (end 113.780707 105.56508) (width 0.109) (layer "In6.Cu") (net 42))
  (segment (start 114.209689 106.742726) (end 114.240327 106.76716) (width 0.109) (layer "In6.Cu") (net 42))
  (segment (start 116.06 104.7) (end 116.064387 104.661058) (width 0.109) (layer "In6.Cu") (net 42))
  (segment (start 115.960471 100.8) (end 115.956083 100.761058) (width 0.109) (layer "In6.Cu") (net 42))
  (segment (start 115.124209 106.16612) (end 114.982787 106.024698) (width 0.109) (layer "In6.Cu") (net 42))
  (segment (start 115.195588 102.020611) (end 115.1586 102.007668) (width 0.109) (layer "In6.Cu") (net 42))
  (segment (start 115.6336 104.157669) (end 115.600419 104.13682) (width 0.109) (layer "In6.Cu") (net 42))
  (segment (start 116.07733 103.375929) (end 116.064387 103.338941) (width 0.109) (layer "In6.Cu") (net 42))
  (segment (start 107.185 106.225) (end 107.189387 106.186059) (width 0.109) (layer "In6.Cu") (net 42))
  (segment (start 114.240327 106.76716) (end 114.381748 106.908581) (width 0.109) (layer "In6.Cu") (net 42))
  (segment (start 113.064387 106.186059) (end 113.07733 106.149071) (width 0.109) (layer "In6.Cu") (net 42))
  (segment (start 115.76 100.624998) (end 115.721058 100.620611) (width 0.109) (layer "In6.Cu") (net 42))
  (segment (start 110.335 107.475) (end 110.339387 107.513941) (width 0.109) (layer "In6.Cu") (net 42))
  (segment (start 107.11911 107.61182) (end 107.14682 107.58411) (width 0.109) (layer "In6.Cu") (net 42))
  (segment (start 113.37182 106.11589) (end 113.392669 106.149071) (width 0.109) (layer "In6.Cu") (net 42))
  (segment (start 112.775889 107.61182) (end 112.80907 107.632669) (width 0.109) (layer "In6.Cu") (net 42))
  (segment (start 116.098179 104.590889) (end 116.125889 104.563179) (width 0.109) (layer "In6.Cu") (net 42))
  (segment (start 115.07686 101.225928) (end 115.063917 101.18894) (width 0.109) (layer "In6.Cu") (net 42))
  (segment (start 106.900889 107.61182) (end 106.93407 107.632669) (width 0.109) (layer "In6.Cu") (net 42))
  (segment (start 107.321058 106.054388) (end 107.36 106.05) (width 0.109) (layer "In6.Cu") (net 42))
  (segment (start 108.580612 107.513941) (end 108.585 107.475) (width 0.109) (layer "In6.Cu") (net 42))
  (segment (start 114.381748 106.908581) (end 114.412386 106.933014) (width 0.109) (layer "In6.Cu") (net 42))
  (segment (start 112.535 107.05) (end 112.573941 107.054387) (width 0.109) (layer "In6.Cu") (net 42))
  (segment (start 114.56329 106.950017) (end 114.598597 106.933014) (width 0.109) (layer "In6.Cu") (net 42))
  (segment (start 108.485929 107.632669) (end 108.51911 107.61182) (width 0.109) (layer "In6.Cu") (net 42))
  (segment (start 110.35233 107.550929) (end 110.373179 107.58411) (width 0.109) (layer "In6.Cu") (net 42))
  (segment (start 106.79682 107.115889) (end 106.817669 107.14907) (width 0.109) (layer "In6.Cu") (net 42))
  (segment (start 109.635 107.475) (end 109.639387 107.513941) (width 0.109) (layer "In6.Cu") (net 42))
  (segment (start 113.730551 105.708418) (end 113.730551 105.66923) (width 0.109) (layer "In6.Cu") (net 42))
  (segment (start 114.028195 105.56508) (end 114.876722 106.413608) (width 0.109) (layer "In6.Cu") (net 42))
  (segment (start 108.25233 107.550929) (end 108.273179 107.58411) (width 0.109) (layer "In6.Cu") (net 42))
  (segment (start 109.630612 106.186059) (end 109.635 106.225) (width 0.109) (layer "In6.Cu") (net 42))
  (segment (start 106.830612 107.186058) (end 106.835 107.225) (width 0.109) (layer "In6.Cu") (net 42))
  (segment (start 114.941351 105.843156) (end 114.958354 105.807849) (width 0.109) (layer "In6.Cu") (net 42))
  (segment (start 108.567669 107.550929) (end 108.580612 107.513941) (width 0.109) (layer "In6.Cu") (net 42))
  (segment (start 116.585471 103.65) (end 116.581083 103.611058) (width 0.109) (layer "In6.Cu") (net 42))
  (segment (start 113.196058 106.054388) (end 113.235 106.05) (width 0.109) (layer "In6.Cu") (net 42))
  (segment (start 109.071058 107.645612) (end 109.11 107.65) (width 0.109) (layer "In6.Cu") (net 42))
  (segment (start 115.125419 101.986819) (end 115.097709 101.959109) (width 0.109) (layer "In6.Cu") (net 42))
  (segment (start 115.721058 102.379387) (end 115.76 102.375) (width 0.109) (layer "In6.Cu") (net 42))
  (segment (start 112.99411 107.61182) (end 113.02182 107.58411) (width 0.109) (layer "In6.Cu") (net 42))
  (segment (start 113.41 106.225) (end 113.41 106.875) (width 0.109) (layer "In6.Cu") (net 42))
  (segment (start 115.07686 101.074069) (end 115.097709 101.040888) (width 0.109) (layer "In6.Cu") (net 42))
  (segment (start 107.189387 106.186059) (end 107.20233 106.149071) (width 0.109) (layer "In6.Cu") (net 42))
  (segment (start 110.685 107.475) (end 110.685 107.225) (width 0.109) (layer "In6.Cu") (net 42))
  (segment (start 108.16911 106.08818) (end 108.19682 106.11589) (width 0.109) (layer "In6.Cu") (net 42))
  (segment (start 113.06 106.225) (end 113.064387 106.186059) (width 0.109) (layer "In6.Cu") (net 42))
  (segment (start 109.967669 107.550929) (end 109.980612 107.513941) (width 0.109) (layer "In6.Cu") (net 42))
  (segment (start 110.08407 106.067331) (end 110.121058 106.054388) (width 0.109) (layer "In6.Cu") (net 42))
  (segment (start 107.49682 106.11589) (end 107.517669 106.149071) (width 0.109) (layer "In6.Cu") (net 42))
  (segment (start 107.535 107.475) (end 107.539387 107.513941) (width 0.109) (layer "In6.Cu") (net 42))
  (segment (start 115.670588 104.170612) (end 115.6336 104.157669) (width 0.109) (layer "In6.Cu") (net 42))
  (segment (start 116.09314 102.12407) (end 116.072291 102.090889) (width 0.109) (layer "In6.Cu") (net 42))
  (segment (start 115.234529 101.674998) (end 115.78547 101.675) (width 0.109) (layer "In6.Cu") (net 42))
  (segment (start 109.848941 107.645612) (end 109.885929 107.632669) (width 0.109) (layer "In6.Cu") (net 42))
  (segment (start 110.667669 107.550929) (end 110.680612 107.513941) (width 0.109) (layer "In6.Cu") (net 42))
  (segment (start 116.4864 103.807669) (end 116.519581 103.78682) (width 0.109) (layer "In6.Cu") (net 42))
  (segment (start 107.867669 107.550929) (end 107.880612 107.513941) (width 0.109) (layer "In6.Cu") (net 42))
  (segment (start 115.063917 101.811057) (end 115.07686 101.774069) (width 0.109) (layer "In6.Cu") (net 42))
  (segment (start 107.880612 107.513941) (end 107.885 107.475) (width 0.109) (layer "In6.Cu") (net 42))
  (segment (start 107.573179 107.58411) (end 107.600889 107.61182) (width 0.109) (layer "In6.Cu") (net 42))
  (segment (start 107.71 107.65) (end 107.748941 107.645612) (width 0.109) (layer "In6.Cu") (net 42))
  (segment (start 116.341657 98.938343) (end 117.279975 98.938343) (width 0.109) (layer "In6.Cu") (net 42))
  (segment (start 107.517669 106.149071) (end 107.530612 106.186059) (width 0.109) (layer "In6.Cu") (net 42))
  (segment (start 115.097709 101.259109) (end 115.07686 101.225928) (width 0.109) (layer "In6.Cu") (net 42))
  (segment (start 115.894581 100.93682) (end 115.922291 100.90911) (width 0.109) (layer "In6.Cu") (net 42))
  (segment (start 113.414387 106.913942) (end 113.42733 106.95093) (width 0.109) (layer "In6.Cu") (net 42))
  (segment (start 113.273941 106.054388) (end 113.310929 106.067331) (width 0.109) (layer "In6.Cu") (net 42))
  (segment (start 116.106083 102.161058) (end 116.09314 102.12407) (width 0.109) (layer "In6.Cu") (net 42))
  (segment (start 115.23453 101.324999) (end 115.785471 101.324999) (width 0.109) (layer "In6.Cu") (net 42))
  (segment (start 107.539387 107.513941) (end 107.55233 107.550929) (width 0.109) (layer "In6.Cu") (net 42))
  (segment (start 108.589387 106.186059) (end 108.60233 106.149071) (width 0.109) (layer "In6.Cu") (net 42))
  (segment (start 116.519581 103.78682) (end 116.547291 103.75911) (width 0.109) (layer "In6.Cu") (net 42))
  (segment (start 112.692669 107.14907) (end 112.705612 107.186058) (width 0.109) (layer "In6.Cu") (net 42))
  (segment (start 93.3125 109.8875) (end 93.3125 109.0375) (width 0.109) (layer "In6.Cu") (net 42))
  (segment (start 115.589387 100.48894) (end 115.585 100.449998) (width 0.109) (layer "In6.Cu") (net 42))
  (segment (start 115.894581 101.63682) (end 115.922291 101.60911) (width 0.109) (layer "In6.Cu") (net 42))
  (segment (start 114.67939 106.804431) (end 114.67939 106.765243) (width 0.109) (layer "In6.Cu") (net 42))
  (segment (start 112.705612 107.186058) (end 112.71 107.225) (width 0.109) (layer "In6.Cu") (net 42))
  (segment (start 115.824412 101.329387) (end 115.785471 101.324999) (width 0.109) (layer "In6.Cu") (net 42))
  (segment (start 109.56911 106.08818) (end 109.59682 106.11589) (width 0.109) (layer "In6.Cu") (net 42))
  (segment (start 109.91911 107.61182) (end 109.94682 107.58411) (width 0.109) (layer "In6.Cu") (net 42))
  (segment (start 114.136177 106.717004) (end 114.174382 106.725724) (width 0.109) (layer "In6.Cu") (net 42))
  (segment (start 115.670588 103.829387) (end 115.709529 103.825) (width 0.109) (layer "In6.Cu") (net 42))
  (segment (start 112.72733 107.550929) (end 112.748179 107.58411) (width 0.109) (layer "In6.Cu") (net 42))
  (segment (start 108.650889 106.08818) (end 108.68407 106.067331) (width 0.109) (layer "In6.Cu") (net 42))
  (segment (start 115.125419 101.713178) (end 115.1586 101.692329) (width 0.109) (layer "In6.Cu") (net 42))
  (segment (start 106.76911 107.088179) (end 106.79682 107.115889) (width 0.109) (layer "In6.Cu") (net 42))
  (segment (start 106.839387 107.513941) (end 106.85233 107.550929) (width 0.109) (layer "In6.Cu") (net 42))
  (segment (start 110.29682 106.11589) (end 110.317669 106.149071) (width 0.109) (layer "In6.Cu") (net 42))
  (segment (start 115.956083 101.461058) (end 115.94314 101.42407) (width 0.109) (layer "In6.Cu") (net 42))
  (segment (start 109.000889 107.61182) (end 109.03407 107.632669) (width 0.109) (layer "In6.Cu") (net 42))
  (segment (start 92.84 110.005) (end 93.195 110.005) (width 0.109) (layer "In6.Cu") (net 42))
  (segment (start 110.548941 107.645612) (end 110.585929 107.632669) (width 0.109) (layer "In6.Cu") (net 42))
  (segment (start 109.280612 107.513941) (end 109.285 107.475) (width 0.109) (layer "In6.Cu") (net 42))
  (segment (start 112.71 107.475) (end 112.714387 107.513941) (width 0.109) (layer "In6.Cu") (net 42))
  (segment (start 115.8614 101.657669) (end 115.894581 101.63682) (width 0.109) (layer "In6.Cu") (net 42))
  (segment (start 115.974412 102.029387) (end 115.935471 102.024999) (width 0.109) (layer "In6.Cu") (net 42))
  (segment (start 107.20233 106.149071) (end 107.223179 106.11589) (width 0.109) (layer "In6.Cu") (net 42))
  (segment (start 116.072291 102.090889) (end 116.044581 102.063179) (width 0.109) (layer "In6.Cu") (net 42))
  (segment (start 109.985 106.225) (end 109.989387 106.186059) (width 0.109) (layer "In6.Cu") (net 42))
  (segment (start 113.15907 106.067331) (end 113.196058 106.054388) (width 0.109) (layer "In6.Cu") (net 42))
  (segment (start 110.00233 106.149071) (end 110.023179 106.11589) (width 0.109) (layer "In6.Cu") (net 42))
  (segment (start 107.885 106.225) (end 107.889387 106.186059) (width 0.109) (layer "In6.Cu") (net 42))
  (segment (start 110.70233 107.14907) (end 110.723179 107.115889) (width 0.109) (layer "In6.Cu") (net 42))
  (segment (start 115.1586 101.307668) (end 115.125419 101.286819) (width 0.109) (layer "In6.Cu") (net 42))
  (segment (start 115.922291 101.390889) (end 115.894581 101.363179) (width 0.109) (layer "In6.Cu") (net 42))
  (segment (start 115.1586 102.007668) (end 115.125419 101.986819) (width 0.109) (layer "In6.Cu") (net 42))
  (segment (start 116.547291 103.75911) (end 116.56814 103.725929) (width 0.109) (layer "In6.Cu") (net 42))
  (segment (start 115.23453 102.024999) (end 115.935471 102.024999) (width 0.109) (layer "In6.Cu") (net 42))
  (segment (start 107.535 106.225) (end 107.535 107.475) (width 0.109) (layer "In6.Cu") (net 42))
  (segment (start 113.02182 107.58411) (end 113.042669 107.550929) (width 0.109) (layer "In6.Cu") (net 42))
  (segment (start 116.125889 103.43682) (end 116.098179 103.40911) (width 0.109) (layer "In6.Cu") (net 42))
  (segment (start 108.76 106.05) (end 108.798941 106.054388) (width 0.109) (layer "In6.Cu") (net 42))
  (segment (start 112.748179 107.58411) (end 112.775889 107.61182) (width 0.109) (layer "In6.Cu") (net 42))
  (segment (start 113.997558 105.540646) (end 114.028195 105.56508) (width 0.109) (layer "In6.Cu") (net 42))
  (segment (start 116.56814 103.57407) (end 116.547291 103.540889) (width 0.109) (layer "In6.Cu") (net 42))
  (segment (start 109.700889 107.61182) (end 109.73407 107.632669) (width 0.109) (layer "In6.Cu") (net 42))
  (segment (start 115.148642 106.382969) (end 115.165644 106.347663) (width 0.109) (layer "In6.Cu") (net 42))
  (segment (start 106.835 107.225) (end 106.835 107.475) (width 0.109) (layer "In6.Cu") (net 42))
  (segment (start 114.096989 106.717004) (end 114.136177 106.717004) (width 0.109) (layer "In6.Cu") (net 42))
  (segment (start 107.90233 106.149071) (end 107.923179 106.11589) (width 0.109) (layer "In6.Cu") (net 42))
  (segment (start 110.235929 106.067331) (end 110.26911 106.08818) (width 0.109) (layer "In6.Cu") (net 42))
  (segment (start 108.930612 106.186059) (end 108.935 106.225) (width 0.109) (layer "In6.Cu") (net 42))
  (segment (start 109.21911 107.61182) (end 109.24682 107.58411) (width 0.109) (layer "In6.Cu") (net 42))
  (segment (start 114.958354 105.807849) (end 114.982787 105.777211) (width 0.109) (layer "In6.Cu") (net 42))
  (segment (start 114.598597 106.933014) (end 114.629235 106.908581) (width 0.109) (layer "In6.Cu") (net 42))
  (segment (start 108.217669 106.149071) (end 108.230612 106.186059) (width 0.109) (layer "In6.Cu") (net 42))
  (segment (start 113.739272 105.746623) (end 113.730551 105.708418) (width 0.109) (layer "In6.Cu") (net 42))
  (segment (start 106.698941 107.054387) (end 106.735929 107.06733) (width 0.109) (layer "In6.Cu") (net 42))
  (segment (start 110.61911 107.61182) (end 110.64682 107.58411) (width 0.109) (layer "In6.Cu") (net 42))
  (segment (start 108.89682 106.11589) (end 108.917669 106.149071) (width 0.109) (layer "In6.Cu") (net 42))
  (segment (start 116.449412 104.520612) (end 116.4864 104.507669) (width 0.109) (layer "In6.Cu") (net 42))
  (segment (start 109.289387 106.186059) (end 109.30233 106.149071) (width 0.109) (layer "In6.Cu") (net 42))
  (segment (start 107.01 107.65) (end 107.048941 107.645612) (width 0.109) (layer "In6.Cu") (net 42))
  (segment (start 115.097709 101.959109) (end 115.07686 101.925928) (width 0.109) (layer "In6.Cu") (net 42))
  (segment (start 116.044581 102.063179) (end 116.0114 102.04233) (width 0.109) (layer "In6.Cu") (net 42))
  (segment (start 115.195588 101.679386) (end 115.234529 101.674998) (width 0.109) (layer "In6.Cu") (net 42))
  (segment (start 107.398941 106.054388) (end 107.435929 106.067331) (width 0.109) (layer "In6.Cu") (net 42))
  (segment (start 109.989387 106.186059) (end 110.00233 106.149071) (width 0.109) (layer "In6.Cu") (net 42))
  (segment (start 115.1586 100.992329) (end 115.195588 100.979386) (width 0.109) (layer "In6.Cu") (net 42))
  (segment (start 116.519581 103.513179) (end 116.4864 103.49233) (width 0.109) (layer "In6.Cu") (net 42))
  (segment (start 108.300889 107.61182) (end 108.33407 107.632669) (width 0.109) (layer "In6.Cu") (net 42))
  (segment (start 115.785471 100.624999) (end 115.76 100.624998) (width 0.109) (layer "In6.Cu") (net 42))
  (segment (start 116.56814 103.725929) (end 116.581083 103.688941) (width 0.109) (layer "In6.Cu") (net 42))
  (segment (start 116.4864 104.19233) (end 116.449412 104.179387) (width 0.109) (layer "In6.Cu") (net 42))
  (segment (start 116.06 103.3) (end 116.06 103.025) (width 0.109) (layer "In6.Cu") (net 42))
  (segment (start 115.922291 100.690889) (end 115.894581 100.663179) (width 0.109) (layer "In6.Cu") (net 42))
  (segment (start 109.498941 106.054388) (end 109.535929 106.067331) (width 0.109) (layer "In6.Cu") (net 42))
  (segment (start 109.46 106.05) (end 109.498941 106.054388) (width 0.109) (layer "In6.Cu") (net 42))
  (segment (start 108.917669 106.149071) (end 108.930612 106.186059) (width 0.109) (layer "In6.Cu") (net 42))
  (segment (start 115.174364 106.309458) (end 115.174364 106.27027) (width 0.109) (layer "In6.Cu") (net 42))
  (segment (start 114.653668 106.691731) (end 114.629235 106.661093) (width 0.109) (layer "In6.Cu") (net 42))
  (segment (start 115.059529 101.849999) (end 115.063917 101.811057) (width 0.109) (layer "In6.Cu") (net 42))
  (segment (start 107.55233 107.550929) (end 107.573179 107.58411) (width 0.109) (layer "In6.Cu") (net 42))
  (segment (start 115.063917 101.111057) (end 115.07686 101.074069) (width 0.109) (layer "In6.Cu") (net 42))
  (segment (start 108.273179 107.58411) (end 108.300889 107.61182) (width 0.109) (layer "In6.Cu") (net 42))
  (segment (start 115.824412 100.629387) (end 115.785471 100.624999) (width 0.109) (layer "In6.Cu") (net 42))
  (segment (start 113.884858 105.514924) (end 113.924046 105.514924) (width 0.109) (layer "In6.Cu") (net 42))
  (segment (start 116.044581 102.33682) (end 116.072291 102.30911) (width 0.109) (layer "In6.Cu") (net 42))
  (segment (start 115.922291 100.90911) (end 115.94314 100.875929) (width 0.109) (layer "In6.Cu") (net 42))
  (segment (start 114.629235 106.908581) (end 114.653668 106.877942) (width 0.109) (layer "In6.Cu") (net 42))
  (segment (start 116.0114 102.04233) (end 115.974412 102.029387) (width 0.109) (layer "In6.Cu") (net 42))
  (segment (start 107.84682 107.58411) (end 107.867669 107.550929) (width 0.109) (layer "In6.Cu") (net 42))
  (segment (start 108.230612 106.186059) (end 108.235 106.225) (width 0.109) (layer "In6.Cu") (net 42))
  (segment (start 115.059529 101.149999) (end 115.063917 101.111057) (width 0.109) (layer "In6.Cu") (net 42))
  (segment (start 115.94314 101.575929) (end 115.956083 101.538941) (width 0.109) (layer "In6.Cu") (net 42))
  (segment (start 113.055612 107.513941) (end 113.06 107.475) (width 0.109) (layer "In6.Cu") (net 42))
  (segment (start 113.756274 105.781929) (end 113.739272 105.746623) (width 0.109) (layer "In6.Cu") (net 42))
  (segment (start 108.973179 107.58411) (end 109.000889 107.61182) (width 0.109) (layer "In6.Cu") (net 42))
  (segment (start 106.66 107.05) (end 106.698941 107.054387) (width 0.109) (layer "In6.Cu") (net 42))
  (segment (start 115.23453 101.324999) (end 115.195588 101.320611) (width 0.109) (layer "In6.Cu") (net 42))
  (segment (start 108.935 107.475) (end 108.939387 107.513941) (width 0.109) (layer "In6.Cu") (net 42))
  (segment (start 106.835 107.475) (end 106.839387 107.513941) (width 0.109) (layer "In6.Cu") (net 42))
  (segment (start 114.958354 105.99406) (end 114.941351 105.958753) (width 0.109) (layer "In6.Cu") (net 42))
  (segment (start 108.86911 106.08818) (end 108.89682 106.11589) (width 0.109) (layer "In6.Cu") (net 42))
  (segment (start 114.942666 106.455043) (end 114.980871 106.463763) (width 0.109) (layer "In6.Cu") (net 42))
  (segment (start 115.94314 100.875929) (end 115.956083 100.838941) (width 0.109) (layer "In6.Cu") (net 42))
  (segment (start 110.121058 106.054388) (end 110.16 106.05) (width 0.109) (layer "In6.Cu") (net 42))
  (segment (start 112.67182 107.115889) (end 112.692669 107.14907) (width 0.109) (layer "In6.Cu") (net 42))
  (segment (start 108.939387 107.513941) (end 108.95233 107.550929) (width 0.109) (layer "In6.Cu") (net 42))
  (segment (start 116.4864 104.507669) (end 116.519581 104.48682) (width 0.109) (layer "In6.Cu") (net 42))
  (segment (start 115.650889 102.413179) (end 115.68407 102.39233) (width 0.109) (layer "In6.Cu") (net 42))
  (segment (start 109.148941 107.645612) (end 109.185929 107.632669) (width 0.109) (layer "In6.Cu") (net 42))
  (segment (start 115.76 102.375) (end 115.93547 102.375) (width 0.109) (layer "In6.Cu") (net 42))
  (segment (start 115.600419 103.863179) (end 115.6336 103.84233) (width 0.109) (layer "In6.Cu") (net 42))
  (segment (start 112.846058 107.645612) (end 112.885 107.65) (width 0.109) (layer "In6.Cu") (net 42))
  (segment (start 110.78407 107.06733) (end 110.821058 107.054387) (width 0.109) (layer "In6.Cu") (net 42))
  (segment (start 109.771058 107.645612) (end 109.81 107.65) (width 0.109) (layer "In6.Cu") (net 42))
  (segment (start 109.267669 107.550929) (end 109.280612 107.513941) (width 0.109) (layer "In6.Cu") (net 42))
  (segment (start 116.4864 103.49233) (end 116.449412 103.479387) (width 0.109) (layer "In6.Cu") (net 42))
  (segment (start 109.73407 107.632669) (end 109.771058 107.645612) (width 0.109) (layer "In6.Cu") (net 42))
  (segment (start 109.985 107.475) (end 109.985 106.225) (width 0.109) (layer "In6.Cu") (net 42))
  (segment (start 110.373179 107.58411) (end 110.400889 107.61182) (width 0.109) (layer "In6.Cu") (net 42))
  (segment (start 109.285 107.475) (end 109.285 106.225) (width 0.109) (layer "In6.Cu") (net 42))
  (segment (start 116.064387 103.338941) (end 116.06 103.3) (width 0.109) (layer "In6.Cu") (net 42))
  (segment (start 113.34411 106.08818) (end 113.37182 106.11589) (width 0.109) (layer "In6.Cu") (net 42))
  (segment (start 110.339387 107.513941) (end 110.35233 107.550929) (width 0.109) (layer "In6.Cu") (net 42))
  (segment (start 113.99284 106.76716) (end 114.023478 106.742726) (width 0.109) (layer "In6.Cu") (net 42))
  (segment (start 113.042669 107.550929) (end 113.055612 107.513941) (width 0.109) (layer "In6.Cu") (net 42))
  (segment (start 110.685 107.225) (end 110.689387 107.186058) (width 0.109) (layer "In6.Cu") (net 42))
  (segment (start 113.71 107.05) (end 113.99284 106.76716) (width 0.109) (layer "In6.Cu") (net 42))
  (segment (start 106.735929 107.06733) (end 106.76911 107.088179) (width 0.109) (layer "In6.Cu") (net 42))
  (segment (start 108.51911 107.61182) (end 108.54682 107.58411) (width 0.109) (layer "In6.Cu") (net 42))
  (segment (start 115.721058 100.620611) (end 115.68407 100.607668) (width 0.109) (layer "In6.Cu") (net 42))
  (segment (start 113.739272 105.631025) (end 113.756275 105.595717) (width 0.109) (layer "In6.Cu") (net 42))
  (segment (start 115.600419 104.13682) (end 115.572709 104.10911) (width 0.109) (layer "In6.Cu") (net 42))
  (segment (start 106.873179 107.58411) (end 106.900889 107.61182) (width 0.109) (layer "In6.Cu") (net 42))
  (segment (start 108.835929 106.067331) (end 108.86911 106.08818) (width 0.109) (layer "In6.Cu") (net 42))
  (segment (start 109.350889 106.08818) (end 109.38407 106.067331) (width 0.109) (layer "In6.Cu") (net 42))
  (segment (start 109.535929 106.067331) (end 109.56911 106.08818) (width 0.109) (layer "In6.Cu") (net 42))
  (segment (start 107.28407 106.067331) (end 107.321058 106.054388) (width 0.109) (layer "In6.Cu") (net 42))
  (segment (start 109.635 106.225) (end 109.635 107.475) (width 0.109) (layer "In6.Cu") (net 42))
  (segment (start 107.180612 107.513941) (end 107.185 107.475) (width 0.109) (layer "In6.Cu") (net 42))
  (segment (start 108.798941 106.054388) (end 108.835929 106.067331) (width 0.109) (layer "In6.Cu") (net 42))
  (segment (start 108.021058 106.054388) (end 108.06 106.05) (width 0.109) (layer "In6.Cu") (net 42))
  (segment (start 115.093571 106.438041) (end 115.124209 106.413608) (width 0.109) (layer "In6.Cu") (net 42))
  (segment (start 107.63407 107.632669) (end 107.671058 107.645612) (width 0.109) (layer "In6.Cu") (net 42))
  (segment (start 115.538917 104.038941) (end 115.534529 104) (width 0.109) (layer "In6.Cu") (net 42))
  (segment (start 114.485898 106.958737) (end 114.525085 106.958737) (width 0.109) (layer "In6.Cu") (net 42))
  (segment (start 116.56814 104.425929) (end 116.581083 104.388941) (width 0.109) (layer "In6.Cu") (net 42))
  (segment (start 108.585 106.225) (end 108.589387 106.186059) (width 0.109) (layer "In6.Cu") (net 42))
  (segment (start 116.581083 104.311058) (end 116.56814 104.27407) (width 0.109) (layer "In6.Cu") (net 42))
  (segment (start 113.546058 107.045613) (end 113.585 107.05) (width 0.109) (layer "In6.Cu") (net 42))
  (segment (start 113.42733 106.95093) (end 113.448179 106.984111) (width 0.109) (layer "In6.Cu") (net 42))
  (segment (start 115.960471 101.5) (end 115.956083 101.461058) (width 0.109) (layer "In6.Cu") (net 42))
  (segment (start 115.585001 99.694999) (end 116.341657 98.938343) (width 0.109) (layer "In6.Cu") (net 42))
  (segment (start 116.410471 103.475) (end 116.235 103.475) (width 0.109) (layer "In6.Cu") (net 42))
  (segment (start 115.824412 100.970612) (end 115.8614 100.957669) (width 0.109) (layer "In6.Cu") (net 42))
  (segment (start 107.748941 107.645612) (end 107.785929 107.632669) (width 0.109) (layer "In6.Cu") (net 42))
  (segment (start 110.330612 106.186059) (end 110.335 106.225) (width 0.109) (layer "In6.Cu") (net 42))
  (segment (start 110.750889 107.088179) (end 110.78407 107.06733) (width 0.109) (layer "In6.Cu") (net 42))
  (segment (start 108.60233 106.149071) (end 108.623179 106.11589) (width 0.109) (layer "In6.Cu") (net 42))
  (segment (start 110.335 106.225) (end 110.335 107.475) (width 0.109) (layer "In6.Cu") (net 42))
  (segment (start 108.95233 107.550929) (end 108.973179 107.58411) (width 0.109) (layer "In6.Cu") (net 42))
  (segment (start 108.585 107.475) (end 108.585 106.225) (width 0.109) (layer "In6.Cu") (net 42))
  (segment (start 115.956083 100.761058) (end 115.94314 100.72407) (width 0.109) (layer "In6.Cu") (net 42))
  (segment (start 116.06 103.025) (end 115.585 102.55) (width 0.109) (layer "In6.Cu") (net 42))
  (segment (start 116.072291 102.30911) (end 116.09314 102.275929) (width 0.109) (layer "In6.Cu") (net 42))
  (segment (start 116.56814 104.27407) (end 116.547291 104.240889) (width 0.109) (layer "In6.Cu") (net 42))
  (segment (start 115.78547 101.675) (end 115.824412 101.670612) (width 0.109) (layer "In6.Cu") (net 42))
  (segment (start 113.50907 107.03267) (end 113.546058 107.045613) (width 0.109) (layer "In6.Cu") (net 42))
  (segment (start 113.41 106.875) (end 113.414387 106.913942) (width 0.109) (layer "In6.Cu") (net 42))
  (segment (start 109.185929 107.632669) (end 109.21911 107.61182) (width 0.109) (layer "In6.Cu") (net 42))
  (segment (start 115.78547 100.975) (end 115.824412 100.970612) (width 0.109) (layer "In6.Cu") (net 42))
  (segment (start 113.924046 105.514924) (end 113.96225 105.523645) (width 0.109) (layer "In6.Cu") (net 42))
  (segment (start 115.058264 106.455043) (end 115.093571 106.438041) (width 0.109) (layer "In6.Cu") (net 42))
  (segment (start 110.689387 107.186058) (end 110.70233 107.14907) (width 0.109) (layer "In6.Cu") (net 42))
  (segment (start 116.547291 103.540889) (end 116.519581 103.513179) (width 0.109) (layer "In6.Cu") (net 42))
  (segment (start 93.584581 108.765419) (end 93.790419 108.765419) (width 0.109) (layer "In6.Cu") (net 42))
  (segment (start 113.392669 106.149071) (end 113.405612 106.186059) (width 0.109) (layer "In6.Cu") (net 42))
  (segment (start 116.196058 103.470612) (end 116.15907 103.457669) (width 0.109) (layer "In6.Cu") (net 42))
  (segment (start 107.889387 106.186059) (end 107.90233 106.149071) (width 0.109) (layer "In6.Cu") (net 42))
  (segment (start 115.165644 106.232065) (end 115.148642 106.196758) (width 0.109) (layer "In6.Cu") (net 42))
  (segment (start 107.81911 107.61182) (end 107.84682 107.58411) (width 0.109) (layer "In6.Cu") (net 42))
  (segment (start 116.410471 104.175) (end 115.709529 104.175) (width 0.109) (layer "In6.Cu") (net 42))
  (segment (start 109.65233 107.550929) (end 109.673179 107.58411) (width 0.109) (layer "In6.Cu") (net 42))
  (segment (start 110.723179 107.115889) (end 110.750889 107.088179) (width 0.109) (layer "In6.Cu") (net 42))
  (segment (start 116.09314 102.275929) (end 116.106083 102.238941) (width 0.109) (layer "In6.Cu") (net 42))
  (segment (start 113.96225 105.523645) (end 113.997558 105.540646) (width 0.109) (layer "In6.Cu") (net 42))
  (segment (start 109.285 106.225) (end 109.289387 106.186059) (width 0.109) (layer "In6.Cu") (net 42))
  (segment (start 108.06 106.05) (end 108.098941 106.054388) (width 0.109) (layer "In6.Cu") (net 42))
  (segment (start 112.80907 107.632669) (end 112.846058 107.645612) (width 0.109) (layer "In6.Cu") (net 42))
  (segment (start 110.26911 106.08818) (end 110.29682 106.11589) (width 0.109) (layer "In6.Cu") (net 42))
  (segment (start 108.235 107.475) (end 108.239387 107.513941) (width 0.109) (layer "In6.Cu") (net 42))
  (segment (start 116.581083 103.611058) (end 116.56814 103.57407) (width 0.109) (layer "In6.Cu") (net 42))
  (segment (start 107.785929 107.632669) (end 107.81911 107.61182) (width 0.109) (layer "In6.Cu") (net 42))
  (segment (start 115.534529 104) (end 115.538917 103.961058) (width 0.109) (layer "In6.Cu") (net 42))
  (segment (start 115.974412 102.370612) (end 116.0114 102.357669) (width 0.109) (layer "In6.Cu") (net 42))
  (segment (start 113.780708 105.812566) (end 113.756274 105.781929) (width 0.109) (layer "In6.Cu") (net 42))
  (segment (start 113.07733 106.149071) (end 113.098179 106.11589) (width 0.109) (layer "In6.Cu") (net 42))
  (segment (start 107.98407 106.067331) (end 108.021058 106.054388) (width 0.109) (layer "In6.Cu") (net 42))
  (segment (start 112.714387 107.513941) (end 112.72733 107.550929) (width 0.109) (layer "In6.Cu") (net 42))
  (segment (start 107.600889 107.61182) (end 107.63407 107.632669) (width 0.109) (layer "In6.Cu") (net 42))
  (segment (start 108.54682 107.58411) (end 108.567669 107.550929) (width 0.109) (layer "In6.Cu") (net 42))
  (segment (start 115.824412 101.670612) (end 115.8614 101.657669) (width 0.109) (layer "In6.Cu") (net 42))
  (segment (start 116.410471 104.525) (end 116.449412 104.520612) (width 0.109) (layer "In6.Cu") (net 42))
  (segment (start 107.223179 106.11589) (end 107.250889 106.08818) (width 0.109) (layer "In6.Cu") (net 42))
  (segment (start 116.064387 104.661058) (end 116.07733 104.62407) (width 0.109) (layer "In6.Cu") (net 42))
  (segment (start 116.519581 104.213179) (end 116.4864 104.19233) (width 0.109) (layer "In6.Cu") (net 42))
  (segment (start 113.811346 105.540647) (end 113.846652 105.523645) (width 0.109) (layer "In6.Cu") (net 42))
  (segment (start 109.30233 106.149071) (end 109.323179 106.11589) (width 0.109) (layer "In6.Cu") (net 42))
  (segment (start 113.475889 107.011821) (end 113.50907 107.03267) (width 0.109) (layer "In6.Cu") (net 42))
  (segment (start 115.125419 101.013178) (end 115.1586 100.992329) (width 0.109) (layer "In6.Cu") (net 42))
  (segment (start 93.3125 109.0375) (end 93.584581 108.765419) (width 0.109) (layer "In6.Cu") (net 42))
  (segment (start 112.71 107.225) (end 112.71 107.475) (width 0.109) (layer "In6.Cu") (net 42))
  (segment (start 115.572709 104.10911) (end 115.55186 104.075929) (width 0.109) (layer "In6.Cu") (net 42))
  (segment (start 116.449412 103.820612) (end 116.4864 103.807669) (width 0.109) (layer "In6.Cu") (net 42))
  (segment (start 108.623179 106.11589) (end 108.650889 106.08818) (width 0.109) (layer "In6.Cu") (net 42))
  (segment (start 115.956083 101.538941) (end 115.960471 101.5) (width 0.109) (layer "In6.Cu") (net 42))
  (segment (start 115.165644 106.347663) (end 115.174364 106.309458) (width 0.109) (layer "In6.Cu") (net 42))
  (segment (start 110.64682 107.58411) (end 110.667669 107.550929) (width 0.109) (layer "In6.Cu") (net 42))
  (segment (start 116.15907 104.54233) (end 116.196058 104.529387) (width 0.109) (layer "In6.Cu") (net 42))
  (segment (start 107.250889 106.08818) (end 107.28407 106.067331) (width 0.109) (layer "In6.Cu") (net 42))
  (segment (start 116.0114 102.357669) (end 116.044581 102.33682) (width 0.109) (layer "In6.Cu") (net 42))
  (segment (start 115.1586 101.692329) (end 115.195588 101.679386) (width 0.109) (layer "In6.Cu") (net 42))
  (segment (start 114.412386 106.933014) (end 114.447693 106.950017) (width 0.109) (layer "In6.Cu") (net 42))
  (segment (start 109.94682 107.58411) (end 109.967669 107.550929) (width 0.109) (layer "In6.Cu") (net 42))
  (segment (start 113.730551 105.66923) (end 113.739272 105.631025) (width 0.109) (layer "In6.Cu") (net 42))
  (segment (start 115.623179 102.440889) (end 115.650889 102.413179) (width 0.109) (layer "In6.Cu") (net 42))
  (segment (start 115.894581 101.363179) (end 115.8614 101.34233) (width 0.109) (layer "In6.Cu") (net 42))
  (segment (start 108.19682 106.11589) (end 108.217669 106.149071) (width 0.109) (layer "In6.Cu") (net 42))
  (segment (start 109.421058 106.054388) (end 109.46 106.05) (width 0.109) (layer "In6.Cu") (net 42))
  (segment (start 115.020059 106.463763) (end 115.058264 106.455043) (width 0.109) (layer "In6.Cu") (net 42))
  (segment (start 115.07686 101.925928) (end 115.063917 101.88894) (width 0.109) (layer "In6.Cu") (net 42))
  (segment (start 116.07733 104.62407) (end 116.098179 104.590889) (width 0.109) (layer "In6.Cu") (net 42))
  (segment (start 115.956083 100.838941) (end 115.960471 100.8) (width 0.109) (layer "In6.Cu") (net 42))
  (segment (start 116.125889 104.563179) (end 116.15907 104.54233) (width 0.109) (layer "In6.Cu") (net 42))
  (segment (start 110.198941 106.054388) (end 110.235929 106.067331) (width 0.109) (layer "In6.Cu") (net 42))
  (segment (start 107.530612 106.186059) (end 107.535 106.225) (width 0.109) (layer "In6.Cu") (net 42))
  (segment (start 109.81 107.65) (end 109.848941 107.645612) (width 0.109) (layer "In6.Cu") (net 42))
  (segment (start 110.43407 107.632669) (end 110.471058 107.645612) (width 0.109) (layer "In6.Cu") (net 42))
  (segment (start 116.235 104.525) (end 116.410471 104.525) (width 0.109) (layer "In6.Cu") (net 42))
  (segment (start 115.8614 100.64233) (end 115.824412 100.629387) (width 0.109) (layer "In6.Cu") (net 42))
  (segment (start 113.310929 106.067331) (end 113.34411 106.08818) (width 0.109) (layer "In6.Cu") (net 42))
  (segment (start 115.6336 103.84233) (end 115.670588 103.829387) (width 0.109) (layer "In6.Cu") (net 42))
  (segment (start 115.124209 106.413608) (end 115.148642 106.382969) (width 0.109) (layer "In6.Cu") (net 42))
  (segment (start 110.680612 107.513941) (end 110.685 107.475) (width 0.109) (layer "In6.Cu") (net 42))
  (segment (start 113.585 107.05) (end 113.71 107.05) (width 0.109) (layer "In6.Cu") (net 42))
  (segment (start 115.60233 102.47407) (end 115.623179 102.440889) (width 0.109) (layer "In6.Cu") (net 42))
  (segment (start 110.471058 107.645612) (end 110.51 107.65) (width 0.109) (layer "In6.Cu") (net 42))
  (segment (start 115.894581 100.663179) (end 115.8614 100.64233) (width 0.109) (layer "In6.Cu") (net 42))
  (segment (start 114.90736 106.438041) (end 114.942666 106.455043) (width 0.109) (layer "In6.Cu") (net 42))
  (segment (start 114.941351 105.958753) (end 114.932631 105.920548) (width 0.109) (layer "In6.Cu") (net 42))
  (segment (start 108.721058 106.054388) (end 108.76 106.05) (width 0.109) (layer "In6.Cu") (net 42))
  (segment (start 114.982787 106.024698) (end 114.958354 105.99406) (width 0.109) (layer "In6.Cu") (net 42))
  (segment (start 115.195588 101.320611) (end 115.1586 101.307668) (width 0.109) (layer "In6.Cu") (net 42))
  (segment (start 115.097709 101.040888) (end 115.125419 101.013178) (width 0.109) (layer "In6.Cu") (net 42))
  (segment (start 107.885 107.475) (end 107.885 106.225) (width 0.109) (layer "In6.Cu") (net 42))
  (segment (start 107.923179 106.11589) (end 107.950889 106.08818) (width 0.109) (layer "In6.Cu") (net 42))
  (segment (start 116.106083 102.238941) (end 116.110471 102.2) (width 0.109) (layer "In6.Cu") (net 42))
  (segment (start 107.46911 106.08818) (end 107.49682 106.11589) (width 0.109) (layer "In6.Cu") (net 42))
  (segment (start 114.67067 106.842636) (end 114.67939 106.804431) (width 0.109) (layer "In6.Cu") (net 42))
  (segment (start 112.885 107.65) (end 112.923941 107.645612) (width 0.109) (layer "In6.Cu") (net 42))
  (segment (start 109.617669 106.149071) (end 109.630612 106.186059) (width 0.109) (layer "In6.Cu") (net 42))
  (segment (start 109.673179 107.58411) (end 109.700889 107.61182) (width 0.109) (layer "In6.Cu") (net 42))
  (segment (start 114.980871 106.463763) (end 115.020059 106.463763) (width 0.109) (layer "In6.Cu") (net 42))
  (segment (start 116.098179 103.40911) (end 116.07733 103.375929) (width 0.109) (layer "In6.Cu") (net 42))
  (segment (start 108.235 106.225) (end 108.235 107.475) (width 0.109) (layer "In6.Cu") (net 42))
  (segment (start 113.780707 105.56508) (end 113.811346 105.540647) (width 0.109) (layer "In6.Cu") (net 42))
  (segment (start 114.023478 106.742726) (end 114.058784 106.725724) (width 0.109) (layer "In6.Cu") (net 42))
  (segment (start 108.135929 106.067331) (end 108.16911 106.08818) (width 0.109) (layer "In6.Cu") (net 42))
  (segment (start 115.709529 104.175) (end 115.670588 104.170612) (width 0.109) (layer "In6.Cu") (net 42))
  (segment (start 109.885929 107.632669) (end 109.91911 107.61182) (width 0.109) (layer "In6.Cu") (net 42))
  (segment (start 122.522033 101.484976) (end 122.487524 101.463293) (width 0.182) (layer "F.Cu") (net 43))
  (segment (start 122.678561 101.503) (end 122.601 101.503) (width 0.182) (layer "F.Cu") (net 43))
  (segment (start 122.522033 101.885023) (end 122.560501 101.871563) (width 0.182) (layer "F.Cu") (net 43))
  (segment (start 122.719059 101.862436) (end 122.757527 101.848976) (width 0.182) (layer "F.Cu") (net 43))
  (segment (start 122.560501 101.498436) (end 122.522033 101.484976) (width 0.182) (layer "F.Cu") (net 43))
  (segment (start 122.419 102.22229) (end 122.419 102.049) (width 0.182) (layer "F.Cu") (net 43))
  (segment (start 122.855997 101.644501) (end 122.842537 101.606033) (width 0.182) (layer "F.Cu") (net 43))
  (segment (start 122.860561 101.685) (end 122.855997 101.644501) (width 0.182) (layer "F.Cu") (net 43))
  (segment (start 122.601 101.867) (end 122.678561 101.867) (width 0.182) (layer "F.Cu") (net 43))
  (segment (start 122.419 100.819866) (end 122.419 100.6951) (width 0.182) (layer "F.Cu") (net 43))
  (segment (start 122.757527 101.521023) (end 122.719059 101.507563) (width 0.182) (layer "F.Cu") (net 43))
  (segment (start 122.842537 101.606033) (end 122.820854 101.571524) (width 0.182) (layer "F.Cu") (net 43))
  (segment (start 122.855997 101.725498) (end 122.860561 101.685) (width 0.182) (layer "F.Cu") (net 43))
  (segment (start 122.820854 101.798475) (end 122.842537 101.763966) (width 0.182) (layer "F.Cu") (net 43))
  (segment (start 122.437023 101.970033) (end 122.458706 101.935524) (width 0.182) (layer "F.Cu") (net 43))
  (segment (start 122.820854 101.571524) (end 122.792036 101.542706) (width 0.182) (layer "F.Cu") (net 43))
  (segment (start 122.792036 101.827293) (end 122.820854 101.798475) (width 0.182) (layer "F.Cu") (net 43))
  (segment (start 122.423563 102.008501) (end 122.437023 101.970033) (width 0.182) (layer "F.Cu") (net 43))
  (segment (start 122.733355 102.536645) (end 122.419 102.22229) (width 0.182) (layer "F.Cu") (net 43))
  (segment (start 122.757527 101.848976) (end 122.792036 101.827293) (width 0.182) (layer "F.Cu") (net 43))
  (segment (start 122.719059 101.507563) (end 122.678561 101.503) (width 0.182) (layer "F.Cu") (net 43))
  (segment (start 90.320704 113.195704) (end 90.7865 112.859) (width 0.182) (layer "F.Cu") (net 43))
  (segment (start 122.419 101.321) (end 122.419 100.819866) (width 0.182) (layer "F.Cu") (net 43))
  (segment (start 122.423563 101.361498) (end 122.419 101.321) (width 0.182) (layer "F.Cu") (net 43))
  (segment (start 122.678561 101.867) (end 122.719059 101.862436) (width 0.182) (layer "F.Cu") (net 43))
  (segment (start 122.792036 101.542706) (end 122.757527 101.521023) (width 0.182) (layer "F.Cu") (net 43))
  (segment (start 122.601 101.503) (end 122.560501 101.498436) (width 0.182) (layer "F.Cu") (net 43))
  (segment (start 122.437023 101.399966) (end 122.423563 101.361498) (width 0.182) (layer "F.Cu") (net 43))
  (segment (start 122.560501 101.871563) (end 122.601 101.867) (width 0.182) (layer "F.Cu") (net 43))
  (segment (start 122.419 102.049) (end 122.423563 102.008501) (width 0.182) (layer "F.Cu") (net 43))
  (segment (start 122.458706 101.935524) (end 122.487524 101.906706) (width 0.182) (layer "F.Cu") (net 43))
  (segment (start 122.487524 101.906706) (end 122.522033 101.885023) (width 0.182) (layer "F.Cu") (net 43))
  (segment (start 122.842537 101.763966) (end 122.855997 101.725498) (width 0.182) (layer "F.Cu") (net 43))
  (segment (start 122.487524 101.463293) (end 122.458706 101.434475) (width 0.182) (layer "F.Cu") (net 43))
  (segment (start 122.458706 101.434475) (end 122.437023 101.399966) (width 0.182) (layer "F.Cu") (net 43))
  (via (at 90.320704 113.195704) (size 0.45) (drill 0.1) (layers "F.Cu" "B.Cu") (net 43))
  (via (at 122.733355 102.536645) (size 0.45) (drill 0.1) (layers "F.Cu" "B.Cu") (net 43))
  (segment (start 125.21 107.45) (end 126.7 105.96) (width 0.109) (layer "In6.Cu") (net 43))
  (segment (start 123.31 99.39) (end 122.733355 99.966645) (width 0.109) (layer "In6.Cu") (net 43))
  (segment (start 101.8 116.3) (end 119 116.3) (width 0.109) (layer "In6.Cu") (net 43))
  (segment (start 124.13 107.88) (end 124.56 107.45) (width 0.109) (layer "In6.Cu") (net 43))
  (segment (start 125.97 99.39) (end 123.31 99.39) (width 0.109) (layer "In6.Cu") (net 43))
  (segment (start 88.669 113.152) (end 88.669 114.198) (width 0.109) (layer "In6.Cu") (net 43))
  (segment (start 119 116.3) (end 124.13 111.17) (width 0.109) (layer "In6.Cu") (net 43))
  (segment (start 89.9 112.775) (end 89.046 112.775) (width 0.109) (layer "In6.Cu") (net 43))
  (segment (start 124.56 107.45) (end 125.21 107.45) (width 0.109) (layer "In6.Cu") (net 43))
  (segment (start 122.733355 99.966645) (end 122.733355 102.536645) (width 0.109) (layer "In6.Cu") (net 43))
  (segment (start 126.7 105.96) (end 126.7 100.12) (width 0.109) (layer "In6.Cu") (net 43))
  (segment (start 89.146 114.675) (end 93.975 114.675) (width 0.109) (layer "In6.Cu") (net 43))
  (segment (start 88.669 114.198) (end 89.146 114.675) (width 0.109) (layer "In6.Cu") (net 43))
  (segment (start 124.13 111.17) (end 124.13 107.88) (width 0.109) (layer "In6.Cu") (net 43))
  (segment (start 90.320704 113.195704) (end 89.9 112.775) (width 0.109) (layer "In6.Cu") (net 43))
  (segment (start 89.046 112.775) (end 88.669 113.152) (width 0.109) (layer "In6.Cu") (net 43))
  (segment (start 100.6 115.1) (end 101.8 116.3) (width 0.109) (layer "In6.Cu") (net 43))
  (segment (start 126.7 100.12) (end 125.97 99.39) (width 0.109) (layer "In6.Cu") (net 43))
  (segment (start 93.975 114.675) (end 94.4 115.1) (width 0.109) (layer "In6.Cu") (net 43))
  (segment (start 94.4 115.1) (end 100.6 115.1) (width 0.109) (layer "In6.Cu") (net 43))
  (segment (start 121.917851 103.219453) (end 121.917851 100.701951) (width 0.182) (layer "F.Cu") (net 44))
  (segment (start 90.7865 112.224) (end 91.1715 111.914) (width 0.182) (layer "F.Cu") (net 44))
  (via (at 121.917851 103.219453) (size 0.45) (drill 0.1) (layers "F.Cu" "B.Cu") (net 44))
  (via (at 91.1715 111.914) (size 0.45) (drill 0.1) (layers "F.Cu" "B.Cu") (net 44))
  (segment (start 111.223941 112.154387) (end 111.260929 112.16733) (width 0.109) (layer "In6.Cu") (net 44))
  (segment (start 118.691556 110.52532) (end 118.717817 110.546262) (width 0.109) (layer "In6.Cu") (net 44))
  (segment (start 118.522415 110.860311) (end 118.522415 110.826722) (width 0.109) (layer "In6.Cu") (net 44))
  (segment (start 116.999023 110.954101) (end 116.97808 110.927841) (width 0.109) (layer "In6.Cu") (net 44))
  (segment (start 118.059681 109.893444) (end 118.691556 110.52532) (width 0.109) (layer "In6.Cu") (net 44))
  (segment (start 117.242152 112.165847) (end 117.249626 112.1331) (width 0.109) (layer "In6.Cu") (net 44))
  (segment (start 118.500367 110.763712) (end 118.479425 110.73745) (width 0.109) (layer "In6.Cu") (net 44))
  (segment (start 119.120338 108.620654) (end 119.1466 108.599712) (width 0.109) (layer "In6.Cu") (net 44))
  (segment (start 117.804559 109.982715) (end 117.812033 109.949967) (width 0.109) (layer "In6.Cu") (net 44))
  (segment (start 116.963507 110.798493) (end 116.978081 110.768231) (width 0.109) (layer "In6.Cu") (net 44))
  (segment (start 114.79411 111.68818) (end 114.82182 111.71589) (width 0.109) (layer "In6.Cu") (net 44))
  (segment (start 117.546146 110.274717) (end 117.578894 110.28219) (width 0.109) (layer "In6.Cu") (net 44))
  (segment (start 117.423286 110.317706) (end 117.449548 110.296764) (width 0.109) (layer "In6.Cu") (net 44))
  (segment (start 92.740988 112.340988) (end 95.909012 112.340988) (width 0.109) (layer "In6.Cu") (net 44))
  (segment (start 95.909012 112.340988) (end 96.1 112.15) (width 0.109) (layer "In6.Cu") (net 44))
  (segment (start 117.651841 111.612238) (end 117.630899 111.585976) (width 0.109) (layer "In6.Cu") (net 44))
  (segment (start 113.848179 111.71589) (end 113.875889 111.68818) (width 0.109) (layer "In6.Cu") (net 44))
  (segment (start 111.610929 112.632669) (end 111.64411 112.61182) (width 0.109) (layer "In6.Cu") (net 44))
  (segment (start 116.664032 111.123242) (end 116.69762 111.123243) (width 0.109) (layer "In6.Cu") (net 44))
  (segment (start 112.02182 111.71589) (end 112.042669 111.749071) (width 0.109) (layer "In6.Cu") (net 44))
  (segment (start 119.120338 108.832786) (end 119.099395 108.806526) (width 0.109) (layer "In6.Cu") (net 44))
  (segment (start 112.935 112.65) (end 112.973941 112.645612) (width 0.109) (layer "In6.Cu") (net 44))
  (segment (start 119.077347 108.743516) (end 119.077348 108.709926) (width 0.109) (layer "In6.Cu") (net 44))
  (segment (start 112.235 112.65) (end 112.273941 112.645612) (width 0.109) (layer "In6.Cu") (net 44))
  (segment (start 114.17733 112.550929) (end 114.198179 112.58411) (width 0.109) (layer "In6.Cu") (net 44))
  (segment (start 114.373941 112.645612) (end 114.410929 112.632669) (width 0.109) (layer "In6.Cu") (net 44))
  (segment (start 117.227578 112.19611) (end 117.242152 112.165847) (width 0.109) (layer "In6.Cu") (net 44))
  (segment (start 111.398179 112.58411) (end 111.425889 112.61182) (width 0.109) (layer "In6.Cu") (net 44))
  (segment (start 119.14208 110.121999) (end 119.172343 110.136573) (width 0.109) (layer "In6.Cu") (net 44))
  (segment (start 119.665203 108.873518) (end 119.697951 108.866043) (width 0.109) (layer "In6.Cu") (net 44))
  (segment (start 119.78773 109.521186) (end 119.773156 109.490923) (width 0.109) (layer "In6.Cu") (net 44))
  (segment (start 111.64411 112.61182) (end 111.67182 112.58411) (width 0.109) (layer "In6.Cu") (net 44))
  (segment (start 113.46 112.475) (end 113.464387 112.513941) (width 0.109) (layer "In6.Cu") (net 44))
  (segment (start 119.725952 109.697736) (end 119.752214 109.676794) (width 0.109) (layer "In6.Cu") (net 44))
  (segment (start 119.084822 108.677178) (end 119.099396 108.646916) (width 0.109) (layer "In6.Cu") (net 44))
  (segment (start 111.960929 111.667331) (end 111.99411 111.68818) (width 0.109) (layer "In6.Cu") (net 44))
  (segment (start 92.4 112) (end 92.740988 112.340988) (width 0.109) (layer "In6.Cu") (net 44))
  (segment (start 117.932301 111.416836) (end 117.96589 111.416836) (width 0.109) (layer "In6.Cu") (net 44))
  (segment (start 112.72182 111.71589) (end 112.742669 111.749071) (width 0.109) (layer "In6.Cu") (net 44))
  (segment (start 116.963507 110.897577) (end 116.956032 110.864831) (width 0.109) (layer "In6.Cu") (net 44))
  (segment (start 117.184893 110.721028) (end 117.211155 110.74197) (width 0.109) (layer "In6.Cu") (net 44))
  (segment (start 116.786892 111.166233) (end 117.418767 111.798109) (width 0.109) (layer "In6.Cu") (net 44))
  (segment (start 114.548179 111.71589) (end 114.575889 111.68818) (width 0.109) (layer "In6.Cu") (net 44))
  (segment (start 117.651841 111.771847) (end 117.666415 111.741584) (width 0.109) (layer "In6.Cu") (net 44))
  (segment (start 118.939204 110.369712) (end 118.92463 110.339449) (width 0.109) (layer "In6.Cu") (net 44))
  (segment (start 118.785347 109.001927) (end 118.818935 109.001928) (width 0.109) (layer "In6.Cu") (net 44))
  (segment (start 112.896058 112.645612) (end 112.935 112.65) (width 0.109) (layer "In6.Cu") (net 44))
  (segment (start 119.540082 109.676794) (end 119.566343 109.697736) (width 0.109) (layer "In6.Cu") (net 44))
  (segment (start 119.084822 108.776262) (end 119.077347 108.743516) (width 0.109) (layer "In6.Cu") (net 44))
  (segment (start 116.994504 112.222372) (end 117.020765 112.243314) (width 0.109) (layer "In6.Cu") (net 44))
  (segment (start 113.442669 111.749071) (end 113.455612 111.786059) (width 0.109) (layer "In6.Cu") (net 44))
  (segment (start 118.851683 109.009401) (end 118.881945 109.023976) (width 0.109) (layer "In6.Cu") (net 44))
  (segment (start 118.74808 110.560836) (end 118.780827 110.56831) (width 0.109) (layer "In6.Cu") (net 44))
  (segment (start 116.601022 111.14529) (end 116.631284 111.130717) (width 0.109) (layer "In6.Cu") (net 44))
  (segment (start 117.96589 111.416836) (end 117.998638 111.409362) (width 0.109) (layer "In6.Cu") (net 44))
  (segment (start 116.5725 112.0125) (end 116.598761 111.991557) (width 0.109) (layer "In6.Cu") (net 44))
  (segment (start 112.405612 112.513941) (end 112.41 112.475) (width 0.109) (layer "In6.Cu") (net 44))
  (segment (start 114.86 111.825) (end 114.86 112.475) (width 0.109) (layer "In6.Cu") (net 44))
  (segment (start 118.722337 109.023975) (end 118.752599 109.009402) (width 0.109) (layer "In6.Cu") (net 44))
  (segment (start 116.57476 111.378364) (end 116.553817 111.352104) (width 0.109) (layer "In6.Cu") (net 44))
  (segment (start 116.978081 110.768231) (end 116.999023 110.741969) (width 0.109) (layer "In6.Cu") (net 44))
  (segment (start 114.646058 111.654388) (end 114.685 111.65) (width 0.109) (layer "In6.Cu") (net 44))
  (segment (start 117.998638 111.409362) (end 118.0289 111.394788) (width 0.109) (layer "In6.Cu") (net 44))
  (segment (start 113.114387 111.786059) (end 113.12733 111.749071) (width 0.109) (layer "In6.Cu") (net 44))
  (segment (start 112.623941 111.654388) (end 112.660929 111.667331) (width 0.109) (layer "In6.Cu") (net 44))
  (segment (start 113.105612 112.513941) (end 113.11 112.475) (width 0.109) (layer "In6.Cu") (net 44))
  (segment (start 119.752214 109.676794) (end 119.773156 109.650532) (width 0.109) (layer "In6.Cu") (net 44))
  (segment (start 117.936821 109.850453) (end 117.970409 109.850454) (width 0.109) (layer "In6.Cu") (net 44))
  (segment (start 117.020765 112.243314) (end 117.051028 112.257888) (width 0.109) (layer "In6.Cu") (net 44))
  (segment (start 116.75837 111.991557) (end 116.784632 112.0125) (width 0.109) (layer "In6.Cu") (net 44))
  (segment (start 113.010929 112.632669) (end 113.04411 112.61182) (width 0.109) (layer "In6.Cu") (net 44))
  (segment (start 114.575889 111.68818) (end 114.60907 111.667331) (width 0.109) (layer "In6.Cu") (net 44))
  (segment (start 116.598761 111.991557) (end 116.629024 111.976983) (width 0.109) (layer "In6.Cu") (net 44))
  (segment (start 119.542343 108.830528) (end 119.568605 108.851469) (width 0.109) (layer "In6.Cu") (net 44))
  (segment (start 119.754475 108.830528) (end 120.41 108.175) (width 0.109) (layer "In6.Cu") (net 44))
  (segment (start 115.248179 112.215889) (end 115.275889 112.188179) (width 0.109) (layer "In6.Cu") (net 44))
  (segment (start 119.20961 108.577664) (end 119.243198 108.577665) (width 0.109) (layer "In6.Cu") (net 44))
  (segment (start 114.023941 111.654388) (end 114.060929 111.667331) (width 0.109) (layer "In6.Cu") (net 44))
  (segment (start 116.97808 110.927841) (end 116.963507 110.897577) (width 0.109) (layer "In6.Cu") (net 44))
  (segment (start 117.249626 112.1331) (end 117.249626 112.099511) (width 0.109) (layer "In6.Cu") (net 44))
  (segment (start 111.846058 111.654388) (end 111.885 111.65) (width 0.109) (layer "In6.Cu") (net 44))
  (segment (start 111.425889 112.61182) (end 111.45907 112.632669) (width 0.109) (layer "In6.Cu") (net 44))
  (segment (start 117.826606 110.079315) (end 117.812033 110.049051) (width 0.109) (layer "In6.Cu") (net 44))
  (segment (start 117.47981 110.282191) (end 117.512558 110.274716) (width 0.109) (layer "In6.Cu") (net 44))
  (segment (start 118.422901 110.985099) (end 118.453163 110.970525) (width 0.109) (layer "In6.Cu") (net 44))
  (segment (start 118.250869 109.655052) (end 118.236296 109.624788) (width 0.109) (layer "In6.Cu") (net 44))
  (segment (start 118.055162 111.373846) (end 118.076104 111.347584) (width 0.109) (layer "In6.Cu") (net 44))
  (segment (start 111.692669 112.550929) (end 111.705612 112.513941) (width 0.109) (layer "In6.Cu") (net 44))
  (segment (start 91.1715 111.8885) (end 91.498673 111.561327) (width 0.109) (layer "In6.Cu") (net 44))
  (segment (start 117.055547 110.706454) (end 117.088295 110.698979) (width 0.109) (layer "In6.Cu") (net 44))
  (segment (start 111.885 111.65) (end 111.923941 111.654388) (width 0.109) (layer "In6.Cu") (net 44))
  (segment (start 114.505612 112.513941) (end 114.51 112.475) (width 0.109) (layer "In6.Cu") (net 44))
  (segment (start 117.873811 109.872501) (end 117.904073 109.857928) (width 0.109) (layer "In6.Cu") (net 44))
  (segment (start 113.360929 111.667331) (end 113.39411 111.68818) (width 0.109) (layer "In6.Cu") (net 44))
  (segment (start 116.956032 110.864831) (end 116.956033 110.831241) (width 0.109) (layer "In6.Cu") (net 44))
  (segment (start 112.69411 111.68818) (end 112.72182 111.71589) (width 0.109) (layer "In6.Cu") (net 44))
  (segment (start 114.925889 112.61182) (end 114.95907 112.632669) (width 0.109) (layer "In6.Cu") (net 44))
  (segment (start 91.1715 111.914) (end 91.1715 111.8885) (width 0.109) (layer "In6.Cu") (net 44))
  (segment (start 117.38777 110.37423) (end 117.402344 110.343968) (width 0.109) (layer "In6.Cu") (net 44))
  (segment (start 118.818935 109.001928) (end 118.851683 109.009401) (width 0.109) (layer "In6.Cu") (net 44))
  (segment (start 115.22733 112.24907) (end 115.248179 112.215889) (width 0.109) (layer "In6.Cu") (net 44))
  (segment (start 114.335 112.65) (end 114.373941 112.645612) (width 0.109) (layer "In6.Cu") (net 44))
  (segment (start 115.073941 112.645612) (end 115.110929 112.632669) (width 0.109) (layer "In6.Cu") (net 44))
  (segment (start 113.596058 112.645612) (end 113.635 112.65) (width 0.109) (layer "In6.Cu") (net 44))
  (segment (start 118.908207 109.044918) (end 119.540082 109.676794) (width 0.109) (layer "In6.Cu") (net 44))
  (segment (start 114.060929 111.667331) (end 114.09411 111.68818) (width 0.109) (layer "In6.Cu") (net 44))
  (segment (start 119.243198 108.577665) (end 119.275946 108.585138) (width 0.109) (layer "In6.Cu") (net 44))
  (segment (start 117.121883 110.69898) (end 117.154631 110.706453) (width 0.109) (layer "In6.Cu") (net 44))
  (segment (start 112.37182 112.58411) (end 112.392669 112.550929) (width 0.109) (layer "In6.Cu") (net 44))
  (segment (start 119.271427 110.136573) (end 119.301689 110.121999) (width 0.109) (layer "In6.Cu") (net 44))
  (segment (start 112.125889 112.61182) (end 112.15907 112.632669) (width 0.109) (layer "In6.Cu") (net 44))
  (segment (start 120.41 108.175) (end 120.41 105.010148) (width 0.109) (layer "In6.Cu") (net 44))
  (segment (start 118.298074 109.448238) (end 118.328336 109.433665) (width 0.109) (layer "In6.Cu") (net 44))
  (segment (start 118.881945 109.023976) (end 118.908207 109.044918) (width 0.109) (layer "In6.Cu") (net 44))
  (segment (start 117.812033 109.949967) (end 117.826607 109.919705) (width 0.109) (layer "In6.Cu") (net 44))
  (segment (start 119.629353 109.719784) (end 119.662942 109.719784) (width 0.109) (layer "In6.Cu") (net 44))
  (segment (start 112.042669 111.749071) (end 112.055612 111.786059) (width 0.109) (layer "In6.Cu") (net 44))
  (segment (start 114.514387 111.786059) (end 114.52733 111.749071) (width 0.109) (layer "In6.Cu") (net 44))
  (segment (start 118.939204 110.468795) (end 118.946678 110.436048) (width 0.109) (layer "In6.Cu") (net 44))
  (segment (start 117.206636 112.222372) (end 117.227578 112.19611) (width 0.109) (layer "In6.Cu") (net 44))
  (segment (start 119.69569 109.71231) (end 119.725952 109.697736) (width 0.109) (layer "In6.Cu") (net 44))
  (segment (start 114.164387 112.513941) (end 114.17733 112.550929) (width 0.109) (layer "In6.Cu") (net 44))
  (segment (start 113.39411 111.68818) (end 113.42182 111.71589) (width 0.109) (layer "In6.Cu") (net 44))
  (segment (start 116.631284 111.130717) (end 116.664032 111.123242) (width 0.109) (layer "In6.Cu") (net 44))
  (segment (start 111.714387 111.786059) (end 111.72733 111.749071) (width 0.109) (layer "In6.Cu") (net 44))
  (segment (start 117.804558 110.016305) (end 117.804559 109.982715) (width 0.109) (layer "In6.Cu") (net 44))
  (segment (start 112.825889 112.61182) (end 112.85907 112.632669) (width 0.109) (layer "In6.Cu") (net 44))
  (segment (start 119.795204 109.587522) (end 119.795204 109.553933) (width 0.109) (layer "In6.Cu") (net 44))
  (segment (start 114.864387 112.513941) (end 114.87733 112.550929) (width 0.109) (layer "In6.Cu") (net 44))
  (segment (start 112.196058 112.645612) (end 112.235 112.65) (width 0.109) (layer "In6.Cu") (net 44))
  (segment (start 116.553818 111.192494) (end 116.57476 111.166232) (width 0.109) (layer "In6.Cu") (net 44))
  (segment (start 114.225889 112.61182) (end 114.25907 112.632669) (width 0.109) (layer "In6.Cu") (net 44))
  (segment (start 118.696075 109.044917) (end 118.722337 109.023975) (width 0.109) (layer "In6.Cu") (net 44))
  (segment (start 112.098179 112.58411) (end 112.125889 112.61182) (width 0.109) (layer "In6.Cu") (net 44))
  (segment (start 114.95907 112.632669) (end 114.996058 112.645612) (width 0.109) (layer "In6.Cu") (net 44))
  (segment (start 117.847549 109.893443) (end 117.873811 109.872501) (width 0.109) (layer "In6.Cu") (net 44))
  (segment (start 114.09411 111.68818) (end 114.12182 111.71589) (width 0.109) (layer "In6.Cu") (net 44))
  (segment (start 112.310929 112.632669) (end 112.34411 112.61182) (width 0.109) (layer "In6.Cu") (net 44))
  (segment (start 118.390153 110.992573) (end 118.422901 110.985099) (width 0.109) (layer "In6.Cu") (net 44))
  (segment (start 119.176862 108.585139) (end 119.20961 108.577664) (width 0.109) (layer "In6.Cu") (net 44))
  (segment (start 113.42182 111.71589) (end 113.442669 111.749071) (width 0.109) (layer "In6.Cu") (net 44))
  (segment (start 119.238679 110.144047) (end 119.271427 110.136573) (width 0.109) (layer "In6.Cu") (net 44))
  (segment (start 119.773156 109.490923) (end 119.752214 109.464661) (width 0.109) (layer "In6.Cu") (net 44))
  (segment (start 117.847549 110.105575) (end 117.826606 110.079315) (width 0.109) (layer "In6.Cu") (net 44))
  (segment (start 117.249626 112.099511) (end 117.242152 112.066764) (width 0.109) (layer "In6.Cu") (net 44))
  (segment (start 118.003157 109.857927) (end 118.033419 109.872502) (width 0.109) (layer "In6.Cu") (net 44))
  (segment (start 120.41 105.010148) (end 121.917851 103.502295) (width 0.109) (layer "In6.Cu") (net 44))
  (segment (start 119.306208 108.599713) (end 119.33247 108.620655) (width 0.109) (layer "In6.Cu") (net 44))
  (segment (start 116.53177 111.255504) (end 116.539244 111.222756) (width 0.109) (layer "In6.Cu") (net 44))
  (segment (start 91.498673 111.561327) (end 92.261327 111.561327) (width 0.109) (layer "In6.Cu") (net 44))
  (segment (start 112.07733 112.550929) (end 112.098179 112.58411) (width 0.109) (layer "In6.Cu") (net 44))
  (segment (start 114.996058 112.645612) (end 115.035 112.65) (width 0.109) (layer "In6.Cu") (net 44))
  (segment (start 115.214387 112.286058) (end 115.22733 112.24907) (width 0.109) (layer "In6.Cu") (net 44))
  (segment (start 118.098152 111.250985) (end 118.090678 111.218238) (width 0.109) (layer "In6.Cu") (net 44))
  (segment (start 118.361084 109.42619) (end 118.394672 109.426191) (width 0.109) (layer "In6.Cu") (net 44))
  (segment (start 114.296058 112.645612) (end 114.335 112.65) (width 0.109) (layer "In6.Cu") (net 44))
  (segment (start 117.206636 112.010239) (end 116.57476 111.378364) (width 0.109) (layer "In6.Cu") (net 44))
  (segment (start 114.842669 111.749071) (end 114.855612 111.786059) (width 0.109) (layer "In6.Cu") (net 44))
  (segment (start 119.348893 109.915186) (end 119.327951 109.888924) (width 0.109) (layer "In6.Cu") (net 44))
  (segment (start 115.110929 112.632669) (end 115.14411 112.61182) (width 0.109) (layer "In6.Cu") (net 44))
  (segment (start 113.11 112.475) (end 113.11 111.825) (width 0.109) (layer "In6.Cu") (net 44))
  (segment (start 111.32182 112.215889) (end 111.342669 112.24907) (width 0.109) (layer "In6.Cu") (net 44))
  (segment (start 118.055162 111.161713) (end 117.423286 110.529838) (width 0.109) (layer "In6.Cu") (net 44))
  (segment (start 118.076104 111.187975) (end 118.055162 111.161713) (width 0.109) (layer "In6.Cu") (net 44))
  (segment (start 117.150111 112.257888) (end 117.180374 112.243314) (width 0.109) (layer "In6.Cu") (net 44))
  (segment (start 117.445028 111.819051) (end 117.475291 111.833625) (width 0.109) (layer "In6.Cu") (net 44))
  (segment (start 111.37733 112.550929) (end 111.398179 112.58411) (width 0.109) (layer "In6.Cu") (net 44))
  (segment (start 119.773156 109.650532) (end 119.78773 109.620269) (width 0.109) (layer "In6.Cu") (net 44))
  (segment (start 113.792669 112.550929) (end 113.805612 112.513941) (width 0.109) (layer "In6.Cu") (net 44))
  (segment (start 117.508038 111.841099) (end 117.541627 111.841099) (width 0.109) (layer "In6.Cu") (net 44))
  (segment (start 112.055612 111.786059) (end 112.06 111.825) (width 0.109) (layer "In6.Cu") (net 44))
  (segment (start 117.899554 111.409362) (end 117.932301 111.416836) (width 0.109) (layer "In6.Cu") (net 44))
  (segment (start 111.355612 112.286058) (end 111.36 112.325) (width 0.109) (layer "In6.Cu") (net 44))
  (segment (start 113.77182 112.58411) (end 113.792669 112.550929) (width 0.109) (layer "In6.Cu") (net 44))
  (segment (start 112.755612 111.786059) (end 112.76 111.825) (width 0.109) (layer "In6.Cu") (net 44))
  (segment (start 118.717817 110.546262) (end 118.74808 110.560836) (width 0.109) (layer "In6.Cu") (net 44))
  (segment (start 118.394672 109.426191) (end 118.42742 109.433664) (width 0.109) (layer "In6.Cu") (net 44))
  (segment (start 118.0289 111.394788) (end 118.055162 111.373846) (width 0.109) (layer "In6.Cu") (net 44))
  (segment (start 113.81 112.475) (end 113.81 111.825) (width 0.109) (layer "In6.Cu") (net 44))
  (segment (start 119.568605 108.851469) (end 119.598867 108.866044) (width 0.109) (layer "In6.Cu") (net 44))
  (segment (start 113.12733 111.749071) (end 113.148179 111.71589) (width 0.109) (layer "In6.Cu") (net 44))
  (segment (start 118.514941 110.893058) (end 118.522415 110.860311) (width 0.109) (layer "In6.Cu") (net 44))
  (segment (start 113.285 111.65) (end 113.323941 111.654388) (width 0.109) (layer "In6.Cu") (net 44))
  (segment (start 113.673941 112.645612) (end 113.710929 112.632669) (width 0.109) (layer "In6.Cu") (net 44))
  (segment (start 113.875889 111.68818) (end 113.90907 111.667331) (width 0.109) (layer "In6.Cu") (net 44))
  (segment (start 112.34411 112.61182) (end 112.37182 112.58411) (width 0.109) (layer "In6.Cu") (net 44))
  (segment (start 119.20509 110.144047) (end 119.238679 110.144047) (width 0.109) (layer "In6.Cu") (net 44))
  (segment (start 113.20907 111.667331) (end 113.246058 111.654388) (width 0.109) (layer "In6.Cu") (net 44))
  (segment (start 117.578894 110.28219) (end 117.609156 110.296765) (width 0.109) (layer "In6.Cu") (net 44))
  (segment (start 113.246058 111.654388) (end 113.285 111.65) (width 0.109) (layer "In6.Cu") (net 44))
  (segment (start 113.323941 111.654388) (end 113.360929 111.667331) (width 0.109) (layer "In6.Cu") (net 44))
  (segment (start 113.464387 112.513941) (end 113.47733 112.550929) (width 0.109) (layer "In6.Cu") (net 44))
  (segment (start 113.635 112.65) (end 113.673941 112.645612) (width 0.109) (layer "In6.Cu") (net 44))
  (segment (start 114.723941 111.654388) (end 114.760929 111.667331) (width 0.109) (layer "In6.Cu") (net 44))
  (segment (start 117.211155 110.74197) (end 117.84303 111.373846) (width 0.109) (layer "In6.Cu") (net 44))
  (segment (start 112.392669 112.550929) (end 112.405612 112.513941) (width 0.109) (layer "In6.Cu") (net 44))
  (segment (start 118.522415 110.826722) (end 118.514941 110.793975) (width 0.109) (layer "In6.Cu") (net 44))
  (segment (start 117.826607 109.919705) (end 117.847549 109.893443) (width 0.109) (layer "In6.Cu") (net 44))
  (segment (start 112.06 111.825) (end 112.06 112.475) (width 0.109) (layer "In6.Cu") (net 44))
  (segment (start 115.21 112.325) (end 115.214387 112.286058) (width 0.109) (layer "In6.Cu") (net 44))
  (segment (start 118.236296 109.525704) (end 118.25087 109.495442) (width 0.109) (layer "In6.Cu") (net 44))
  (segment (start 117.117364 112.265362) (end 117.150111 112.257888) (width 0.109) (layer "In6.Cu") (net 44))
  (segment (start 114.16 111.825) (end 114.16 112.475) (width 0.109) (layer "In6.Cu") (net 44))
  (segment (start 118.323817 110.985099) (end 118.356564 110.992573) (width 0.109) (layer "In6.Cu") (net 44))
  (segment (start 113.148179 111.71589) (end 113.175889 111.68818) (width 0.109) (layer "In6.Cu") (net 44))
  (segment (start 113.092669 112.550929) (end 113.105612 112.513941) (width 0.109) (layer "In6.Cu") (net 44))
  (segment (start 118.098152 111.284574) (end 118.098152 111.250985) (width 0.109) (layer "In6.Cu") (net 44))
  (segment (start 112.764387 112.513941) (end 112.77733 112.550929) (width 0.109) (layer "In6.Cu") (net 44))
  (segment (start 119.596606 109.71231) (end 119.629353 109.719784) (width 0.109) (layer "In6.Cu") (net 44))
  (segment (start 117.512558 110.274716) (end 117.546146 110.274717) (width 0.109) (layer "In6.Cu") (net 44))
  (segment (start 117.380296 110.406978) (end 117.38777 110.37423) (width 0.109) (layer "In6.Cu") (net 44))
  (segment (start 92.4 111.7) (end 92.4 112) (width 0.109) (layer "In6.Cu") (net 44))
  (segment (start 119.795204 109.553933) (end 119.78773 109.521186) (width 0.109) (layer "In6.Cu") (net 44))
  (segment (start 114.198179 112.58411) (end 114.225889 112.61182) (width 0.109) (layer "In6.Cu") (net 44))
  (segment (start 117.083775 112.265362) (end 117.117364 112.265362) (width 0.109) (layer "In6.Cu") (net 44))
  (segment (start 112.50907 111.667331) (end 112.546058 111.654388) (width 0.109) (layer "In6.Cu") (net 44))
  (segment (start 119.099395 108.806526) (end 119.084822 108.776262) (width 0.109) (layer "In6.Cu") (net 44))
  (segment (start 117.380295 110.440568) (end 117.380296 110.406978) (width 0.109) (layer "In6.Cu") (net 44))
  (segment (start 111.67182 112.58411) (end 111.692669 112.550929) (width 0.109) (layer "In6.Cu") (net 44))
  (segment (start 113.46 111.825) (end 113.46 112.475) (width 0.109) (layer "In6.Cu") (net 44))
  (segment (start 113.946058 111.654388) (end 113.985 111.65) (width 0.109) (layer "In6.Cu") (net 44))
  (segment (start 112.85907 112.632669) (end 112.896058 112.645612) (width 0.109) (layer "In6.Cu") (net 44))
  (segment (start 116.661771 111.969509) (end 116.69536 111.969509) (width 0.109) (layer "In6.Cu") (net 44))
  (segment (start 113.82733 111.749071) (end 113.848179 111.71589) (width 0.109) (layer "In6.Cu") (net 44))
  (segment (start 117.84303 111.373846) (end 117.869291 111.394788) (width 0.109) (layer "In6.Cu") (net 44))
  (segment (start 119.752214 109.464661) (end 119.120338 108.832786) (width 0.109) (layer "In6.Cu") (net 44))
  (segment (start 118.514941 110.793975) (end 118.500367 110.763712) (width 0.109) (layer "In6.Cu") (net 44))
  (segment (start 112.76 111.825) (end 112.76 112.475) (width 0.109) (layer "In6.Cu") (net 44))
  (segment (start 117.869291 111.394788) (end 117.899554 111.409362) (width 0.109) (layer "In6.Cu") (net 44))
  (segment (start 117.666415 111.642501) (end 117.651841 111.612238) (width 0.109) (layer "In6.Cu") (net 44))
  (segment (start 114.44411 112.61182) (end 114.47182 112.58411) (width 0.109) (layer "In6.Cu") (net 44))
  (segment (start 117.609156 110.296765) (end 117.635418 110.317707) (width 0.109) (layer "In6.Cu") (net 44))
  (segment (start 111.29411 112.188179) (end 111.32182 112.215889) (width 0.109) (layer "In6.Cu") (net 44))
  (segment (start 114.685 111.65) (end 114.723941 111.654388) (width 0.109) (layer "In6.Cu") (net 44))
  (segment (start 119.115819 110.101057) (end 119.14208 110.121999) (width 0.109) (layer "In6.Cu") (net 44))
  (segment (start 117.418767 111.798109) (end 117.445028 111.819051) (width 0.109) (layer "In6.Cu") (net 44))
  (segment (start 111.573941 112.645612) (end 111.610929 112.632669) (width 0.109) (layer "In6.Cu") (net 44))
  (segment (start 119.1466 108.599712) (end 119.176862 108.585139) (width 0.109) (layer "In6.Cu") (net 44))
  (segment (start 113.74411 112.61182) (end 113.77182 112.58411) (width 0.109) (layer "In6.Cu") (net 44))
  (segment (start 118.293554 110.970525) (end 118.323817 110.985099) (width 0.109) (layer "In6.Cu") (net 44))
  (segment (start 117.604637 111.819051) (end 117.630899 111.798109) (width 0.109) (layer "In6.Cu") (net 44))
  (segment (start 112.448179 111.71589) (end 112.475889 111.68818) (width 0.109) (layer "In6.Cu") (net 44))
  (segment (start 114.492669 112.550929) (end 114.505612 112.513941) (width 0.109) (layer "In6.Cu") (net 44))
  (segment (start 119.728213 108.85147) (end 119.754475 108.830528) (width 0.109) (layer "In6.Cu") (net 44))
  (segment (start 114.410929 112.632669) (end 114.44411 112.61182) (width 0.109) (layer "In6.Cu") (net 44))
  (segment (start 114.760929 111.667331) (end 114.79411 111.68818) (width 0.109) (layer "In6.Cu") (net 44))
  (segment (start 119.370941 110.011785) (end 119.370941 109.978196) (width 0.109) (layer "In6.Cu") (net 44))
  (segment (start 92.261327 111.561327) (end 92.4 111.7) (width 0.109) (layer "In6.Cu") (net 44))
  (segment (start 118.479425 110.73745) (end 117.847549 110.105575) (width 0.109) (layer "In6.Cu") (net 44))
  (segment (start 118.847164 110.560836) (end 118.877426 110.546262) (width 0.109) (layer "In6.Cu") (net 44))
  (segment (start 116.956033 110.831241) (end 116.963507 110.798493) (width 0.109) (layer "In6.Cu") (net 44))
  (segment (start 119.301689 110.121999) (end 119.327951 110.101057) (width 0.109) (layer "In6.Cu") (net 44))
  (segment (start 118.780827 110.56831) (end 118.814416 110.56831) (width 0.109) (layer "In6.Cu") (net 44))
  (segment (start 117.402344 110.343968) (end 117.423286 110.317706) (width 0.109) (layer "In6.Cu") (net 44))
  (segment (start 112.15907 112.632669) (end 112.196058 112.645612) (width 0.109) (layer "In6.Cu") (net 44))
  (segment (start 119.662942 109.719784) (end 119.69569 109.71231) (width 0.109) (layer "In6.Cu") (net 44))
  (segment (start 121.917851 103.502295) (end 121.917851 103.219453) (width 0.109) (layer "In6.Cu") (net 44))
  (segment (start 112.41 111.825) (end 112.414387 111.786059) (width 0.109) (layer "In6.Cu") (net 44))
  (segment (start 113.455612 111.786059) (end 113.46 111.825) (width 0.109) (layer "In6.Cu") (net 44))
  (segment (start 116.539244 111.222756) (end 116.553818 111.192494) (width 0.109) (layer "In6.Cu") (net 44))
  (segment (start 111.185 112.15) (end 111.223941 112.154387) (width 0.109) (layer "In6.Cu") (net 44))
  (segment (start 111.923941 111.654388) (end 111.960929 111.667331) (width 0.109) (layer "In6.Cu") (net 44))
  (segment (start 118.328336 109.433665) (end 118.361084 109.42619) (width 0.109) (layer "In6.Cu") (net 44))
  (segment (start 118.814416 110.56831) (end 118.847164 110.560836) (width 0.109) (layer "In6.Cu") (net 44))
  (segment (start 118.356564 110.992573) (end 118.390153 110.992573) (width 0.109) (layer "In6.Cu") (net 44))
  (segment (start 118.271812 109.46918) (end 118.298074 109.448238) (width 0.109) (layer "In6.Cu") (net 44))
  (segment (start 118.92463 110.499058) (end 118.939204 110.468795) (width 0.109) (layer "In6.Cu") (net 44))
  (segment (start 115.21 112.475) (end 115.21 112.325) (width 0.109) (layer "In6.Cu") (net 44))
  (segment (start 118.090678 111.317321) (end 118.098152 111.284574) (width 0.109) (layer "In6.Cu") (net 44))
  (segment (start 119.33247 108.620655) (end 119.542343 108.830528) (width 0.109) (layer "In6.Cu") (net 44))
  (segment (start 116.784632 112.0125) (end 116.994504 112.222372) (width 0.109) (layer "In6.Cu") (net 44))
  (segment (start 114.155612 111.786059) (end 114.16 111.825) (width 0.109) (layer "In6.Cu") (net 44))
  (segment (start 112.41 112.475) (end 112.41 111.825) (width 0.109) (layer "In6.Cu") (net 44))
  (segment (start 117.666415 111.741584) (end 117.673889 111.708837) (width 0.109) (layer "In6.Cu") (net 44))
  (segment (start 116.531769 111.289094) (end 116.53177 111.255504) (width 0.109) (layer "In6.Cu") (net 44))
  (segment (start 118.92463 110.339449) (end 118.903688 110.313187) (width 0.109) (layer "In6.Cu") (net 44))
  (segment (start 117.38777 110.473314) (end 117.380295 110.440568) (width 0.109) (layer "In6.Cu") (net 44))
  (segment (start 115.346058 112.154387) (end 115.385 112.15) (width 0.109) (layer "In6.Cu") (net 44))
  (segment (start 118.675132 109.230789) (end 118.660559 109.200525) (width 0.109) (layer "In6.Cu") (net 44))
  (segment (start 119.370941 109.978196) (end 119.363467 109.945449) (width 0.109) (layer "In6.Cu") (net 44))
  (segment (start 117.154631 110.706453) (end 117.184893 110.721028) (width 0.109) (layer "In6.Cu") (net 44))
  (segment (start 111.496058 112.645612) (end 111.535 112.65) (width 0.109) (layer "In6.Cu") (net 44))
  (segment (start 114.60907 111.667331) (end 114.646058 111.654388) (width 0.109) (layer "In6.Cu") (net 44))
  (segment (start 118.696075 109.257049) (end 118.675132 109.230789) (width 0.109) (layer "In6.Cu") (net 44))
  (segment (start 117.812033 110.049051) (end 117.804558 110.016305) (width 0.109) (layer "In6.Cu") (net 44))
  (segment (start 116.76063 111.145291) (end 116.786892 111.166233) (width 0.109) (layer "In6.Cu") (net 44))
  (segment (start 117.180374 112.243314) (end 117.206636 112.222372) (width 0.109) (layer "In6.Cu") (net 44))
  (segment (start 112.414387 111.786059) (end 112.42733 111.749071) (width 0.109) (layer "In6.Cu") (net 44))
  (segment (start 115.14411 112.61182) (end 115.17182 112.58411) (width 0.109) (layer "In6.Cu") (net 44))
  (segment (start 114.25907 112.632669) (end 114.296058 112.645612) (width 0.109) (layer "In6.Cu") (net 44))
  (segment (start 118.946678 110.402459) (end 118.939204 110.369712) (width 0.109) (layer "In6.Cu") (net 44))
  (segment (start 119.598867 108.866044) (end 119.631615 108.873517) (width 0.109) (layer "In6.Cu") (net 44))
  (segment (start 112.76 112.475) (end 112.764387 112.513941) (width 0.109) (layer "In6.Cu") (net 44))
  (segment (start 111.260929 112.16733) (end 111.29411 112.188179) (width 0.109) (layer "In6.Cu") (net 44))
  (segment (start 116.435 112.15) (end 116.5725 112.0125) (width 0.109) (layer "In6.Cu") (net 44))
  (segment (start 112.064387 112.513941) (end 112.07733 112.550929) (width 0.109) (layer "In6.Cu") (net 44))
  (segment (start 111.748179 111.71589) (end 111.775889 111.68818) (width 0.109) (layer "In6.Cu") (net 44))
  (segment (start 112.42733 111.749071) (end 112.448179 111.71589) (width 0.109) (layer "In6.Cu") (net 44))
  (segment (start 119.327951 110.101057) (end 119.348893 110.074795) (width 0.109) (layer "In6.Cu") (net 44))
  (segment (start 115.385 112.15) (end 116.435 112.15) (width 0.109) (layer "In6.Cu") (net 44))
  (segment (start 111.80907 111.667331) (end 111.846058 111.654388) (width 0.109) (layer "In6.Cu") (net 44))
  (segment (start 113.81 111.825) (end 113.814387 111.786059) (width 0.109) (layer "In6.Cu") (net 44))
  (segment (start 119.172343 110.136573) (end 119.20509 110.144047) (width 0.109) (layer "In6.Cu") (net 44))
  (segment (start 117.673889 111.675248) (end 117.666415 111.642501) (width 0.109) (layer "In6.Cu") (net 44))
  (segment (start 117.088295 110.698979) (end 117.121883 110.69898) (width 0.109) (layer "In6.Cu") (net 44))
  (segment (start 112.973941 112.645612) (end 113.010929 112.632669) (width 0.109) (layer "In6.Cu") (net 44))
  (segment (start 117.051028 112.257888) (end 117.083775 112.265362) (width 0.109) (layer "In6.Cu") (net 44))
  (segment (start 117.630899 111.585976) (end 116.999023 110.954101) (width 0.109) (layer "In6.Cu") (net 44))
  (segment (start 113.55907 112.632669) (end 113.596058 112.645612) (width 0.109) (layer "In6.Cu") (net 44))
  (segment (start 119.631615 108.873517) (end 119.665203 108.873518) (width 0.109) (layer "In6.Cu") (net 44))
  (segment (start 114.51 111.825) (end 114.514387 111.786059) (width 0.109) (layer "In6.Cu") (net 44))
  (segment (start 117.025285 110.721027) (end 117.055547 110.706454) (width 0.109) (layer "In6.Cu") (net 44))
  (segment (start 115.17182 112.58411) (end 115.192669 112.550929) (width 0.109) (layer "In6.Cu") (net 44))
  (segment (start 118.903688 110.52532) (end 118.92463 110.499058) (width 0.109) (layer "In6.Cu") (net 44))
  (segment (start 114.82182 111.71589) (end 114.842669 111.749071) (width 0.109) (layer "In6.Cu") (net 44))
  (segment (start 118.660559 109.101441) (end 118.675133 109.071179) (width 0.109) (layer "In6.Cu") (net 44))
  (segment (start 113.814387 111.786059) (end 113.82733 111.749071) (width 0.109) (layer "In6.Cu") (net 44))
  (segment (start 119.78773 109.620269) (end 119.795204 109.587522) (width 0.109) (layer "In6.Cu") (net 44))
  (segment (start 116.730368 111.130716) (end 116.76063 111.145291) (width 0.109) (layer "In6.Cu") (net 44))
  (segment (start 117.574375 111.833625) (end 117.604637 111.819051) (width 0.109) (layer "In6.Cu") (net 44))
  (segment (start 112.475889 111.68818) (end 112.50907 111.667331) (width 0.109) (layer "In6.Cu") (net 44))
  (segment (start 116.69536 111.969509) (end 116.728107 111.976983) (width 0.109) (layer "In6.Cu") (net 44))
  (segment (start 116.629024 111.976983) (end 116.661771 111.969509) (width 0.109) (layer "In6.Cu") (net 44))
  (segment (start 118.25087 109.495442) (end 118.271812 109.46918) (width 0.109) (layer "In6.Cu") (net 44))
  (segment (start 113.47733 112.550929) (end 113.498179 112.58411) (width 0.109) (layer "In6.Cu") (net 44))
  (segment (start 112.585 111.65) (end 112.623941 111.654388) (width 0.109) (layer "In6.Cu") (net 44))
  (segment (start 111.705612 112.513941) (end 111.71 112.475) (width 0.109) (layer "In6.Cu") (net 44))
  (segment (start 119.327951 109.888924) (end 118.696075 109.257049) (width 0.109) (layer "In6.Cu") (net 44))
  (segment (start 118.228822 109.558452) (end 118.236296 109.525704) (width 0.109) (layer "In6.Cu") (net 44))
  (segment (start 115.205612 112.513941) (end 115.21 112.475) (width 0.109) (layer "In6.Cu") (net 44))
  (segment (start 111.36 112.475) (end 111.364387 112.513941) (width 0.109) (layer "In6.Cu") (net 44))
  (segment (start 113.498179 112.58411) (end 113.525889 112.61182) (width 0.109) (layer "In6.Cu") (net 44))
  (segment (start 118.877426 110.546262) (end 118.903688 110.52532) (width 0.109) (layer "In6.Cu") (net 44))
  (segment (start 118.236296 109.624788) (end 118.228821 109.592042) (width 0.109) (layer "In6.Cu") (net 44))
  (segment (start 115.30907 112.16733) (end 115.346058 112.154387) (width 0.109) (layer "In6.Cu") (net 44))
  (segment (start 118.653084 109.167779) (end 118.653085 109.134189) (width 0.109) (layer "In6.Cu") (net 44))
  (segment (start 117.904073 109.857928) (end 117.936821 109.850453) (width 0.109) (layer "In6.Cu") (net 44))
  (segment (start 111.535 112.65) (end 111.573941 112.645612) (width 0.109) (layer "In6.Cu") (net 44))
  (segment (start 113.04411 112.61182) (end 113.07182 112.58411) (width 0.109) (layer "In6.Cu") (net 44))
  (segment (start 118.752599 109.009402) (end 118.785347 109.001927) (width 0.109) (layer "In6.Cu") (net 44))
  (segment (start 118.453163 110.970525) (end 118.479425 110.949583) (width 0.109) (layer "In6.Cu") (net 44))
  (segment (start 119.566343 109.697736) (end 119.596606 109.71231) (width 0.109) (layer "In6.Cu") (net 44))
  (segment (start 111.45907 112.632669) (end 111.496058 112.645612) (width 0.109) (layer "In6.Cu") (net 44))
  (segment (start 119.348893 110.074795) (end 119.363467 110.044532) (width 0.109) (layer "In6.Cu") (net 44))
  (segment (start 118.076104 111.347584) (end 118.090678 111.317321) (width 0.109) (layer "In6.Cu") (net 44))
  (segment (start 114.52733 111.749071) (end 114.548179 111.71589) (width 0.109) (layer "In6.Cu") (net 44))
  (segment (start 113.985 111.65) (end 114.023941 111.654388) (width 0.109) (layer "In6.Cu") (net 44))
  (segment (start 112.273941 112.645612) (end 112.310929 112.632669) (width 0.109) (layer "In6.Cu") (net 44))
  (segment (start 119.077348 108.709926) (end 119.084822 108.677178) (width 0.109) (layer "In6.Cu") (net 44))
  (segment (start 114.47182 112.58411) (end 114.492669 112.550929) (width 0.109) (layer "In6.Cu") (net 44))
  (segment (start 119.363467 110.044532) (end 119.370941 110.011785) (width 0.109) (layer "In6.Cu") (net 44))
  (segment (start 116.553817 111.352104) (end 116.539244 111.32184) (width 0.109) (layer "In6.Cu") (net 44))
  (segment (start 112.06 112.475) (end 112.064387 112.513941) (width 0.109) (layer "In6.Cu") (net 44))
  (segment (start 118.267293 110.949583) (end 118.293554 110.970525) (width 0.109) (layer "In6.Cu") (net 44))
  (segment (start 111.342669 112.24907) (end 111.355612 112.286058) (width 0.109) (layer "In6.Cu") (net 44))
  (segment (start 111.72733 111.749071) (end 111.748179 111.71589) (width 0.109) (layer "In6.Cu") (net 44))
  (segment (start 117.630899 111.798109) (end 117.651841 111.771847) (width 0.109) (layer "In6.Cu") (net 44))
  (segment (start 116.69762 111.123243) (end 116.730368 111.130716) (width 0.109) (layer "In6.Cu") (net 44))
  (segment (start 117.242152 112.066764) (end 117.227578 112.036501) (width 0.109) (layer "In6.Cu") (net 44))
  (segment (start 112.77733 112.550929) (end 112.798179 112.58411) (width 0.109) (layer "In6.Cu") (net 44))
  (segment (start 117.970409 109.850454) (end 118.003157 109.857927) (width 0.109) (layer "In6.Cu") (net 44))
  (segment (start 118.903688 110.313187) (end 118.271812 109.681312) (width 0.109) (layer "In6.Cu") (net 44))
  (segment (start 114.142669 111.749071) (end 114.155612 111.786059) (width 0.109) (layer "In6.Cu") (net 44))
  (segment (start 113.11 111.825) (end 113.114387 111.786059) (width 0.109) (layer "In6.Cu") (net 44))
  (segment (start 118.457682 109.448239) (end 118.483944 109.469181) (width 0.109) (layer "In6.Cu") (net 44))
  (segment (start 112.742669 111.749071) (end 112.755612 111.786059) (width 0.109) (layer "In6.Cu") (net 44))
  (segment (start 113.710929 112.632669) (end 113.74411 112.61182) (width 0.109) (layer "In6.Cu") (net 44))
  (segment (start 118.653085 109.134189) (end 118.660559 109.101441) (width 0.109) (layer "In6.Cu") (net 44))
  (segment (start 118.228821 109.592042) (end 118.228822 109.558452) (width 0.109) (layer "In6.Cu") (net 44))
  (segment (start 116.539244 111.32184) (end 116.531769 111.289094) (width 0.109) (layer "In6.Cu") (net 44))
  (segment (start 112.798179 112.58411) (end 112.825889 112.61182) (width 0.109) (layer "In6.Cu") (net 44))
  (segment (start 111.71 111.825) (end 111.714387 111.786059) (width 0.109) (layer "In6.Cu") (net 44))
  (segment (start 118.42742 109.433664) (end 118.457682 109.448239) (width 0.109) (layer "In6.Cu") (net 44))
  (segment (start 114.855612 111.786059) (end 114.86 111.825) (width 0.109) (layer "In6.Cu") (net 44))
  (segment (start 118.033419 109.872502) (end 118.059681 109.893444) (width 0.109) (layer "In6.Cu") (net 44))
  (segment (start 113.525889 112.61182) (end 113.55907 112.632669) (width 0.109) (layer "In6.Cu") (net 44))
  (segment (start 117.541627 111.841099) (end 117.574375 111.833625) (width 0.109) (layer "In6.Cu") (net 44))
  (segment (start 119.275946 108.585138) (end 119.306208 108.599713) (width 0.109) (layer "In6.Cu") (net 44))
  (segment (start 116.57476 111.166232) (end 116.601022 111.14529) (width 0.109) (layer "In6.Cu") (net 44))
  (segment (start 117.635418 110.317707) (end 118.267293 110.949583) (width 0.109) (layer "In6.Cu") (net 44))
  (segment (start 113.07182 112.58411) (end 113.092669 112.550929) (width 0.109) (layer "In6.Cu") (net 44))
  (segment (start 118.479425 110.949583) (end 118.500367 110.923321) (width 0.109) (layer "In6.Cu") (net 44))
  (segment (start 96.1 112.15) (end 111.185 112.15) (width 0.109) (layer "In6.Cu") (net 44))
  (segment (start 119.363467 109.945449) (end 119.348893 109.915186) (width 0.109) (layer "In6.Cu") (net 44))
  (segment (start 119.099396 108.646916) (end 119.120338 108.620654) (width 0.109) (layer "In6.Cu") (net 44))
  (segment (start 114.51 112.475) (end 114.51 111.825) (width 0.109) (layer "In6.Cu") (net 44))
  (segment (start 117.449548 110.296764) (end 117.47981 110.282191) (width 0.109) (layer "In6.Cu") (net 44))
  (segment (start 117.673889 111.708837) (end 117.673889 111.675248) (width 0.109) (layer "In6.Cu") (net 44))
  (segment (start 116.728107 111.976983) (end 116.75837 111.991557) (width 0.109) (layer "In6.Cu") (net 44))
  (segment (start 118.090678 111.218238) (end 118.076104 111.187975) (width 0.109) (layer "In6.Cu") (net 44))
  (segment (start 118.500367 110.923321) (end 118.514941 110.893058) (width 0.109) (layer "In6.Cu") (net 44))
  (segment (start 118.483944 109.469181) (end 119.115819 110.101057) (width 0.109) (layer "In6.Cu") (net 44))
  (segment (start 115.035 112.65) (end 115.073941 112.645612) (width 0.109) (layer "In6.Cu") (net 44))
  (segment (start 115.275889 112.188179) (end 115.30907 112.16733) (width 0.109) (layer "In6.Cu") (net 44))
  (segment (start 118.660559 109.200525) (end 118.653084 109.167779) (width 0.109) (layer "In6.Cu") (net 44))
  (segment (start 112.546058 111.654388) (end 112.585 111.65) (width 0.109) (layer "In6.Cu") (net 44))
  (segment (start 118.675133 109.071179) (end 118.696075 109.044917) (width 0.109) (layer "In6.Cu") (net 44))
  (segment (start 114.16 112.475) (end 114.164387 112.513941) (width 0.109) (layer "In6.Cu") (net 44))
  (segment (start 117.475291 111.833625) (end 117.508038 111.841099) (width 0.109) (layer "In6.Cu") (net 44))
  (segment (start 113.805612 112.513941) (end 113.81 112.475) (width 0.109) (layer "In6.Cu") (net 44))
  (segment (start 114.87733 112.550929) (end 114.898179 112.58411) (width 0.109) (layer "In6.Cu") (net 44))
  (segment (start 119.697951 108.866043) (end 119.728213 108.85147) (width 0.109) (layer "In6.Cu") (net 44))
  (segment (start 111.775889 111.68818) (end 111.80907 111.667331) (width 0.109) (layer "In6.Cu") (net 44))
  (segment (start 117.423286 110.529838) (end 117.402343 110.503578) (width 0.109) (layer "In6.Cu") (net 44))
  (segment (start 117.402343 110.503578) (end 117.38777 110.473314) (width 0.109) (layer "In6.Cu") (net 44))
  (segment (start 114.12182 111.71589) (end 114.142669 111.749071) (width 0.109) (layer "In6.Cu") (net 44))
  (segment (start 118.946678 110.436048) (end 118.946678 110.402459) (width 0.109) (layer "In6.Cu") (net 44))
  (segment (start 112.660929 111.667331) (end 112.69411 111.68818) (width 0.109) (layer "In6.Cu") (net 44))
  (segment (start 117.227578 112.036501) (end 117.206636 112.010239) (width 0.109) (layer "In6.Cu") (net 44))
  (segment (start 111.99411 111.68818) (end 112.02182 111.71589) (width 0.109) (layer "In6.Cu") (net 44))
  (segment (start 111.364387 112.513941) (end 111.37733 112.550929) (width 0.109) (layer "In6.Cu") (net 44))
  (segment (start 115.192669 112.550929) (end 115.205612 112.513941) (width 0.109) (layer "In6.Cu") (net 44))
  (segment (start 116.999023 110.741969) (end 117.025285 110.721027) (width 0.109) (layer "In6.Cu") (net 44))
  (segment (start 113.175889 111.68818) (end 113.20907 111.667331) (width 0.109) (layer "In6.Cu") (net 44))
  (segment (start 114.86 112.475) (end 114.864387 112.513941) (width 0.109) (layer "In6.Cu") (net 44))
  (segment (start 111.36 112.325) (end 111.36 112.475) (width 0.109) (layer "In6.Cu") (net 44))
  (segment (start 114.898179 112.58411) (end 114.925889 112.61182) (width 0.109) (layer "In6.Cu") (net 44))
  (segment (start 113.90907 111.667331) (end 113.946058 111.654388) (width 0.109) (layer "In6.Cu") (net 44))
  (segment (start 118.271812 109.681312) (end 118.250869 109.655052) (width 0.109) (layer "In6.Cu") (net 44))
  (segment (start 111.71 112.475) (end 111.71 111.825) (width 0.109) (layer "In6.Cu") (net 44))
  (segment (start 121.015557 101.694966) (end 121.03724 101.729475) (width 0.182) (layer "F.Cu") (net 45))
  (segment (start 121.066058 101.758293) (end 121.100567 101.779976) (width 0.182) (layer "F.Cu") (net 45))
  (segment (start 121.100567 101.779976) (end 121.139035 101.793436) (width 0.182) (layer "F.Cu") (net 45))
  (segment (start 121.03724 101.502524) (end 121.015557 101.537033) (width 0.182) (layer "F.Cu") (net 45))
  (segment (start 121.363293 101.365475) (end 121.334475 101.394293) (width 0.182) (layer "F.Cu") (net 45))
  (segment (start 121.384976 101.330966) (end 121.363293 101.365475) (width 0.182) (layer "F.Cu") (net 45))
  (segment (start 121.139035 101.438563) (end 121.100567 101.452023) (width 0.182) (layer "F.Cu") (net 45))
  (segment (start 121.139035 101.793436) (end 121.179534 101.798) (width 0.182) (layer "F.Cu") (net 45))
  (segment (start 121.002097 101.656498) (end 121.015557 101.694966) (width 0.182) (layer "F.Cu") (net 45))
  (segment (start 90.7865 111.589) (end 91.1715 111.278999) (width 0.182) (layer "F.Cu") (net 45))
  (segment (start 121.179534 101.798) (end 121.221 101.798) (width 0.182) (layer "F.Cu") (net 45))
  (segment (start 120.997534 101.616) (end 121.002097 101.656498) (width 0.182) (layer "F.Cu") (net 45))
  (segment (start 121.03724 101.729475) (end 121.066058 101.758293) (width 0.182) (layer "F.Cu") (net 45))
  (segment (start 121.299966 101.816023) (end 121.334475 101.837706) (width 0.182) (layer "F.Cu") (net 45))
  (segment (start 121.299966 101.415976) (end 121.261498 101.429436) (width 0.182) (layer "F.Cu") (net 45))
  (segment (start 121.221 101.434) (end 121.179534 101.434) (width 0.182) (layer "F.Cu") (net 45))
  (segment (start 121.100567 101.452023) (end 121.066058 101.473706) (width 0.182) (layer "F.Cu") (net 45))
  (segment (start 121.363293 101.866524) (end 121.384976 101.901033) (width 0.182) (layer "F.Cu") (net 45))
  (segment (start 121.066058 101.473706) (end 121.03724 101.502524) (width 0.182) (layer "F.Cu") (net 45))
  (segment (start 121.398436 101.292498) (end 121.384976 101.330966) (width 0.182) (layer "F.Cu") (net 45))
  (segment (start 121.002097 101.575501) (end 120.997534 101.616) (width 0.182) (layer "F.Cu") (net 45))
  (segment (start 121.384976 101.901033) (end 121.398436 101.939501) (width 0.182) (layer "F.Cu") (net 45))
  (segment (start 121.221 101.798) (end 121.261498 101.802563) (width 0.182) (layer "F.Cu") (net 45))
  (segment (start 121.334475 101.837706) (end 121.363293 101.866524) (width 0.182) (layer "F.Cu") (net 45))
  (segment (start 121.179534 101.434) (end 121.139035 101.438563) (width 0.182) (layer "F.Cu") (net 45))
  (segment (start 121.398436 101.939501) (end 121.403 101.98) (width 0.182) (layer "F.Cu") (net 45))
  (segment (start 121.403 102.375646) (end 121.174323 102.604323) (width 0.182) (layer "F.Cu") (net 45))
  (segment (start 121.261498 101.429436) (end 121.221 101.434) (width 0.182) (layer "F.Cu") (net 45))
  (segment (start 121.403 101.98) (end 121.403 102.375646) (width 0.182) (layer "F.Cu") (net 45))
  (segment (start 121.261498 101.802563) (end 121.299966 101.816023) (width 0.182) (layer "F.Cu") (net 45))
  (segment (start 121.403 101.252) (end 121.398436 101.292498) (width 0.182) (layer "F.Cu") (net 45))
  (segment (start 121.334475 101.394293) (end 121.299966 101.415976) (width 0.182) (layer "F.Cu") (net 45))
  (segment (start 121.015557 101.537033) (end 121.002097 101.575501) (width 0.182) (layer "F.Cu") (net 45))
  (segment (start 121.403 100.6951) (end 121.403 101.252) (width 0.182) (layer "F.Cu") (net 45))
  (via (at 121.174323 102.604323) (size 0.45) (drill 0.1) (layers "F.Cu" "B.Cu") (net 45))
  (via (at 91.1715 111.278999) (size 0.45) (drill 0.1) (layers "F.Cu" "B.Cu") (net 45))
  (segment (start 112.50907 113.373361) (end 112.546058 113.360418) (width 0.109) (layer "In6.Cu") (net 45))
  (segment (start 112.15907 114.326639) (end 112.196058 114.339582) (width 0.109) (layer "In6.Cu") (net 45))
  (segment (start 113.323941 113.360418) (end 113.360929 113.373361) (width 0.109) (layer "In6.Cu") (net 45))
  (segment (start 111.748179 113.42192) (end 111.775889 113.39421) (width 0.109) (layer "In6.Cu") (net 45))
  (segment (start 112.764387 114.207911) (end 112.77733 114.244899) (width 0.109) (layer "In6.Cu") (net 45))
  (segment (start 111.80907 113.373361) (end 111.846058 113.360418) (width 0.109) (layer "In6.Cu") (net 45))
  (segment (start 121.825 106.055) (end 122.45 105.43) (width 0.109) (layer "In6.Cu") (net 45))
  (segment (start 113.39411 113.39421) (end 113.42182 113.42192) (width 0.109) (layer "In6.Cu") (net 45))
  (segment (start 112.85907 114.326639) (end 112.896058 114.339582) (width 0.109) (layer "In6.Cu") (net 45))
  (segment (start 113.848179 113.42192) (end 113.875889 113.39421) (width 0.109) (layer "In6.Cu") (net 45))
  (segment (start 113.90907 113.373361) (end 113.946058 113.360418) (width 0.109) (layer "In6.Cu") (net 45))
  (segment (start 113.47733 114.244899) (end 113.498179 114.27808) (width 0.109) (layer "In6.Cu") (net 45))
  (segment (start 113.55907 114.326639) (end 113.596058 114.339582) (width 0.109) (layer "In6.Cu") (net 45))
  (segment (start 113.175889 113.39421) (end 113.20907 113.373361) (width 0.109) (layer "In6.Cu") (net 45))
  (segment (start 113.635 114.34397) (end 113.673941 114.339582) (width 0.109) (layer "In6.Cu") (net 45))
  (segment (start 124.6 104.33) (end 124.6 101.98) (width 0.109) (layer "In6.Cu") (net 45))
  (segment (start 113.12733 113.455101) (end 113.148179 113.42192) (width 0.109) (layer "In6.Cu") (net 45))
  (segment (start 112.825889 114.30579) (end 112.85907 114.326639) (width 0.109) (layer "In6.Cu") (net 45))
  (segment (start 114.12182 113.42192) (end 114.142669 113.455101) (width 0.109) (layer "In6.Cu") (net 45))
  (segment (start 112.798179 114.27808) (end 112.825889 114.30579) (width 0.109) (layer "In6.Cu") (net 45))
  (segment (start 113.20907 113.373361) (end 113.246058 113.360418) (width 0.109) (layer "In6.Cu") (net 45))
  (segment (start 112.77733 114.244899) (end 112.798179 114.27808) (width 0.109) (layer "In6.Cu") (net 45))
  (segment (start 114.646058 113.360418) (end 114.685 113.35603) (width 0.109) (layer "In6.Cu") (net 45))
  (segment (start 114.505612 114.207911) (end 114.51 114.16897) (width 0.109) (layer "In6.Cu") (net 45))
  (segment (start 112.475889 113.39421) (end 112.50907 113.373361) (width 0.109) (layer "In6.Cu") (net 45))
  (segment (start 113.246058 113.360418) (end 113.285 113.35603) (width 0.109) (layer "In6.Cu") (net 45))
  (segment (start 124.5 100) (end 123.8 100) (width 0.109) (layer "In6.Cu") (net 45))
  (segment (start 115.035 113.85) (end 117.430003 113.85) (width 0.109) (layer "In6.Cu") (net 45))
  (segment (start 112.06 113.53103) (end 112.06 114.16897) (width 0.109) (layer "In6.Cu") (net 45))
  (segment (start 111.705612 114.207911) (end 111.71 114.16897) (width 0.109) (layer "In6.Cu") (net 45))
  (segment (start 112.660929 113.373361) (end 112.69411 113.39421) (width 0.109) (layer "In6.Cu") (net 45))
  (segment (start 111.923941 113.360418) (end 111.960929 113.373361) (width 0.109) (layer "In6.Cu") (net 45))
  (segment (start 123.15 103.48) (end 122.76 103.48) (width 0.109) (layer "In6.Cu") (net 45))
  (segment (start 111.355612 113.986058) (end 111.36 114.025) (width 0.109) (layer "In6.Cu") (net 45))
  (segment (start 114.864387 113.713942) (end 114.87733 113.75093) (width 0.109) (layer "In6.Cu") (net 45))
  (segment (start 113.148179 113.42192) (end 113.175889 113.39421) (width 0.109) (layer "In6.Cu") (net 45))
  (segment (start 93.947436 112.759011) (end 94.738425 113.55) (width 0.109) (layer "In6.Cu") (net 45))
  (segment (start 111.610929 114.326639) (end 111.64411 114.30579) (width 0.109) (layer "In6.Cu") (net 45))
  (segment (start 114.492669 114.244899) (end 114.505612 114.207911) (width 0.109) (layer "In6.Cu") (net 45))
  (segment (start 113.105612 114.207911) (end 113.11 114.16897) (width 0.109) (layer "In6.Cu") (net 45))
  (segment (start 124.7 100.504662) (end 124.7 100.2) (width 0.109) (layer "In6.Cu") (net 45))
  (segment (start 123.8 100) (end 123.525 100.275) (width 0.109) (layer "In6.Cu") (net 45))
  (segment (start 114.155612 113.492089) (end 114.16 113.53103) (width 0.109) (layer "In6.Cu") (net 45))
  (segment (start 121.884323 102.604323) (end 121.174323 102.604323) (width 0.109) (layer "In6.Cu") (net 45))
  (segment (start 114.225889 114.30579) (end 114.25907 114.326639) (width 0.109) (layer "In6.Cu") (net 45))
  (segment (start 113.07182 114.27808) (end 113.092669 114.244899) (width 0.109) (layer "In6.Cu") (net 45))
  (segment (start 114.164387 114.207911) (end 114.17733 114.244899) (width 0.109) (layer "In6.Cu") (net 45))
  (segment (start 112.585 113.35603) (end 112.623941 113.360418) (width 0.109) (layer "In6.Cu") (net 45))
  (segment (start 112.055612 113.492089) (end 112.06 113.53103) (width 0.109) (layer "In6.Cu") (net 45))
  (segment (start 113.455612 113.492089) (end 113.46 113.53103) (width 0.109) (layer "In6.Cu") (net 45))
  (segment (start 114.52733 113.455101) (end 114.548179 113.42192) (width 0.109) (layer "In6.Cu") (net 45))
  (segment (start 112.06 114.16897) (end 112.064387 114.207911) (width 0.109) (layer "In6.Cu") (net 45))
  (segment (start 112.742669 113.455101) (end 112.755612 113.492089) (width 0.109) (layer "In6.Cu") (net 45))
  (segment (start 123.5 105.43) (end 124.6 104.33) (width 0.109) (layer "In6.Cu") (net 45))
  (segment (start 112.098179 114.27808) (end 112.125889 114.30579) (width 0.109) (layer "In6.Cu") (net 45))
  (segment (start 111.775889 113.39421) (end 111.80907 113.373361) (width 0.109) (layer "In6.Cu") (net 45))
  (segment (start 117.430003 113.85) (end 120.718035 110.561968) (width 0.109) (layer "In6.Cu") (net 45))
  (segment (start 92.134875 112.425) (end 92.468886 112.759011) (width 0.109) (layer "In6.Cu") (net 45))
  (segment (start 112.064387 114.207911) (end 112.07733 114.244899) (width 0.109) (layer "In6.Cu") (net 45))
  (segment (start 113.42182 113.42192) (end 113.442669 113.455101) (width 0.109) (layer "In6.Cu") (net 45))
  (segment (start 112.973941 114.339582) (end 113.010929 114.326639) (width 0.109) (layer "In6.Cu") (net 45))
  (segment (start 114.16 114.16897) (end 114.164387 114.207911) (width 0.109) (layer "In6.Cu") (net 45))
  (segment (start 114.17733 114.244899) (end 114.198179 114.27808) (width 0.109) (layer "In6.Cu") (net 45))
  (segment (start 113.092669 114.244899) (end 113.105612 114.207911) (width 0.109) (layer "In6.Cu") (net 45))
  (segment (start 111.36 114.025) (end 111.36 114.16897) (width 0.109) (layer "In6.Cu") (net 45))
  (segment (start 113.464387 114.207911) (end 113.47733 114.244899) (width 0.109) (layer "In6.Cu") (net 45))
  (segment (start 114.51 114.16897) (end 114.51 113.53103) (width 0.109) (layer "In6.Cu") (net 45))
  (segment (start 112.392669 114.244899) (end 112.405612 114.207911) (width 0.109) (layer "In6.Cu") (net 45))
  (segment (start 112.42733 113.455101) (end 112.448179 113.42192) (width 0.109) (layer "In6.Cu") (net 45))
  (segment (start 124.6 101.98) (end 124.4 101.78) (width 0.109) (layer "In6.Cu") (net 45))
  (segment (start 113.498179 114.27808) (end 113.525889 114.30579) (width 0.109) (layer "In6.Cu") (net 45))
  (segment (start 103.05 113.55) (end 103.35 113.85) (width 0.109) (layer "In6.Cu") (net 45))
  (segment (start 112.69411 113.39421) (end 112.72182 113.42192) (width 0.109) (layer "In6.Cu") (net 45))
  (segment (start 114.685 113.35603) (end 114.723941 113.360418) (width 0.109) (layer "In6.Cu") (net 45))
  (segment (start 113.46 113.53103) (end 113.46 114.16897) (width 0.109) (layer "In6.Cu") (net 45))
  (segment (start 111.496058 114.339582) (end 111.535 114.34397) (width 0.109) (layer "In6.Cu") (net 45))
  (segment (start 112.37182 114.27808) (end 112.392669 114.244899) (width 0.109) (layer "In6.Cu") (net 45))
  (segment (start 113.805612 114.207911) (end 113.81 114.16897) (width 0.109) (layer "In6.Cu") (net 45))
  (segment (start 112.41 113.53103) (end 112.414387 113.492089) (width 0.109) (layer "In6.Cu") (net 45))
  (segment (start 114.198179 114.27808) (end 114.225889 114.30579) (width 0.109) (layer "In6.Cu") (net 45))
  (segment (start 114.87733 113.75093) (end 114.898179 113.784111) (width 0.109) (layer "In6.Cu") (net 45))
  (segment (start 111.260929 113.86733) (end 111.29411 113.888179) (width 0.109) (layer "In6.Cu") (net 45))
  (segment (start 113.010929 114.326639) (end 113.04411 114.30579) (width 0.109) (layer "In6.Cu") (net 45))
  (segment (start 112.125889 114.30579) (end 112.15907 114.326639) (width 0.109) (layer "In6.Cu") (net 45))
  (segment (start 111.36 114.16897) (end 111.364387 114.207911) (width 0.109) (layer "In6.Cu") (net 45))
  (segment (start 114.51 113.53103) (end 114.514387 113.492089) (width 0.109) (layer "In6.Cu") (net 45))
  (segment (start 90.956 112.425) (end 92.134875 112.425) (width 0.109) (layer "In6.Cu") (net 45))
  (segment (start 114.16 113.53103) (end 114.16 114.16897) (width 0.109) (layer "In6.Cu") (net 45))
  (segment (start 114.760929 113.373361) (end 114.79411 113.39421) (width 0.109) (layer "In6.Cu") (net 45))
  (segment (start 114.925889 113.811821) (end 114.95907 113.83267) (width 0.109) (layer "In6.Cu") (net 45))
  (segment (start 113.285 113.35603) (end 113.323941 113.360418) (width 0.109) (layer "In6.Cu") (net 45))
  (segment (start 114.296058 114.339582) (end 114.335 114.34397) (width 0.109) (layer "In6.Cu") (net 45))
  (segment (start 114.855612 113.492089) (end 114.86 113.53103) (width 0.109) (layer "In6.Cu") (net 45))
  (segment (start 112.310929 114.326639) (end 112.34411 114.30579) (width 0.109) (layer "In6.Cu") (net 45))
  (segment (start 123.525 100.275) (end 123.525 103.105) (width 0.109) (layer "In6.Cu") (net 45))
  (segment (start 111.398179 114.27808) (end 111.425889 114.30579) (width 0.109) (layer "In6.Cu") (net 45))
  (segment (start 113.11 114.16897) (end 113.11 113.53103) (width 0.109) (layer "In6.Cu") (net 45))
  (segment (start 113.985 113.35603) (end 114.023941 113.360418) (width 0.109) (layer "In6.Cu") (net 45))
  (segment (start 114.514387 113.492089) (end 114.52733 113.455101) (width 0.109) (layer "In6.Cu") (net 45))
  (segment (start 111.45907 114.326639) (end 111.496058 114.339582) (width 0.109) (layer "In6.Cu") (net 45))
  (segment (start 112.235 114.34397) (end 112.273941 114.339582) (width 0.109) (layer "In6.Cu") (net 45))
  (segment (start 122.45 105.43) (end 123.5 105.43) (width 0.109) (layer "In6.Cu") (net 45))
  (segment (start 113.710929 114.326639) (end 113.74411 114.30579) (width 0.109) (layer "In6.Cu") (net 45))
  (segment (start 114.82182 113.42192) (end 114.842669 113.455101) (width 0.109) (layer "In6.Cu") (net 45))
  (segment (start 114.86 113.675) (end 114.864387 113.713942) (width 0.109) (layer "In6.Cu") (net 45))
  (segment (start 111.32182 113.915889) (end 111.342669 113.94907) (width 0.109) (layer "In6.Cu") (net 45))
  (segment (start 94.738425 113.55) (end 103.05 113.55) (width 0.109) (layer "In6.Cu") (net 45))
  (segment (start 113.946058 113.360418) (end 113.985 113.35603) (width 0.109) (layer "In6.Cu") (net 45))
  (segment (start 114.575889 113.39421) (end 114.60907 113.373361) (width 0.109) (layer "In6.Cu") (net 45))
  (segment (start 114.023941 113.360418) (end 114.060929 113.373361) (width 0.109) (layer "In6.Cu") (net 45))
  (segment (start 113.875889 113.39421) (end 113.90907 113.373361) (width 0.109) (layer "In6.Cu") (net 45))
  (segment (start 120.718035 110.561968) (end 121.825 109.455) (width 0.109) (layer "In6.Cu") (net 45))
  (segment (start 111.185 113.85) (end 111.223941 113.854387) (width 0.109) (layer "In6.Cu") (net 45))
  (segment (start 114.47182 114.27808) (end 114.492669 114.244899) (width 0.109) (layer "In6.Cu") (net 45))
  (segment (start 112.196058 114.339582) (end 112.235 114.34397) (width 0.109) (layer "In6.Cu") (net 45))
  (segment (start 111.71 114.16897) (end 111.71 113.53103) (width 0.109) (layer "In6.Cu") (net 45))
  (segment (start 121.825 109.455) (end 121.825 106.055) (width 0.109) (layer "In6.Cu") (net 45))
  (segment (start 112.414387 113.492089) (end 112.42733 113.455101) (width 0.109) (layer "In6.Cu") (net 45))
  (segment (start 113.82733 113.455101) (end 113.848179 113.42192) (width 0.109) (layer "In6.Cu") (net 45))
  (segment (start 111.223941 113.854387) (end 111.260929 113.86733) (width 0.109) (layer "In6.Cu") (net 45))
  (segment (start 114.996058 113.845613) (end 115.035 113.85) (width 0.109) (layer "In6.Cu") (net 45))
  (segment (start 114.25907 114.326639) (end 114.296058 114.339582) (width 0.109) (layer "In6.Cu") (net 45))
  (segment (start 112.623941 113.360418) (end 112.660929 113.373361) (width 0.109) (layer "In6.Cu") (net 45))
  (segment (start 113.81 113.53103) (end 113.814387 113.492089) (width 0.109) (layer "In6.Cu") (net 45))
  (segment (start 114.09411 113.39421) (end 114.12182 113.42192) (width 0.109) (layer "In6.Cu") (net 45))
  (segment (start 111.535 114.34397) (end 111.573941 114.339582) (width 0.109) (layer "In6.Cu") (net 45))
  (segment (start 112.72182 113.42192) (end 112.742669 113.455101) (width 0.109) (layer "In6.Cu") (net 45))
  (segment (start 113.81 114.16897) (end 113.81 113.53103) (width 0.109) (layer "In6.Cu") (net 45))
  (segment (start 114.60907 113.373361) (end 114.646058 113.360418) (width 0.109) (layer "In6.Cu") (net 45))
  (segment (start 90.772 112.241) (end 90.956 112.425) (width 0.109) (layer "In6.Cu") (net 45))
  (segment (start 123.525 103.105) (end 123.15 103.48) (width 0.109) (layer "In6.Cu") (net 45))
  (segment (start 111.846058 113.360418) (end 111.885 113.35603) (width 0.109) (layer "In6.Cu") (net 45))
  (segment (start 114.44411 114.30579) (end 114.47182 114.27808) (width 0.109) (layer "In6.Cu") (net 45))
  (segment (start 122.76 103.48) (end 121.884323 102.604323) (width 0.109) (layer "In6.Cu") (net 45))
  (segment (start 114.335 114.34397) (end 114.373941 114.339582) (width 0.109) (layer "In6.Cu") (net 45))
  (segment (start 113.04411 114.30579) (end 113.07182 114.27808) (width 0.109) (layer "In6.Cu") (net 45))
  (segment (start 112.07733 114.244899) (end 112.098179 114.27808) (width 0.109) (layer "In6.Cu") (net 45))
  (segment (start 103.35 113.85) (end 111.185 113.85) (width 0.109) (layer "In6.Cu") (net 45))
  (segment (start 124.4 101.78) (end 124.4 100.804662) (width 0.109) (layer "In6.Cu") (net 45))
  (segment (start 111.72733 113.455101) (end 111.748179 113.42192) (width 0.109) (layer "In6.Cu") (net 45))
  (segment (start 112.41 114.16897) (end 112.41 113.53103) (width 0.109) (layer "In6.Cu") (net 45))
  (segment (start 114.373941 114.339582) (end 114.410929 114.326639) (width 0.109) (layer "In6.Cu") (net 45))
  (segment (start 111.37733 114.244899) (end 111.398179 114.27808) (width 0.109) (layer "In6.Cu") (net 45))
  (segment (start 112.546058 113.360418) (end 112.585 113.35603) (width 0.109) (layer "In6.Cu") (net 45))
  (segment (start 111.64411 114.30579) (end 111.67182 114.27808) (width 0.109) (layer "In6.Cu") (net 45))
  (segment (start 113.596058 114.339582) (end 113.635 114.34397) (width 0.109) (layer "In6.Cu") (net 45))
  (segment (start 114.548179 113.42192) (end 114.575889 113.39421) (width 0.109) (layer "In6.Cu") (net 45))
  (segment (start 111.71 113.53103) (end 111.714387 113.492089) (width 0.109) (layer "In6.Cu") (net 45))
  (segment (start 114.79411 113.39421) (end 114.82182 113.42192) (width 0.109) (layer "In6.Cu") (net 45))
  (segment (start 113.46 114.16897) (end 113.464387 114.207911) (width 0.109) (layer "In6.Cu") (net 45))
  (segment (start 112.34411 114.30579) (end 112.37182 114.27808) (width 0.109) (layer "In6.Cu") (net 45))
  (segment (start 111.692669 114.244899) (end 111.705612 114.207911) (width 0.109) (layer "In6.Cu") (net 45))
  (segment (start 90.772 111.688) (end 90.772 112.241) (width 0.109) (layer "In6.Cu") (net 45))
  (segment (start 113.360929 113.373361) (end 113.39411 113.39421) (width 0.109) (layer "In6.Cu") (net 45))
  (segment (start 111.67182 114.27808) (end 111.692669 114.244899) (width 0.109) (layer "In6.Cu") (net 45))
  (segment (start 112.448179 113.42192) (end 112.475889 113.39421) (width 0.109) (layer "In6.Cu") (net 45))
  (segment (start 91.1715 111.2885) (end 90.772 111.688) (width 0.109) (layer "In6.Cu") (net 45))
  (segment (start 111.364387 114.207911) (end 111.37733 114.244899) (width 0.109) (layer "In6.Cu") (net 45))
  (segment (start 114.410929 114.326639) (end 114.44411 114.30579) (width 0.109) (layer "In6.Cu") (net 45))
  (segment (start 113.525889 114.30579) (end 113.55907 114.326639) (width 0.109) (layer "In6.Cu") (net 45))
  (segment (start 111.342669 113.94907) (end 111.355612 113.986058) (width 0.109) (layer "In6.Cu") (net 45))
  (segment (start 91.1715 111.278999) (end 91.1715 111.2885) (width 0.109) (layer "In6.Cu") (net 45))
  (segment (start 114.898179 113.784111) (end 114.925889 113.811821) (width 0.109) (layer "In6.Cu") (net 45))
  (segment (start 92.468886 112.759011) (end 93.947436 112.759011) (width 0.109) (layer "In6.Cu") (net 45))
  (segment (start 112.405612 114.207911) (end 112.41 114.16897) (width 0.109) (layer "In6.Cu") (net 45))
  (segment (start 111.885 113.35603) (end 111.923941 113.360418) (width 0.109) (layer "In6.Cu") (net 45))
  (segment (start 113.114387 113.492089) (end 113.12733 113.455101) (width 0.109) (layer "In6.Cu") (net 45))
  (segment (start 124.4 100.804662) (end 124.7 100.504662) (width 0.109) (layer "In6.Cu") (net 45))
  (segment (start 112.76 113.53103) (end 112.76 114.16897) (width 0.109) (layer "In6.Cu") (net 45))
  (segment (start 113.814387 113.492089) (end 113.82733 113.455101) (width 0.109) (layer "In6.Cu") (net 45))
  (segment (start 112.76 114.16897) (end 112.764387 114.207911) (width 0.109) (layer "In6.Cu") (net 45))
  (segment (start 111.960929 113.373361) (end 111.99411 113.39421) (width 0.109) (layer "In6.Cu") (net 45))
  (segment (start 112.896058 114.339582) (end 112.935 114.34397) (width 0.109) (layer "In6.Cu") (net 45))
  (segment (start 113.77182 114.27808) (end 113.792669 114.244899) (width 0.109) (layer "In6.Cu") (net 45))
  (segment (start 111.99411 113.39421) (end 112.02182 113.42192) (width 0.109) (layer "In6.Cu") (net 45))
  (segment (start 112.02182 113.42192) (end 112.042669 113.455101) (width 0.109) (layer "In6.Cu") (net 45))
  (segment (start 113.792669 114.244899) (end 113.805612 114.207911) (width 0.109) (layer "In6.Cu") (net 45))
  (segment (start 114.142669 113.455101) (end 114.155612 113.492089) (width 0.109) (layer "In6.Cu") (net 45))
  (segment (start 113.74411 114.30579) (end 113.77182 114.27808) (width 0.109) (layer "In6.Cu") (net 45))
  (segment (start 114.060929 113.373361) (end 114.09411 113.39421) (width 0.109) (layer "In6.Cu") (net 45))
  (segment (start 112.935 114.34397) (end 112.973941 114.339582) (width 0.109) (layer "In6.Cu") (net 45))
  (segment (start 111.714387 113.492089) (end 111.72733 113.455101) (width 0.109) (layer "In6.Cu") (net 45))
  (segment (start 124.7 100.2) (end 124.5 100) (width 0.109) (layer "In6.Cu") (net 45))
  (segment (start 113.442669 113.455101) (end 113.455612 113.492089) (width 0.109) (layer "In6.Cu") (net 45))
  (segment (start 113.11 113.53103) (end 113.114387 113.492089) (width 0.109) (layer "In6.Cu") (net 45))
  (segment (start 112.042669 113.455101) (end 112.055612 113.492089) (width 0.109) (layer "In6.Cu") (net 45))
  (segment (start 112.273941 114.339582) (end 112.310929 114.326639) (width 0.109) (layer "In6.Cu") (net 45))
  (segment (start 111.29411 113.888179) (end 111.32182 113.915889) (width 0.109) (layer "In6.Cu") (net 45))
  (segment (start 114.95907 113.83267) (end 114.996058 113.845613) (width 0.109) (layer "In6.Cu") (net 45))
  (segment (start 113.673941 114.339582) (end 113.710929 114.326639) (width 0.109) (layer "In6.Cu") (net 45))
  (segment (start 114.723941 113.360418) (end 114.760929 113.373361) (width 0.109) (layer "In6.Cu") (net 45))
  (segment (start 112.755612 113.492089) (end 112.76 113.53103) (width 0.109) (layer "In6.Cu") (net 45))
  (segment (start 111.425889 114.30579) (end 111.45907 114.326639) (width 0.109) (layer "In6.Cu") (net 45))
  (segment (start 114.842669 113.455101) (end 114.855612 113.492089) (width 0.109) (layer "In6.Cu") (net 45))
  (segment (start 111.573941 114.339582) (end 111.610929 114.326639) (width 0.109) (layer "In6.Cu") (net 45))
  (segment (start 114.86 113.53103) (end 114.86 113.675) (width 0.109) (layer "In6.Cu") (net 45))
  (segment (start 116.836689 99.491) (end 116.734883 99.389194) (width 0.182) (layer "F.Cu") (net 46))
  (segment (start 89.8265 114.129) (end 90.3 113.815) (width 0.182) (layer "F.Cu") (net 46))
  (segment (start 119.1829 99.491) (end 116.836689 99.491) (width 0.182) (layer "F.Cu") (net 46))
  (via (at 90.3 113.815) (size 0.45) (drill 0.1) (layers "F.Cu" "B.Cu") (net 46))
  (via (at 116.734883 99.389194) (size 0.45) (drill 0.1) (layers "F.Cu" "B.Cu") (net 46))
  (segment (start 106.135 108.173536) (end 106.139387 108.212477) (width 0.109) (layer "In6.Cu") (net 46))
  (segment (start 105.88407 107.468795) (end 105.921058 107.455852) (width 0.109) (layer "In6.Cu") (net 46))
  (segment (start 101.235 108.173536) (end 101.239387 108.212477) (width 0.109) (layer "In6.Cu") (net 46))
  (segment (start 105.998941 107.455852) (end 106.035929 107.468795) (width 0.109) (layer "In6.Cu") (net 46))
  (segment (start 100.517669 107.550535) (end 100.530612 107.587523) (width 0.109) (layer "In6.Cu") (net 46))
  (segment (start 100.950889 107.489644) (end 100.98407 107.468795) (width 0.109) (layer "In6.Cu") (net 46))
  (segment (start 116.200006 99.924071) (end 116.734883 99.389194) (width 0.109) (layer "In6.Cu") (net 46))
  (segment (start 99.58407 107.468795) (end 99.621058 107.455852) (width 0.109) (layer "In6.Cu") (net 46))
  (segment (start 101.230612 107.587523) (end 101.235 107.626464) (width 0.109) (layer "In6.Cu") (net 46))
  (segment (start 100.880612 108.212477) (end 100.885 108.173536) (width 0.109) (layer "In6.Cu") (net 46))
  (segment (start 103.330612 107.587523) (end 103.335 107.626464) (width 0.109) (layer "In6.Cu") (net 46))
  (segment (start 105.473179 108.282646) (end 105.500889 108.310356) (width 0.109) (layer "In6.Cu") (net 46))
  (segment (start 102.24682 108.282646) (end 102.267669 108.249465) (width 0.109) (layer "In6.Cu") (net 46))
  (segment (start 105.39682 107.517354) (end 105.417669 107.550535) (width 0.109) (layer "In6.Cu") (net 46))
  (segment (start 101.19682 107.517354) (end 101.217669 107.550535) (width 0.109) (layer "In6.Cu") (net 46))
  (segment (start 98.921058 107.455852) (end 98.96 107.451464) (width 0.109) (layer "In6.Cu") (net 46))
  (segment (start 103.43407 108.331205) (end 103.471058 108.344148) (width 0.109) (layer "In6.Cu") (net 46))
  (segment (start 105.439387 108.212477) (end 105.45233 108.249465) (width 0.109) (layer "In6.Cu") (net 46))
  (segment (start 100.189387 107.587523) (end 100.20233 107.550535) (width 0.109) (layer "In6.Cu") (net 46))
  (segment (start 104.635929 107.468795) (end 104.66911 107.489644) (width 0.109) (layer "In6.Cu") (net 46))
  (segment (start 103.86 107.451464) (end 103.898941 107.455852) (width 0.109) (layer "In6.Cu") (net 46))
  (segment (start 97.800889 108.310356) (end 97.83407 108.331205) (width 0.109) (layer "In6.Cu") (net 46))
  (segment (start 98.61 108.348536) (end 98.648941 108.344148) (width 0.109) (layer "In6.Cu") (net 46))
  (segment (start 106.200889 108.310356) (end 106.23407 108.331205) (width 0.109) (layer "In6.Cu") (net 46))
  (segment (start 102.635 108.173536) (end 102.639387 108.212477) (width 0.109) (layer "In6.Cu") (net 46))
  (segment (start 100.223179 107.517354) (end 100.250889 107.489644) (width 0.109) (layer "In6.Cu") (net 46))
  (segment (start 104.13407 108.331205) (end 104.171058 108.344148) (width 0.109) (layer "In6.Cu") (net 46))
  (segment (start 99.817669 107.550535) (end 99.830612 107.587523) (width 0.109) (layer "In6.Cu") (net 46))
  (segment (start 103.198941 107.455852) (end 103.235929 107.468795) (width 0.109) (layer "In6.Cu") (net 46))
  (segment (start 106.485 108.075) (end 106.489387 108.036058) (width 0.109) (layer "In6.Cu") (net 46))
  (segment (start 97.948941 108.344148) (end 97.985929 108.331205) (width 0.109) (layer "In6.Cu") (net 46))
  (segment (start 100.923179 107.517354) (end 100.950889 107.489644) (width 0.109) (layer "In6.Cu") (net 46))
  (segment (start 103.339387 108.212477) (end 103.35233 108.249465) (width 0.109) (layer "In6.Cu") (net 46))
  (segment (start 106.489387 108.036058) (end 106.50233 107.99907) (width 0.109) (layer "In6.Cu") (net 46))
  (segment (start 97.31911 108.310356) (end 97.34682 108.282646) (width 0.109) (layer "In6.Cu") (net 46))
  (segment (start 100.90233 107.550535) (end 100.923179 107.517354) (width 0.109) (layer "In6.Cu") (net 46))
  (segment (start 103.898941 107.455852) (end 103.935929 107.468795) (width 0.109) (layer "In6.Cu") (net 46))
  (segment (start 101.300889 108.310356) (end 101.33407 108.331205) (width 0.109) (layer "In6.Cu") (net 46))
  (segment (start 105.04682 108.282646) (end 105.067669 108.249465) (width 0.109) (layer "In6.Cu") (net 46))
  (segment (start 105.80233 107.550535) (end 105.823179 107.517354) (width 0.109) (layer "In6.Cu") (net 46))
  (segment (start 104.800889 108.310356) (end 104.83407 108.331205) (width 0.109) (layer "In6.Cu") (net 46))
  (segment (start 100.573179 108.282646) (end 100.600889 108.310356) (width 0.109) (layer "In6.Cu") (net 46))
  (segment (start 98.417669 107.550535) (end 98.430612 107.587523) (width 0.109) (layer "In6.Cu") (net 46))
  (segment (start 89.216 112.516) (end 88.9 112.2) (width 0.109) (layer "In6.Cu") (net 46))
  (segment (start 106.139387 108.212477) (end 106.15233 108.249465) (width 0.109) (layer "In6.Cu") (net 46))
  (segment (start 105.785 108.173536) (end 105.785 107.626464) (width 0.109) (layer "In6.Cu") (net 46))
  (segment (start 102.91911 108.310356) (end 102.94682 108.282646) (width 0.109) (layer "In6.Cu") (net 46))
  (segment (start 104.21 108.348536) (end 104.248941 108.344148) (width 0.109) (layer "In6.Cu") (net 46))
  (segment (start 98.473179 108.282646) (end 98.500889 108.310356) (width 0.109) (layer "In6.Cu") (net 46))
  (segment (start 105.36911 107.489644) (end 105.39682 107.517354) (width 0.109) (layer "In6.Cu") (net 46))
  (segment (start 101.06 107.451464) (end 101.098941 107.455852) (width 0.109) (layer "In6.Cu") (net 46))
  (segment (start 104.735 107.626464) (end 104.735 108.173536) (width 0.109) (layer "In6.Cu") (net 46))
  (segment (start 99.485 108.173536) (end 99.485 107.626464) (width 0.109) (layer "In6.Cu") (net 46))
  (segment (start 94.225 110.010499) (end 96.335499 107.9) (width 0.109) (layer "In6.Cu") (net 46))
  (segment (start 105.080612 108.212477) (end 105.085 108.173536) (width 0.109) (layer "In6.Cu") (net 46))
  (segment (start 102.071058 108.344148) (end 102.11 108.348536) (width 0.109) (layer "In6.Cu") (net 46))
  (segment (start 97.21 108.348536) (end 97.248941 108.344148) (width 0.109) (layer "In6.Cu") (net 46))
  (segment (start 100.28407 107.468795) (end 100.321058 107.455852) (width 0.109) (layer "In6.Cu") (net 46))
  (segment (start 100.539387 108.212477) (end 100.55233 108.249465) (width 0.109) (layer "In6.Cu") (net 46))
  (segment (start 106.348941 108.344148) (end 106.385929 108.331205) (width 0.109) (layer "In6.Cu") (net 46))
  (segment (start 97.248941 108.344148) (end 97.285929 108.331205) (width 0.109) (layer "In6.Cu") (net 46))
  (segment (start 96.99682 107.965889) (end 97.017669 107.99907) (width 0.109) (layer "In6.Cu") (net 46))
  (segment (start 101.60233 107.550535) (end 101.623179 107.517354) (width 0.109) (layer "In6.Cu") (net 46))
  (segment (start 103.29682 107.517354) (end 103.317669 107.550535) (width 0.109) (layer "In6.Cu") (net 46))
  (segment (start 103.023179 107.517354) (end 103.050889 107.489644) (width 0.109) (layer "In6.Cu") (net 46))
  (segment (start 97.389387 107.587523) (end 97.40233 107.550535) (width 0.109) (layer "In6.Cu") (net 46))
  (segment (start 105.067669 108.249465) (end 105.080612 108.212477) (width 0.109) (layer "In6.Cu") (net 46))
  (segment (start 99.621058 107.455852) (end 99.66 107.451464) (width 0.109) (layer "In6.Cu") (net 46))
  (segment (start 102.285 108.173536) (end 102.285 107.626464) (width 0.109) (layer "In6.Cu") (net 46))
  (segment (start 98.998941 107.455852) (end 99.035929 107.468795) (width 0.109) (layer "In6.Cu") (net 46))
  (segment (start 105.26 107.451464) (end 105.298941 107.455852) (width 0.109) (layer "In6.Cu") (net 46))
  (segment (start 97.05233 108.249465) (end 97.073179 108.282646) (width 0.109) (layer "In6.Cu") (net 46))
  (segment (start 97.40233 107.550535) (end 97.423179 107.517354) (width 0.109) (layer "In6.Cu") (net 46))
  (segment (start 90.3 113.815) (end 90.485 113.815) (width 0.109) (layer "In6.Cu") (net 46))
  (segment (start 98.080612 108.212477) (end 98.085 108.173536) (width 0.109) (layer "In6.Cu") (net 46))
  (segment (start 97.66911 107.489644) (end 97.69682 107.517354) (width 0.109) (layer "In6.Cu") (net 46))
  (segment (start 103.400889 108.310356) (end 103.43407 108.331205) (width 0.109) (layer "In6.Cu") (net 46))
  (segment (start 96.335499 107.9) (end 96.86 107.9) (width 0.109) (layer "In6.Cu") (net 46))
  (segment (start 103.26911 107.489644) (end 103.29682 107.517354) (width 0.109) (layer "In6.Cu") (net 46))
  (segment (start 104.450889 107.489644) (end 104.48407 107.468795) (width 0.109) (layer "In6.Cu") (net 46))
  (segment (start 106.31 108.348536) (end 106.348941 108.344148) (width 0.109) (layer "In6.Cu") (net 46))
  (segment (start 102.535929 107.468795) (end 102.56911 107.489644) (width 0.109) (layer "In6.Cu") (net 46))
  (segment (start 106.173179 108.282646) (end 106.200889 108.310356) (width 0.109) (layer "In6.Cu") (net 46))
  (segment (start 105.18407 107.468795) (end 105.221058 107.455852) (width 0.109) (layer "In6.Cu") (net 46))
  (segment (start 104.017669 107.550535) (end 104.030612 107.587523) (width 0.109) (layer "In6.Cu") (net 46))
  (segment (start 99.348941 108.344148) (end 99.385929 108.331205) (width 0.109) (layer "In6.Cu") (net 46))
  (segment (start 88.9 111.025) (end 89.352489 110.572511) (width 0.109) (layer "In6.Cu") (net 46))
  (segment (start 105.221058 107.455852) (end 105.26 107.451464) (width 0.109) (layer "In6.Cu") (net 46))
  (segment (start 102.000889 108.310356) (end 102.03407 108.331205) (width 0.109) (layer "In6.Cu") (net 46))
  (segment (start 100.49682 107.517354) (end 100.517669 107.550535) (width 0.109) (layer "In6.Cu") (net 46))
  (segment (start 106.50233 107.99907) (end 106.523179 107.965889) (width 0.109) (layer "In6.Cu") (net 46))
  (segment (start 99.130612 107.587523) (end 99.135 107.626464) (width 0.109) (layer "In6.Cu") (net 46))
  (segment (start 102.967669 108.249465) (end 102.980612 108.212477) (width 0.109) (layer "In6.Cu") (net 46))
  (segment (start 100.55233 108.249465) (end 100.573179 108.282646) (width 0.109) (layer "In6.Cu") (net 46))
  (segment (start 92.194414 110.45) (end 93.95 110.45) (width 0.109) (layer "In6.Cu") (net 46))
  (segment (start 99.79682 107.517354) (end 99.817669 107.550535) (width 0.109) (layer "In6.Cu") (net 46))
  (segment (start 99.830612 107.587523) (end 99.835 107.626464) (width 0.109) (layer "In6.Cu") (net 46))
  (segment (start 98.780612 108.212477) (end 98.785 108.173536) (width 0.109) (layer "In6.Cu") (net 46))
  (segment (start 99.135 107.626464) (end 99.135 108.173536) (width 0.109) (layer "In6.Cu") (net 46))
  (segment (start 99.76911 107.489644) (end 99.79682 107.517354) (width 0.109) (layer "In6.Cu") (net 46))
  (segment (start 90.75 113.082) (end 90.184 112.516) (width 0.109) (layer "In6.Cu") (net 46))
  (segment (start 104.948941 108.344148) (end 104.985929 108.331205) (width 0.109) (layer "In6.Cu") (net 46))
  (segment (start 99.271058 108.344148) (end 99.31 108.348536) (width 0.109) (layer "In6.Cu") (net 46))
  (segment (start 97.635929 107.468795) (end 97.66911 107.489644) (width 0.109) (layer "In6.Cu") (net 46))
  (segment (start 102.635 107.626464) (end 102.635 108.173536) (width 0.109) (layer "In6.Cu") (net 46))
  (segment (start 98.439387 108.212477) (end 98.45233 108.249465) (width 0.109) (layer "In6.Cu") (net 46))
  (segment (start 103.235929 107.468795) (end 103.26911 107.489644) (width 0.109) (layer "In6.Cu") (net 46))
  (segment (start 102.885929 108.331205) (end 102.91911 108.310356) (width 0.109) (layer "In6.Cu") (net 46))
  (segment (start 106.485 108.173536) (end 106.485 108.075) (width 0.109) (layer "In6.Cu") (net 46))
  (segment (start 98.785 107.626464) (end 98.789387 107.587523) (width 0.109) (layer "In6.Cu") (net 46))
  (segment (start 116.2 101.84) (end 116.2 99.924071) (width 0.109) (layer "In6.Cu") (net 46))
  (segment (start 102.81 108.348536) (end 102.848941 108.344148) (width 0.109) (layer "In6.Cu") (net 46))
  (segment (start 102.185929 108.331205) (end 102.21911 108.310356) (width 0.109) (layer "In6.Cu") (net 46))
  (segment (start 98.150889 107.489644) (end 98.18407 107.468795) (width 0.109) (layer "In6.Cu") (net 46))
  (segment (start 103.821058 107.455852) (end 103.86 107.451464) (width 0.109) (layer "In6.Cu") (net 46))
  (segment (start 104.66911 107.489644) (end 104.69682 107.517354) (width 0.109) (layer "In6.Cu") (net 46))
  (segment (start 103.51 108.348536) (end 103.548941 108.344148) (width 0.109) (layer "In6.Cu") (net 46))
  (segment (start 99.839387 108.212477) (end 99.85233 108.249465) (width 0.109) (layer "In6.Cu") (net 46))
  (segment (start 104.380612 108.212477) (end 104.385 108.173536) (width 0.109) (layer "In6.Cu") (net 46))
  (segment (start 105.648941 108.344148) (end 105.685929 108.331205) (width 0.109) (layer "In6.Cu") (net 46))
  (segment (start 97.423179 107.517354) (end 97.450889 107.489644) (width 0.109) (layer "In6.Cu") (net 46))
  (segment (start 100.398941 107.455852) (end 100.435929 107.468795) (width 0.109) (layer "In6.Cu") (net 46))
  (segment (start 100.885 108.173536) (end 100.885 107.626464) (width 0.109) (layer "In6.Cu") (net 46))
  (segment (start 98.500889 108.310356) (end 98.53407 108.331205) (width 0.109) (layer "In6.Cu") (net 46))
  (segment (start 101.021058 107.455852) (end 101.06 107.451464) (width 0.109) (layer "In6.Cu") (net 46))
  (segment (start 101.25233 108.249465) (end 101.273179 108.282646) (width 0.109) (layer "In6.Cu") (net 46))
  (segment (start 97.521058 107.455852) (end 97.56 107.451464) (width 0.109) (layer "In6.Cu") (net 46))
  (segment (start 104.69682 107.517354) (end 104.717669 107.550535) (width 0.109) (layer "In6.Cu") (net 46))
  (segment (start 99.66 107.451464) (end 99.698941 107.455852) (width 0.109) (layer "In6.Cu") (net 46))
  (segment (start 99.035929 107.468795) (end 99.06911 107.489644) (width 0.109) (layer "In6.Cu") (net 46))
  (segment (start 98.435 108.173536) (end 98.439387 108.212477) (width 0.109) (layer "In6.Cu") (net 46))
  (segment (start 99.93407 108.331205) (end 99.971058 108.344148) (width 0.109) (layer "In6.Cu") (net 46))
  (segment (start 96.86 107.9) (end 96.898941 107.904387) (width 0.109) (layer "In6.Cu") (net 46))
  (segment (start 103.585929 108.331205) (end 103.61911 108.310356) (width 0.109) (layer "In6.Cu") (net 46))
  (segment (start 100.889387 107.587523) (end 100.90233 107.550535) (width 0.109) (layer "In6.Cu") (net 46))
  (segment (start 97.56 107.451464) (end 97.598941 107.455852) (width 0.109) (layer "In6.Cu") (net 46))
  (segment (start 103.96911 107.489644) (end 103.99682 107.517354) (width 0.109) (layer "In6.Cu") (net 46))
  (segment (start 102.848941 108.344148) (end 102.885929 108.331205) (width 0.109) (layer "In6.Cu") (net 46))
  (segment (start 99.735929 107.468795) (end 99.76911 107.489644) (width 0.109) (layer "In6.Cu") (net 46))
  (segment (start 98.850889 107.489644) (end 98.88407 107.468795) (width 0.109) (layer "In6.Cu") (net 46))
  (segment (start 97.285929 108.331205) (end 97.31911 108.310356) (width 0.109) (layer "In6.Cu") (net 46))
  (segment (start 101.567669 108.249465) (end 101.580612 108.212477) (width 0.109) (layer "In6.Cu") (net 46))
  (segment (start 96.96911 107.938179) (end 96.99682 107.965889) (width 0.109) (layer "In6.Cu") (net 46))
  (segment (start 100.36 107.451464) (end 100.398941 107.455852) (width 0.109) (layer "In6.Cu") (net 46))
  (segment (start 103.689387 107.587523) (end 103.70233 107.550535) (width 0.109) (layer "In6.Cu") (net 46))
  (segment (start 105.123179 107.517354) (end 105.150889 107.489644) (width 0.109) (layer "In6.Cu") (net 46))
  (segment (start 99.31 108.348536) (end 99.348941 108.344148) (width 0.109) (layer "In6.Cu") (net 46))
  (segment (start 100.180612 108.212477) (end 100.185 108.173536) (width 0.109) (layer "In6.Cu") (net 46))
  (segment (start 98.298941 107.455852) (end 98.335929 107.468795) (width 0.109) (layer "In6.Cu") (net 46))
  (segment (start 98.04682 108.282646) (end 98.067669 108.249465) (width 0.109) (layer "In6.Cu") (net 46))
  (segment (start 97.730612 107.587523) (end 97.735 107.626464) (width 0.109) (layer "In6.Cu") (net 46))
  (segment (start 101.935 107.626464) (end 101.935 108.173536) (width 0.109) (layer "In6.Cu") (net 46))
  (segment (start 105.780612 108.212477) (end 105.785 108.173536) (width 0.109) (layer "In6.Cu") (net 46))
  (segment (start 100.785929 108.331205) (end 100.81911 108.310356) (width 0.109) (layer "In6.Cu") (net 46))
  (segment (start 101.33407 108.331205) (end 101.371058 108.344148) (width 0.109) (layer "In6.Cu") (net 46))
  (segment (start 106.621058 107.904387) (end 106.66 107.9) (width 0.109) (layer "In6.Cu") (net 46))
  (segment (start 100.530612 107.587523) (end 100.535 107.626464) (width 0.109) (layer "In6.Cu") (net 46))
  (segment (start 101.589387 107.587523) (end 101.60233 107.550535) (width 0.109) (layer "In6.Cu") (net 46))
  (segment (start 101.95233 108.249465) (end 101.973179 108.282646) (width 0.109) (layer "In6.Cu") (net 46))
  (segment (start 100.885 107.626464) (end 100.889387 107.587523) (width 0.109) (layer "In6.Cu") (net 46))
  (segment (start 104.75233 108.249465) (end 104.773179 108.282646) (width 0.109) (layer "In6.Cu") (net 46))
  (segment (start 97.035 108.075) (end 97.035 108.173536) (width 0.109) (layer "In6.Cu") (net 46))
  (segment (start 101.217669 107.550535) (end 101.230612 107.587523) (width 0.109) (layer "In6.Cu") (net 46))
  (segment (start 105.150889 107.489644) (end 105.18407 107.468795) (width 0.109) (layer "In6.Cu") (net 46))
  (segment (start 105.085 107.626464) (end 105.089387 107.587523) (width 0.109) (layer "In6.Cu") (net 46))
  (segment (start 100.535 108.173536) (end 100.539387 108.212477) (width 0.109) (layer "In6.Cu") (net 46))
  (segment (start 98.789387 107.587523) (end 98.80233 107.550535) (width 0.109) (layer "In6.Cu") (net 46))
  (segment (start 99.85233 108.249465) (end 99.873179 108.282646) (width 0.109) (layer "In6.Cu") (net 46))
  (segment (start 90.485 113.815) (end 90.75 113.55) (width 0.109) (layer "In6.Cu") (net 46))
  (segment (start 97.735 107.626464) (end 97.735 108.173536) (width 0.109) (layer "In6.Cu") (net 46))
  (segment (start 101.68407 107.468795) (end 101.721058 107.455852) (width 0.109) (layer "In6.Cu") (net 46))
  (segment (start 106.523179 107.965889) (end 106.550889 107.938179) (width 0.109) (layer "In6.Cu") (net 46))
  (segment (start 104.83407 108.331205) (end 104.871058 108.344148) (width 0.109) (layer "In6.Cu") (net 46))
  (segment (start 98.685929 108.331205) (end 98.71911 108.310356) (width 0.109) (layer "In6.Cu") (net 46))
  (segment (start 98.88407 107.468795) (end 98.921058 107.455852) (width 0.109) (layer "In6.Cu") (net 46))
  (segment (start 98.085 108.173536) (end 98.085 107.626464) (width 0.109) (layer "In6.Cu") (net 46))
  (segment (start 105.500889 108.310356) (end 105.53407 108.331205) (width 0.109) (layer "In6.Cu") (net 46))
  (segment (start 116.9 102.54) (end 116.2 101.84) (width 0.109) (layer "In6.Cu") (net 46))
  (segment (start 102.148941 108.344148) (end 102.185929 108.331205) (width 0.109) (layer "In6.Cu") (net 46))
  (segment (start 103.685 108.173536) (end 103.685 107.626464) (width 0.109) (layer "In6.Cu") (net 46))
  (segment (start 102.700889 108.310356) (end 102.73407 108.331205) (width 0.109) (layer "In6.Cu") (net 46))
  (segment (start 105.335929 107.468795) (end 105.36911 107.489644) (width 0.109) (layer "In6.Cu") (net 46))
  (segment (start 106.385929 108.331205) (end 106.41911 108.310356) (width 0.109) (layer "In6.Cu") (net 46))
  (segment (start 98.067669 108.249465) (end 98.080612 108.212477) (width 0.109) (layer "In6.Cu") (net 46))
  (segment (start 100.535 107.626464) (end 100.535 108.173536) (width 0.109) (layer "In6.Cu") (net 46))
  (segment (start 103.723179 107.517354) (end 103.750889 107.489644) (width 0.109) (layer "In6.Cu") (net 46))
  (segment (start 103.935929 107.468795) (end 103.96911 107.489644) (width 0.109) (layer "In6.Cu") (net 46))
  (segment (start 99.900889 108.310356) (end 99.93407 108.331205) (width 0.109) (layer "In6.Cu") (net 46))
  (segment (start 97.450889 107.489644) (end 97.48407 107.468795) (width 0.109) (layer "In6.Cu") (net 46))
  (segment (start 104.385 107.626464) (end 104.389387 107.587523) (width 0.109) (layer "In6.Cu") (net 46))
  (segment (start 103.00233 107.550535) (end 103.023179 107.517354) (width 0.109) (layer "In6.Cu") (net 46))
  (segment (start 99.09682 107.517354) (end 99.117669 107.550535) (width 0.109) (layer "In6.Cu") (net 46))
  (segment (start 98.96 107.451464) (end 98.998941 107.455852) (width 0.109) (layer "In6.Cu") (net 46))
  (segment (start 100.20233 107.550535) (end 100.223179 107.517354) (width 0.109) (layer "In6.Cu") (net 46))
  (segment (start 105.789387 107.587523) (end 105.80233 107.550535) (width 0.109) (layer "In6.Cu") (net 46))
  (segment (start 99.117669 107.550535) (end 99.130612 107.587523) (width 0.109) (layer "In6.Cu") (net 46))
  (segment (start 97.717669 107.550535) (end 97.730612 107.587523) (width 0.109) (layer "In6.Cu") (net 46))
  (segment (start 104.56 107.451464) (end 104.598941 107.455852) (width 0.109) (layer "In6.Cu") (net 46))
  (segment (start 102.639387 108.212477) (end 102.65233 108.249465) (width 0.109) (layer "In6.Cu") (net 46))
  (segment (start 98.74682 108.282646) (end 98.767669 108.249465) (width 0.109) (layer "In6.Cu") (net 46))
  (segment (start 98.767669 108.249465) (end 98.780612 108.212477) (width 0.109) (layer "In6.Cu") (net 46))
  (segment (start 104.030612 107.587523) (end 104.035 107.626464) (width 0.109) (layer "In6.Cu") (net 46))
  (segment (start 102.350889 107.489644) (end 102.38407 107.468795) (width 0.109) (layer "In6.Cu") (net 46))
  (segment (start 102.11 108.348536) (end 102.148941 108.344148) (width 0.109) (layer "In6.Cu") (net 46))
  (segment (start 97.83407 108.331205) (end 97.871058 108.344148) (width 0.109) (layer "In6.Cu") (net 46))
  (segment (start 101.930612 107.587523) (end 101.935 107.626464) (width 0.109) (layer "In6.Cu") (net 46))
  (segment (start 97.171058 108.344148) (end 97.21 108.348536) (width 0.109) (layer "In6.Cu") (net 46))
  (segment (start 99.41911 108.310356) (end 99.44682 108.282646) (width 0.109) (layer "In6.Cu") (net 46))
  (segment (start 104.773179 108.282646) (end 104.800889 108.310356) (width 0.109) (layer "In6.Cu") (net 46))
  (segment (start 105.823179 107.517354) (end 105.850889 107.489644) (width 0.109) (layer "In6.Cu") (net 46))
  (segment (start 104.389387 107.587523) (end 104.40233 107.550535) (width 0.109) (layer "In6.Cu") (net 46))
  (segment (start 99.06911 107.489644) (end 99.09682 107.517354) (width 0.109) (layer "In6.Cu") (net 46))
  (segment (start 101.54682 108.282646) (end 101.567669 108.249465) (width 0.109) (layer "In6.Cu") (net 46))
  (segment (start 103.667669 108.249465) (end 103.680612 108.212477) (width 0.109) (layer "In6.Cu") (net 46))
  (segment (start 103.680612 108.212477) (end 103.685 108.173536) (width 0.109) (layer "In6.Cu") (net 46))
  (segment (start 98.01911 108.310356) (end 98.04682 108.282646) (width 0.109) (layer "In6.Cu") (net 46))
  (segment (start 99.173179 108.282646) (end 99.200889 108.310356) (width 0.109) (layer "In6.Cu") (net 46))
  (segment (start 100.250889 107.489644) (end 100.28407 107.468795) (width 0.109) (layer "In6.Cu") (net 46))
  (segment (start 98.089387 107.587523) (end 98.10233 107.550535) (width 0.109) (layer "In6.Cu") (net 46))
  (segment (start 99.15233 108.249465) (end 99.173179 108.282646) (width 0.109) (layer "In6.Cu") (net 46))
  (segment (start 104.40233 107.550535) (end 104.423179 107.517354) (width 0.109) (layer "In6.Cu") (net 46))
  (segment (start 105.10233 107.550535) (end 105.123179 107.517354) (width 0.109) (layer "In6.Cu") (net 46))
  (segment (start 97.039387 108.212477) (end 97.05233 108.249465) (width 0.109) (layer "In6.Cu") (net 46))
  (segment (start 104.285929 108.331205) (end 104.31911 108.310356) (width 0.109) (layer "In6.Cu") (net 46))
  (segment (start 104.423179 107.517354) (end 104.450889 107.489644) (width 0.109) (layer "In6.Cu") (net 46))
  (segment (start 101.448941 108.344148) (end 101.485929 108.331205) (width 0.109) (layer "In6.Cu") (net 46))
  (segment (start 99.835 108.173536) (end 99.839387 108.212477) (width 0.109) (layer "In6.Cu") (net 46))
  (segment (start 102.771058 108.344148) (end 102.81 108.348536) (width 0.109) (layer "In6.Cu") (net 46))
  (segment (start 98.123179 107.517354) (end 98.150889 107.489644) (width 0.109) (layer "In6.Cu") (net 46))
  (segment (start 105.435 108.173536) (end 105.439387 108.212477) (width 0.109) (layer "In6.Cu") (net 46))
  (segment (start 104.367669 108.249465) (end 104.380612 108.212477) (width 0.109) (layer "In6.Cu") (net 46))
  (segment (start 102.980612 108.212477) (end 102.985 108.173536) (width 0.109) (layer "In6.Cu") (net 46))
  (segment (start 103.64682 108.282646) (end 103.667669 108.249465) (width 0.109) (layer "In6.Cu") (net 46))
  (segment (start 104.039387 108.212477) (end 104.05233 108.249465) (width 0.109) (layer "In6.Cu") (net 46))
  (segment (start 88.9 112.2) (end 88.9 111.025) (width 0.109) (layer "In6.Cu") (net 46))
  (segment (start 98.71911 108.310356) (end 98.74682 108.282646) (width 0.109) (layer "In6.Cu") (net 46))
  (segment (start 100.46911 107.489644) (end 100.49682 107.517354) (width 0.109) (layer "In6.Cu") (net 46))
  (segment (start 102.285 107.626464) (end 102.289387 107.587523) (width 0.109) (layer "In6.Cu") (net 46))
  (segment (start 97.735 108.173536) (end 97.739387 108.212477) (width 0.109) (layer "In6.Cu") (net 46))
  (segment (start 97.739387 108.212477) (end 97.75233 108.249465) (width 0.109) (layer "In6.Cu") (net 46))
  (segment (start 104.100889 108.310356) (end 104.13407 108.331205) (width 0.109) (layer "In6.Cu") (net 46))
  (segment (start 94.225 110.175) (end 94.225 110.010499) (width 0.109) (layer "In6.Cu") (net 46))
  (segment (start 101.585 107.626464) (end 101.589387 107.587523) (width 0.109) (layer "In6.Cu") (net 46))
  (segment (start 103.99682 107.517354) (end 104.017669 107.550535) (width 0.109) (layer "In6.Cu") (net 46))
  (segment (start 100.81911 108.310356) (end 100.84682 108.282646) (width 0.109) (layer "In6.Cu") (net 46))
  (segment (start 101.835929 107.468795) (end 101.86911 107.489644) (width 0.109) (layer "In6.Cu") (net 46))
  (segment (start 103.78407 107.468795) (end 103.821058 107.455852) (width 0.109) (layer "In6.Cu") (net 46))
  (segment (start 105.430612 107.587523) (end 105.435 107.626464) (width 0.109) (layer "In6.Cu") (net 46))
  (segment (start 106.15233 108.249465) (end 106.173179 108.282646) (width 0.109) (layer "In6.Cu") (net 46))
  (segment (start 104.035 107.626464) (end 104.035 108.173536) (width 0.109) (layer "In6.Cu") (net 46))
  (segment (start 98.36911 107.489644) (end 98.39682 107.517354) (width 0.109) (layer "In6.Cu") (net 46))
  (segment (start 97.69682 107.517354) (end 97.717669 107.550535) (width 0.109) (layer "In6.Cu") (net 46))
  (segment (start 103.685 107.626464) (end 103.689387 107.587523) (width 0.109) (layer "In6.Cu") (net 46))
  (segment (start 105.417669 107.550535) (end 105.430612 107.587523) (width 0.109) (layer "In6.Cu") (net 46))
  (segment (start 90.75 113.55) (end 90.75 113.082) (width 0.109) (layer "In6.Cu") (net 46))
  (segment (start 102.989387 107.587523) (end 103.00233 107.550535) (width 0.109) (layer "In6.Cu") (net 46))
  (segment (start 98.823179 107.517354) (end 98.850889 107.489644) (width 0.109) (layer "In6.Cu") (net 46))
  (segment (start 89.352489 110.572511) (end 92.071903 110.572511) (width 0.109) (layer "In6.Cu") (net 46))
  (segment (start 97.598941 107.455852) (end 97.635929 107.468795) (width 0.109) (layer "In6.Cu") (net 46))
  (segment (start 105.435 107.626464) (end 105.435 108.173536) (width 0.109) (layer "In6.Cu") (net 46))
  (segment (start 101.650889 107.489644) (end 101.68407 107.468795) (width 0.109) (layer "In6.Cu") (net 46))
  (segment (start 104.48407 107.468795) (end 104.521058 107.455852) (width 0.109) (layer "In6.Cu") (net 46))
  (segment (start 106.117669 107.550535) (end 106.130612 107.587523) (width 0.109) (layer "In6.Cu") (net 46))
  (segment (start 105.089387 107.587523) (end 105.10233 107.550535) (width 0.109) (layer "In6.Cu") (net 46))
  (segment (start 116.2 99.924071) (end 116.200006 99.924071) (width 0.109) (layer "In6.Cu") (net 46))
  (segment (start 99.50233 107.550535) (end 99.523179 107.517354) (width 0.109) (layer "In6.Cu") (net 46))
  (segment (start 97.030612 108.036058) (end 97.035 108.075) (width 0.109) (layer "In6.Cu") (net 46))
  (segment (start 104.31911 108.310356) (end 104.34682 108.282646) (width 0.109) (layer "In6.Cu") (net 46))
  (segment (start 102.46 107.451464) (end 102.498941 107.455852) (width 0.109) (layer "In6.Cu") (net 46))
  (segment (start 100.435929 107.468795) (end 100.46911 107.489644) (width 0.109) (layer "In6.Cu") (net 46))
  (segment (start 97.100889 108.310356) (end 97.13407 108.331205) (width 0.109) (layer "In6.Cu") (net 46))
  (segment (start 105.96 107.451464) (end 105.998941 107.455852) (width 0.109) (layer "In6.Cu") (net 46))
  (segment (start 102.65233 108.249465) (end 102.673179 108.282646) (width 0.109) (layer "In6.Cu") (net 46))
  (segment (start 98.53407 108.331205) (end 98.571058 108.344148) (width 0.109) (layer "In6.Cu") (net 46))
  (segment (start 101.89682 107.517354) (end 101.917669 107.550535) (width 0.109) (layer "In6.Cu") (net 46))
  (segment (start 100.085929 108.331205) (end 100.11911 108.310356) (width 0.109) (layer "In6.Cu") (net 46))
  (segment (start 100.321058 107.455852) (end 100.36 107.451464) (width 0.109) (layer "In6.Cu") (net 46))
  (segment (start 103.335 107.626464) (end 103.335 108.173536) (width 0.109) (layer "In6.Cu") (net 46))
  (segment (start 97.871058 108.344148) (end 97.91 108.348536) (width 0.109) (layer "In6.Cu") (net 46))
  (segment (start 106.58407 107.91733) (end 106.621058 107.904387) (width 0.109) (layer "In6.Cu") (net 46))
  (segment (start 103.335 108.173536) (end 103.339387 108.212477) (width 0.109) (layer "In6.Cu") (net 46))
  (segment (start 106.06911 107.489644) (end 106.09682 107.517354) (width 0.109) (layer "In6.Cu") (net 46))
  (segment (start 102.673179 108.282646) (end 102.700889 108.310356) (width 0.109) (layer "In6.Cu") (net 46))
  (segment (start 101.935 108.173536) (end 101.939387 108.212477) (width 0.109) (layer "In6.Cu") (net 46))
  (segment (start 100.600889 108.310356) (end 100.63407 108.331205) (width 0.109) (layer "In6.Cu") (net 46))
  (segment (start 101.721058 107.455852) (end 101.76 107.451464) (width 0.109) (layer "In6.Cu") (net 46))
  (segment (start 98.26 107.451464) (end 98.298941 107.455852) (width 0.109) (layer "In6.Cu") (net 46))
  (segment (start 114 107.9) (end 116.9 105) (width 0.109) (layer "In6.Cu") (net 46))
  (segment (start 103.750889 107.489644) (end 103.78407 107.468795) (width 0.109) (layer "In6.Cu") (net 46))
  (segment (start 105.785 107.626464) (end 105.789387 107.587523) (width 0.109) (layer "In6.Cu") (net 46))
  (segment (start 99.44682 108.282646) (end 99.467669 108.249465) (width 0.109) (layer "In6.Cu") (net 46))
  (segment (start 101.939387 108.212477) (end 101.95233 108.249465) (width 0.109) (layer "In6.Cu") (net 46))
  (segment (start 106.44682 108.282646) (end 106.467669 108.249465) (width 0.109) (layer "In6.Cu") (net 46))
  (segment (start 102.38407 107.468795) (end 102.421058 107.455852) (width 0.109) (layer "In6.Cu") (net 46))
  (segment (start 97.385 107.626464) (end 97.389387 107.587523) (width 0.109) (layer "In6.Cu") (net 46))
  (segment (start 104.739387 108.212477) (end 104.75233 108.249465) (width 0.109) (layer "In6.Cu") (net 46))
  (segment (start 101.239387 108.212477) (end 101.25233 108.249465) (width 0.109) (layer "In6.Cu") (net 46))
  (segment (start 100.63407 108.331205) (end 100.671058 108.344148) (width 0.109) (layer "In6.Cu") (net 46))
  (segment (start 101.585 108.173536) (end 101.585 107.626464) (width 0.109) (layer "In6.Cu") (net 46))
  (segment (start 101.371058 108.344148) (end 101.41 108.348536) (width 0.109) (layer "In6.Cu") (net 46))
  (segment (start 97.75233 108.249465) (end 97.773179 108.282646) (width 0.109) (layer "In6.Cu") (net 46))
  (segment (start 98.571058 108.344148) (end 98.61 108.348536) (width 0.109) (layer "In6.Cu") (net 46))
  (segment (start 101.135929 107.468795) (end 101.16911 107.489644) (width 0.109) (layer "In6.Cu") (net 46))
  (segment (start 106.035929 107.468795) (end 106.06911 107.489644) (width 0.109) (layer "In6.Cu") (net 46))
  (segment (start 104.035 108.173536) (end 104.039387 108.212477) (width 0.109) (layer "In6.Cu") (net 46))
  (segment (start 99.873179 108.282646) (end 99.900889 108.310356) (width 0.109) (layer "In6.Cu") (net 46))
  (segment (start 99.200889 108.310356) (end 99.23407 108.331205) (width 0.109) (layer "In6.Cu") (net 46))
  (segment (start 102.498941 107.455852) (end 102.535929 107.468795) (width 0.109) (layer "In6.Cu") (net 46))
  (segment (start 99.467669 108.249465) (end 99.480612 108.212477) (width 0.109) (layer "In6.Cu") (net 46))
  (segment (start 96.935929 107.91733) (end 96.96911 107.938179) (width 0.109) (layer "In6.Cu") (net 46))
  (segment (start 104.735 108.173536) (end 104.739387 108.212477) (width 0.109) (layer "In6.Cu") (net 46))
  (segment (start 99.523179 107.517354) (end 99.550889 107.489644) (width 0.109) (layer "In6.Cu") (net 46))
  (segment (start 101.798941 107.455852) (end 101.835929 107.468795) (width 0.109) (layer "In6.Cu") (net 46))
  (segment (start 98.18407 107.468795) (end 98.221058 107.455852) (width 0.109) (layer "In6.Cu") (net 46))
  (segment (start 101.485929 108.331205) (end 101.51911 108.310356) (width 0.109) (layer "In6.Cu") (net 46))
  (segment (start 100.867669 108.249465) (end 100.880612 108.212477) (width 0.109) (layer "In6.Cu") (net 46))
  (segment (start 90.184 112.516) (end 89.216 112.516) (width 0.109) (layer "In6.Cu") (net 46))
  (segment (start 99.698941 107.455852) (end 99.735929 107.468795) (width 0.109) (layer "In6.Cu") (net 46))
  (segment (start 104.717669 107.550535) (end 104.730612 107.587523) (width 0.109) (layer "In6.Cu") (net 46))
  (segment (start 100.98407 107.468795) (end 101.021058 107.455852) (width 0.109) (layer "In6.Cu") (net 46))
  (segment (start 96.898941 107.904387) (end 96.935929 107.91733) (width 0.109) (layer "In6.Cu") (net 46))
  (segment (start 102.56911 107.489644) (end 102.59682 107.517354) (width 0.109) (layer "In6.Cu") (net 46))
  (segment (start 97.91 108.348536) (end 97.948941 108.344148) (width 0.109) (layer "In6.Cu") (net 46))
  (segment (start 101.580612 108.212477) (end 101.585 108.173536) (width 0.109) (layer "In6.Cu") (net 46))
  (segment (start 100.048941 108.344148) (end 100.085929 108.331205) (width 0.109) (layer "In6.Cu") (net 46))
  (segment (start 102.421058 107.455852) (end 102.46 107.451464) (width 0.109) (layer "In6.Cu") (net 46))
  (segment (start 104.34682 108.282646) (end 104.367669 108.249465) (width 0.109) (layer "In6.Cu") (net 46))
  (segment (start 106.41911 108.310356) (end 106.44682 108.282646) (width 0.109) (layer "In6.Cu") (net 46))
  (segment (start 103.35233 108.249465) (end 103.373179 108.282646) (width 0.109) (layer "In6.Cu") (net 46))
  (segment (start 100.185 108.173536) (end 100.185 107.626464) (width 0.109) (layer "In6.Cu") (net 46))
  (segment (start 98.39682 107.517354) (end 98.417669 107.550535) (width 0.109) (layer "In6.Cu") (net 46))
  (segment (start 101.235 107.626464) (end 101.235 108.173536) (width 0.109) (layer "In6.Cu") (net 46))
  (segment (start 105.71911 108.310356) (end 105.74682 108.282646) (width 0.109) (layer "In6.Cu") (net 46))
  (segment (start 102.289387 107.587523) (end 102.30233 107.550535) (width 0.109) (layer "In6.Cu") (net 46))
  (segment (start 104.248941 108.344148) (end 104.285929 108.331205) (width 0.109) (layer "In6.Cu") (net 46))
  (segment (start 104.985929 108.331205) (end 105.01911 108.310356) (width 0.109) (layer "In6.Cu") (net 46))
  (segment (start 102.617669 107.550535) (end 102.630612 107.587523) (width 0.109) (layer "In6.Cu") (net 46))
  (segment (start 105.571058 108.344148) (end 105.61 108.348536) (width 0.109) (layer "In6.Cu") (net 46))
  (segment (start 100.11911 108.310356) (end 100.14682 108.282646) (width 0.109) (layer "In6.Cu") (net 46))
  (segment (start 102.630612 107.587523) (end 102.635 107.626464) (width 0.109) (layer "In6.Cu") (net 46))
  (segment (start 101.098941 107.455852) (end 101.135929 107.468795) (width 0.109) (layer "In6.Cu") (net 46))
  (segment (start 103.317669 107.550535) (end 103.330612 107.587523) (width 0.109) (layer "In6.Cu") (net 46))
  (segment (start 101.76 107.451464) (end 101.798941 107.455852) (width 0.109) (layer "In6.Cu") (net 46))
  (segment (start 104.171058 108.344148) (end 104.21 108.348536) (width 0.109) (layer "In6.Cu") (net 46))
  (segment (start 98.648941 108.344148) (end 98.685929 108.331205) (width 0.109) (layer "In6.Cu") (net 46))
  (segment (start 103.050889 107.489644) (end 103.08407 107.468795) (width 0.109) (layer "In6.Cu") (net 46))
  (segment (start 116.9 105) (end 116.9 102.54) (width 0.109) (layer "In6.Cu") (net 46))
  (segment (start 101.917669 107.550535) (end 101.930612 107.587523) (width 0.109) (layer "In6.Cu") (net 46))
  (segment (start 97.34682 108.282646) (end 97.367669 108.249465) (width 0.109) (layer "In6.Cu") (net 46))
  (segment (start 97.385 108.173536) (end 97.385 107.626464) (width 0.109) (layer "In6.Cu") (net 46))
  (segment (start 99.135 108.173536) (end 99.139387 108.212477) (width 0.109) (layer "In6.Cu") (net 46))
  (segment (start 104.730612 107.587523) (end 104.735 107.626464) (width 0.109) (layer "In6.Cu") (net 46))
  (segment (start 101.273179 108.282646) (end 101.300889 108.310356) (width 0.109) (layer "In6.Cu") (net 46))
  (segment (start 99.550889 107.489644) (end 99.58407 107.468795) (width 0.109) (layer "In6.Cu") (net 46))
  (segment (start 105.61 108.348536) (end 105.648941 108.344148) (width 0.109) (layer "In6.Cu") (net 46))
  (segment (start 101.51911 108.310356) (end 101.54682 108.282646) (width 0.109) (layer "In6.Cu") (net 46))
  (segment (start 106.23407 108.331205) (end 106.271058 108.344148) (width 0.109) (layer "In6.Cu") (net 46))
  (segment (start 99.23407 108.331205) (end 99.271058 108.344148) (width 0.109) (layer "In6.Cu") (net 46))
  (segment (start 101.623179 107.517354) (end 101.650889 107.489644) (width 0.109) (layer "In6.Cu") (net 46))
  (segment (start 97.073179 108.282646) (end 97.100889 108.310356) (width 0.109) (layer "In6.Cu") (net 46))
  (segment (start 106.467669 108.249465) (end 106.480612 108.212477) (width 0.109) (layer "In6.Cu") (net 46))
  (segment (start 97.017669 107.99907) (end 97.030612 108.036058) (width 0.109) (layer "In6.Cu") (net 46))
  (segment (start 102.985 108.173536) (end 102.985 107.626464) (width 0.109) (layer "In6.Cu") (net 46))
  (segment (start 104.598941 107.455852) (end 104.635929 107.468795) (width 0.109) (layer "In6.Cu") (net 46))
  (segment (start 106.09682 107.517354) (end 106.117669 107.550535) (width 0.109) (layer "In6.Cu") (net 46))
  (segment (start 98.435 107.626464) (end 98.435 108.173536) (width 0.109) (layer "In6.Cu") (net 46))
  (segment (start 93.95 110.45) (end 94.225 110.175) (width 0.109) (layer "In6.Cu") (net 46))
  (segment (start 103.373179 108.282646) (end 103.400889 108.310356) (width 0.109) (layer "In6.Cu") (net 46))
  (segment (start 102.323179 107.517354) (end 102.350889 107.489644) (width 0.109) (layer "In6.Cu") (net 46))
  (segment (start 102.267669 108.249465) (end 102.280612 108.212477) (width 0.109) (layer "In6.Cu") (net 46))
  (segment (start 97.035 108.173536) (end 97.039387 108.212477) (width 0.109) (layer "In6.Cu") (net 46))
  (segment (start 100.71 108.348536) (end 100.748941 108.344148) (width 0.109) (layer "In6.Cu") (net 46))
  (segment (start 98.085 107.626464) (end 98.089387 107.587523) (width 0.109) (layer "In6.Cu") (net 46))
  (segment (start 102.985 107.626464) (end 102.989387 107.587523) (width 0.109) (layer "In6.Cu") (net 46))
  (segment (start 106.550889 107.938179) (end 106.58407 107.91733) (width 0.109) (layer "In6.Cu") (net 46))
  (segment (start 104.521058 107.455852) (end 104.56 107.451464) (width 0.109) (layer "In6.Cu") (net 46))
  (segment (start 101.973179 108.282646) (end 102.000889 108.310356) (width 0.109) (layer "In6.Cu") (net 46))
  (segment (start 105.298941 107.455852) (end 105.335929 107.468795) (width 0.109) (layer "In6.Cu") (net 46))
  (segment (start 97.48407 107.468795) (end 97.521058 107.455852) (width 0.109) (layer "In6.Cu") (net 46))
  (segment (start 102.03407 108.331205) (end 102.071058 108.344148) (width 0.109) (layer "In6.Cu") (net 46))
  (segment (start 103.471058 108.344148) (end 103.51 108.348536) (width 0.109) (layer "In6.Cu") (net 46))
  (segment (start 99.835 107.626464) (end 99.835 108.173536) (width 0.109) (layer "In6.Cu") (net 46))
  (segment (start 97.13407 108.331205) (end 97.171058 108.344148) (width 0.109) (layer "In6.Cu") (net 46))
  (segment (start 105.53407 108.331205) (end 105.571058 108.344148) (width 0.109) (layer "In6.Cu") (net 46))
  (segment (start 101.86911 107.489644) (end 101.89682 107.517354) (width 0.109) (layer "In6.Cu") (net 46))
  (segment (start 98.785 108.173536) (end 98.785 107.626464) (width 0.109) (layer "In6.Cu") (net 46))
  (segment (start 105.850889 107.489644) (end 105.88407 107.468795) (width 0.109) (layer "In6.Cu") (net 46))
  (segment (start 105.767669 108.249465) (end 105.780612 108.212477) (width 0.109) (layer "In6.Cu") (net 46))
  (segment (start 97.773179 108.282646) (end 97.800889 108.310356) (width 0.109) (layer "In6.Cu") (net 46))
  (segment (start 106.66 107.9) (end 114 107.9) (width 0.109) (layer "In6.Cu") (net 46))
  (segment (start 92.071903 110.572511) (end 92.194414 110.45) (width 0.109) (layer "In6.Cu") (net 46))
  (segment (start 104.073179 108.282646) (end 104.100889 108.310356) (width 0.109) (layer "In6.Cu") (net 46))
  (segment (start 97.985929 108.331205) (end 98.01911 108.310356) (width 0.109) (layer "In6.Cu") (net 46))
  (segment (start 105.74682 108.282646) (end 105.767669 108.249465) (width 0.109) (layer "In6.Cu") (net 46))
  (segment (start 102.30233 107.550535) (end 102.323179 107.517354) (width 0.109) (layer "In6.Cu") (net 46))
  (segment (start 98.221058 107.455852) (end 98.26 107.451464) (width 0.109) (layer "In6.Cu") (net 46))
  (segment (start 100.185 107.626464) (end 100.189387 107.587523) (width 0.109) (layer "In6.Cu") (net 46))
  (segment (start 105.01911 108.310356) (end 105.04682 108.282646) (width 0.109) (layer "In6.Cu") (net 46))
  (segment (start 100.748941 108.344148) (end 100.785929 108.331205) (width 0.109) (layer "In6.Cu") (net 46))
  (segment (start 98.45233 108.249465) (end 98.473179 108.282646) (width 0.109) (layer "In6.Cu") (net 46))
  (segment (start 97.367669 108.249465) (end 97.380612 108.212477) (width 0.109) (layer "In6.Cu") (net 46))
  (segment (start 102.94682 108.282646) (end 102.967669 108.249465) (width 0.109) (layer "In6.Cu") (net 46))
  (segment (start 102.73407 108.331205) (end 102.771058 108.344148) (width 0.109) (layer "In6.Cu") (net 46))
  (segment (start 98.335929 107.468795) (end 98.36911 107.489644) (width 0.109) (layer "In6.Cu") (net 46))
  (segment (start 102.280612 108.212477) (end 102.285 108.173536) (width 0.109) (layer "In6.Cu") (net 46))
  (segment (start 99.385929 108.331205) (end 99.41911 108.310356) (width 0.109) (layer "In6.Cu") (net 46))
  (segment (start 100.167669 108.249465) (end 100.180612 108.212477) (width 0.109) (layer "In6.Cu") (net 46))
  (segment (start 100.01 108.348536) (end 100.048941 108.344148) (width 0.109) (layer "In6.Cu") (net 46))
  (segment (start 98.10233 107.550535) (end 98.123179 107.517354) (width 0.109) (layer "In6.Cu") (net 46))
  (segment (start 98.430612 107.587523) (end 98.435 107.626464) (width 0.109) (layer "In6.Cu") (net 46))
  (segment (start 104.05233 108.249465) (end 104.073179 108.282646) (width 0.109) (layer "In6.Cu") (net 46))
  (segment (start 104.385 108.173536) (end 104.385 107.626464) (width 0.109) (layer "In6.Cu") (net 46))
  (segment (start 106.130612 107.587523) (end 106.135 107.626464) (width 0.109) (layer "In6.Cu") (net 46))
  (segment (start 101.16911 107.489644) (end 101.19682 107.517354) (width 0.109) (layer "In6.Cu") (net 46))
  (segment (start 103.08407 107.468795) (end 103.121058 107.455852) (width 0.109) (layer "In6.Cu") (net 46))
  (segment (start 104.871058 108.344148) (end 104.91 108.348536) (width 0.109) (layer "In6.Cu") (net 46))
  (segment (start 103.70233 107.550535) (end 103.723179 107.517354) (width 0.109) (layer "In6.Cu") (net 46))
  (segment (start 103.121058 107.455852) (end 103.16 107.451464) (width 0.109) (layer "In6.Cu") (net 46))
  (segment (start 97.380612 108.212477) (end 97.385 108.173536) (width 0.109) (layer "In6.Cu") (net 46))
  (segment (start 98.80233 107.550535) (end 98.823179 107.517354) (width 0.109) (layer "In6.Cu") (net 46))
  (segment (start 106.271058 108.344148) (end 106.31 108.348536) (width 0.109) (layer "In6.Cu") (net 46))
  (segment (start 103.548941 108.344148) (end 103.585929 108.331205) (width 0.109) (layer "In6.Cu") (net 46))
  (segment (start 100.671058 108.344148) (end 100.71 108.348536) (width 0.109) (layer "In6.Cu") (net 46))
  (segment (start 104.91 108.348536) (end 104.948941 108.344148) (width 0.109) (layer "In6.Cu") (net 46))
  (segment (start 105.921058 107.455852) (end 105.96 107.451464) (width 0.109) (layer "In6.Cu") (net 46))
  (segment (start 100.14682 108.282646) (end 100.167669 108.249465) (width 0.109) (layer "In6.Cu") (net 46))
  (segment (start 106.135 107.626464) (end 106.135 108.173536) (width 0.109) (layer "In6.Cu") (net 46))
  (segment (start 99.971058 108.344148) (end 100.01 108.348536) (width 0.109) (layer "In6.Cu") (net 46))
  (segment (start 105.45233 108.249465) (end 105.473179 108.282646) (width 0.109) (layer "In6.Cu") (net 46))
  (segment (start 103.61911 108.310356) (end 103.64682 108.282646) (width 0.109) (layer "In6.Cu") (net 46))
  (segment (start 103.16 107.451464) (end 103.198941 107.455852) (width 0.109) (layer "In6.Cu") (net 46))
  (segment (start 106.480612 108.212477) (end 106.485 108.173536) (width 0.109) (layer "In6.Cu") (net 46))
  (segment (start 100.84682 108.282646) (end 100.867669 108.249465) (width 0.109) (layer "In6.Cu") (net 46))
  (segment (start 99.139387 108.212477) (end 99.15233 108.249465) (width 0.109) (layer "In6.Cu") (net 46))
  (segment (start 99.480612 108.212477) (end 99.485 108.173536) (width 0.109) (layer "In6.Cu") (net 46))
  (segment (start 105.685929 108.331205) (end 105.71911 108.310356) (width 0.109) (layer "In6.Cu") (net 46))
  (segment (start 105.085 108.173536) (end 105.085 107.626464) (width 0.109) (layer "In6.Cu") (net 46))
  (segment (start 101.41 108.348536) (end 101.448941 108.344148) (width 0.109) (layer "In6.Cu") (net 46))
  (segment (start 102.21911 108.310356) (end 102.24682 108.282646) (width 0.109) (layer "In6.Cu") (net 46))
  (segment (start 102.59682 107.517354) (end 102.617669 107.550535) (width 0.109) (layer "In6.Cu") (net 46))
  (segment (start 99.485 107.626464) (end 99.489387 107.587523) (width 0.109) (layer "In6.Cu") (net 46))
  (segment (start 99.489387 107.587523) (end 99.50233 107.550535) (width 0.109) (layer "In6.Cu") (net 46))
  (segment (start 123.8517 101.045) (end 124.855 101.045) (width 0.182) (layer "F.Cu") (net 47))
  (segment (start 123.67335 100.18665) (end 123.4857 99.999) (width 0.182) (layer "F.Cu") (net 47))
  (segment (start 123.4857 99.999) (end 123.1151 99.999) (width 0.182) (layer "F.Cu") (net 47))
  (segment (start 123.67335 100.86665) (end 123.67335 100.18665) (width 0.182) (layer "F.Cu") (net 47))
  (segment (start 89.4415 113.804) (end 89.8265 113.494) (width 0.182) (layer "F.Cu") (net 47))
  (segment (start 123.67335 100.86665) (end 123.8517 101.045) (width 0.182) (layer "F.Cu") (net 47))
  (via (at 89.4415 113.804) (size 0.45) (drill 0.1) (layers "F.Cu" "B.Cu") (net 47))
  (via (at 124.855 101.045) (size 0.45) (drill 0.1) (layers "F.Cu" "B.Cu") (net 47))
  (segment (start 107.285 114.383492) (end 107.285 115.016508) (width 0.109) (layer "In6.Cu") (net 47))
  (segment (start 105.600889 114.246672) (end 105.63407 114.225823) (width 0.109) (layer "In6.Cu") (net 47))
  (segment (start 108.023179 115.125618) (end 108.050889 115.153328) (width 0.109) (layer "In6.Cu") (net 47))
  (segment (start 108.898941 115.18712) (end 108.935929 115.174177) (width 0.109) (layer "In6.Cu") (net 47))
  (segment (start 108.35233 114.307563) (end 108.373179 114.274382) (width 0.109) (layer "In6.Cu") (net 47))
  (segment (start 108.61911 114.246672) (end 108.64682 114.274382) (width 0.109) (layer "In6.Cu") (net 47))
  (segment (start 107.81 114.208492) (end 107.848941 114.21288) (width 0.109) (layer "In6.Cu") (net 47))
  (segment (start 107.289387 115.055449) (end 107.30233 115.092437) (width 0.109) (layer "In6.Cu") (net 47))
  (segment (start 105.880612 114.344551) (end 105.885 114.383492) (width 0.109) (layer "In6.Cu") (net 47))
  (segment (start 107.03407 114.225823) (end 107.071058 114.21288) (width 0.109) (layer "In6.Cu") (net 47))
  (segment (start 108.330612 115.055449) (end 108.335 115.016508) (width 0.109) (layer "In6.Cu") (net 47))
  (segment (start 105.185 114.383492) (end 105.185 115.016508) (width 0.109) (layer "In6.Cu") (net 47))
  (segment (start 106.235 115.016508) (end 106.235 114.383492) (width 0.109) (layer "In6.Cu") (net 47))
  (segment (start 107.635 114.383492) (end 107.639387 114.344551) (width 0.109) (layer "In6.Cu") (net 47))
  (segment (start 107.535929 115.174177) (end 107.56911 115.153328) (width 0.109) (layer "In6.Cu") (net 47))
  (segment (start 108.935929 115.174177) (end 108.96911 115.153328) (width 0.109) (layer "In6.Cu") (net 47))
  (segment (start 109.389387 115.055449) (end 109.40233 115.092437) (width 0.109) (layer "In6.Cu") (net 47))
  (segment (start 110.430612 115.055449) (end 110.435 115.016508) (width 0.109) (layer "In6.Cu") (net 47))
  (segment (start 117.92 114.7) (end 122.5 110.12) (width 0.109) (layer "In6.Cu") (net 47))
  (segment (start 110.39682 115.125618) (end 110.417669 115.092437) (width 0.109) (layer "In6.Cu") (net 47))
  (segment (start 109.073179 114.274382) (end 109.100889 114.246672) (width 0.109) (layer "In6.Cu") (net 47))
  (segment (start 105.085929 114.225823) (end 105.11911 114.246672) (width 0.109) (layer "In6.Cu") (net 47))
  (segment (start 108.64682 114.274382) (end 108.667669 114.307563) (width 0.109) (layer "In6.Cu") (net 47))
  (segment (start 109.035 114.383492) (end 109.039387 114.344551) (width 0.109) (layer "In6.Cu") (net 47))
  (segment (start 106.16911 115.153328) (end 106.19682 115.125618) (width 0.109) (layer "In6.Cu") (net 47))
  (segment (start 110.085 115.016508) (end 110.089387 115.055449) (width 0.109) (layer "In6.Cu") (net 47))
  (segment (start 107.989387 115.055449) (end 108.00233 115.092437) (width 0.109) (layer "In6.Cu") (net 47))
  (segment (start 107.59682 115.125618) (end 107.617669 115.092437) (width 0.109) (layer "In6.Cu") (net 47))
  (segment (start 106.650889 115.153328) (end 106.68407 115.174177) (width 0.109) (layer "In6.Cu") (net 47))
  (segment (start 109.66911 115.153328) (end 109.69682 115.125618) (width 0.109) (layer "In6.Cu") (net 47))
  (segment (start 109.83407 114.225823) (end 109.871058 114.21288) (width 0.109) (layer "In6.Cu") (net 47))
  (segment (start 110.53407 114.225823) (end 110.571058 114.21288) (width 0.109) (layer "In6.Cu") (net 47))
  (segment (start 105.20233 115.092437) (end 105.223179 115.125618) (width 0.109) (layer "In6.Cu") (net 47))
  (segment (start 105.048941 114.21288) (end 105.085929 114.225823) (width 0.109) (layer "In6.Cu") (net 47))
  (segment (start 108.16 115.191508) (end 108.198941 115.18712) (width 0.109) (layer "In6.Cu") (net 47))
  (segment (start 109.31911 114.246672) (end 109.34682 114.274382) (width 0.109) (layer "In6.Cu") (net 47))
  (segment (start 105.530612 115.055449) (end 105.535 115.016508) (width 0.109) (layer "In6.Cu") (net 47))
  (segment (start 109.13407 114.225823) (end 109.171058 114.21288) (width 0.109) (layer "In6.Cu") (net 47))
  (segment (start 108.78407 115.174177) (end 108.821058 115.18712) (width 0.109) (layer "In6.Cu") (net 47))
  (segment (start 106.623179 115.125618) (end 106.650889 115.153328) (width 0.109) (layer "In6.Cu") (net 47))
  (segment (start 105.81911 114.246672) (end 105.84682 114.274382) (width 0.109) (layer "In6.Cu") (net 47))
  (segment (start 107.38407 115.174177) (end 107.421058 115.18712) (width 0.109) (layer "In6.Cu") (net 47))
  (segment (start 107.285 115.016508) (end 107.289387 115.055449) (width 0.109) (layer "In6.Cu") (net 47))
  (segment (start 106.300889 114.246672) (end 106.33407 114.225823) (width 0.109) (layer "In6.Cu") (net 47))
  (segment (start 105.90233 115.092437) (end 105.923179 115.125618) (width 0.109) (layer "In6.Cu") (net 47))
  (segment (start 107.91911 114.246672) (end 107.94682 114.274382) (width 0.109) (layer "In6.Cu") (net 47))
  (segment (start 106.721058 115.18712) (end 106.76 115.191508) (width 0.109) (layer "In6.Cu") (net 47))
  (segment (start 104.31 114.7) (end 104.348941 114.704387) (width 0.109) (layer "In6.Cu") (net 47))
  (segment (start 109.48407 115.174177) (end 109.521058 115.18712) (width 0.109) (layer "In6.Cu") (net 47))
  (segment (start 102.15 114.05) (end 102.8 114.7) (width 0.109) (layer "In6.Cu") (net 47))
  (segment (start 107.65233 114.307563) (end 107.673179 114.274382) (width 0.109) (layer "In6.Cu") (net 47))
  (segment (start 107.885929 114.225823) (end 107.91911 114.246672) (width 0.109) (layer "In6.Cu") (net 47))
  (segment (start 107.980612 114.344551) (end 107.985 114.383492) (width 0.109) (layer "In6.Cu") (net 47))
  (segment (start 106.95233 114.307563) (end 106.973179 114.274382) (width 0.109) (layer "In6.Cu") (net 47))
  (segment (start 110.18407 115.174177) (end 110.221058 115.18712) (width 0.109) (layer "In6.Cu") (net 47))
  (segment (start 106.448941 114.21288) (end 106.485929 114.225823) (width 0.109) (layer "In6.Cu") (net 47))
  (segment (start 109.773179 114.274382) (end 109.800889 114.246672) (width 0.109) (layer "In6.Cu") (net 47))
  (segment (start 105.867669 114.307563) (end 105.880612 114.344551) (width 0.109) (layer "In6.Cu") (net 47))
  (segment (start 104.485 115.016508) (end 104.489387 115.055449) (width 0.109) (layer "In6.Cu") (net 47))
  (segment (start 107.421058 115.18712) (end 107.46 115.191508) (width 0.109) (layer "In6.Cu") (net 47))
  (segment (start 107.94682 114.274382) (end 107.967669 114.307563) (width 0.109) (layer "In6.Cu") (net 47))
  (segment (start 109.717669 115.092437) (end 109.730612 115.055449) (width 0.109) (layer "In6.Cu") (net 47))
  (segment (start 106.68407 115.174177) (end 106.721058 115.18712) (width 0.109) (layer "In6.Cu") (net 47))
  (segment (start 108.400889 114.246672) (end 108.43407 114.225823) (width 0.109) (layer "In6.Cu") (net 47))
  (segment (start 110.850889 114.661821) (end 110.88407 114.68267) (width 0.109) (layer "In6.Cu") (net 47))
  (segment (start 108.335 114.383492) (end 108.339387 114.344551) (width 0.109) (layer "In6.Cu") (net 47))
  (segment (start 110.150889 115.153328) (end 110.18407 115.174177) (width 0.109) (layer "In6.Cu") (net 47))
  (segment (start 107.985 115.016508) (end 107.989387 115.055449) (width 0.109) (layer "In6.Cu") (net 47))
  (segment (start 110.80233 114.60093) (end 110.823179 114.634111) (width 0.109) (layer "In6.Cu") (net 47))
  (segment (start 108.050889 115.153328) (end 108.08407 115.174177) (width 0.109) (layer "In6.Cu") (net 47))
  (segment (start 108.86 115.191508) (end 108.898941 115.18712) (width 0.109) (layer "In6.Cu") (net 47))
  (segment (start 109.21 114.208492) (end 109.248941 114.21288) (width 0.109) (layer "In6.Cu") (net 47))
  (segment (start 108.685 115.016508) (end 108.689387 115.055449) (width 0.109) (layer "In6.Cu") (net 47))
  (segment (start 104.93407 114.225823) (end 104.971058 114.21288) (width 0.109) (layer "In6.Cu") (net 47))
  (segment (start 123.86 106.1) (end 125.3 104.66) (width 0.109) (layer "In6.Cu") (net 47))
  (segment (start 105.28407 115.174177) (end 105.321058 115.18712) (width 0.109) (layer "In6.Cu") (net 47))
  (segment (start 104.58407 115.174177) (end 104.621058 115.18712) (width 0.109) (layer "In6.Cu") (net 47))
  (segment (start 104.467669 114.79907) (end 104.480612 114.836058) (width 0.109) (layer "In6.Cu") (net 47))
  (segment (start 89.8625 114.225) (end 93.275 114.225) (width 0.109) (layer "In6.Cu") (net 47))
  (segment (start 110.01911 114.246672) (end 110.04682 114.274382) (width 0.109) (layer "In6.Cu") (net 47))
  (segment (start 106.580612 114.344551) (end 106.585 114.383492) (width 0.109) (layer "In6.Cu") (net 47))
  (segment (start 122.5 110.12) (end 122.5 106.78) (width 0.109) (layer "In6.Cu") (net 47))
  (segment (start 106.273179 114.274382) (end 106.300889 114.246672) (width 0.109) (layer "In6.Cu") (net 47))
  (segment (start 105.535 114.383492) (end 105.539387 114.344551) (width 0.109) (layer "In6.Cu") (net 47))
  (segment (start 105.185 115.016508) (end 105.189387 115.055449) (width 0.109) (layer "In6.Cu") (net 47))
  (segment (start 108.373179 114.274382) (end 108.400889 114.246672) (width 0.109) (layer "In6.Cu") (net 47))
  (segment (start 110.648941 114.21288) (end 110.685929 114.225823) (width 0.109) (layer "In6.Cu") (net 47))
  (segment (start 109.450889 115.153328) (end 109.48407 115.174177) (width 0.109) (layer "In6.Cu") (net 47))
  (segment (start 109.171058 114.21288) (end 109.21 114.208492) (width 0.109) (layer "In6.Cu") (net 47))
  (segment (start 109.40233 115.092437) (end 109.423179 115.125618) (width 0.109) (layer "In6.Cu") (net 47))
  (segment (start 110.089387 115.055449) (end 110.10233 115.092437) (width 0.109) (layer "In6.Cu") (net 47))
  (segment (start 107.185929 114.225823) (end 107.21911 114.246672) (width 0.109) (layer "In6.Cu") (net 47))
  (segment (start 106.89682 115.125618) (end 106.917669 115.092437) (width 0.109) (layer "In6.Cu") (net 47))
  (segment (start 104.489387 115.055449) (end 104.50233 115.092437) (width 0.109) (layer "In6.Cu") (net 47))
  (segment (start 104.735929 115.174177) (end 104.76911 115.153328) (width 0.109) (layer "In6.Cu") (net 47))
  (segment (start 107.56911 115.153328) (end 107.59682 115.125618) (width 0.109) (layer "In6.Cu") (net 47))
  (segment (start 106.76 115.191508) (end 106.798941 115.18712) (width 0.109) (layer "In6.Cu") (net 47))
  (segment (start 108.335 115.016508) (end 108.335 114.383492) (width 0.109) (layer "In6.Cu") (net 47))
  (segment (start 108.29682 115.125618) (end 108.317669 115.092437) (width 0.109) (layer "In6.Cu") (net 47))
  (segment (start 105.180612 114.344551) (end 105.185 114.383492) (width 0.109) (layer "In6.Cu") (net 47))
  (segment (start 110.685929 114.225823) (end 110.71911 114.246672) (width 0.109) (layer "In6.Cu") (net 47))
  (segment (start 110.473179 114.274382) (end 110.500889 114.246672) (width 0.109) (layer "In6.Cu") (net 47))
  (segment (start 106.589387 115.055449) (end 106.60233 115.092437) (width 0.109) (layer "In6.Cu") (net 47))
  (segment (start 107.21911 114.246672) (end 107.24682 114.274382) (width 0.109) (layer "In6.Cu") (net 47))
  (segment (start 109.035 115.016508) (end 109.035 114.383492) (width 0.109) (layer "In6.Cu") (net 47))
  (segment (start 109.75233 114.307563) (end 109.773179 114.274382) (width 0.109) (layer "In6.Cu") (net 47))
  (segment (start 104.698941 115.18712) (end 104.735929 115.174177) (width 0.109) (layer "In6.Cu") (net 47))
  (segment (start 110.74682 114.274382) (end 110.767669 114.307563) (width 0.109) (layer "In6.Cu") (net 47))
  (segment (start 109.05233 114.307563) (end 109.073179 114.274382) (width 0.109) (layer "In6.Cu") (net 47))
  (segment (start 105.435929 115.174177) (end 105.46911 115.153328) (width 0.109) (layer "In6.Cu") (net 47))
  (segment (start 107.985 114.383492) (end 107.985 115.016508) (width 0.109) (layer "In6.Cu") (net 47))
  (segment (start 109.735 115.016508) (end 109.735 114.383492) (width 0.109) (layer "In6.Cu") (net 47))
  (segment (start 110.96 114.7) (end 117.92 114.7) (width 0.109) (layer "In6.Cu") (net 47))
  (segment (start 108.70233 115.092437) (end 108.723179 115.125618) (width 0.109) (layer "In6.Cu") (net 47))
  (segment (start 108.685 114.383492) (end 108.685 115.016508) (width 0.109) (layer "In6.Cu") (net 47))
  (segment (start 93.45 114.05) (end 102.15 114.05) (width 0.109) (layer "In6.Cu") (net 47))
  (segment (start 102.8 114.7) (end 104.31 114.7) (width 0.109) (layer "In6.Cu") (net 47))
  (segment (start 105.321058 115.18712) (end 105.36 115.191508) (width 0.109) (layer "In6.Cu") (net 47))
  (segment (start 105.748941 114.21288) (end 105.785929 114.225823) (width 0.109) (layer "In6.Cu") (net 47))
  (segment (start 106.54682 114.274382) (end 106.567669 114.307563) (width 0.109) (layer "In6.Cu") (net 47))
  (segment (start 106.235 114.383492) (end 106.239387 114.344551) (width 0.109) (layer "In6.Cu") (net 47))
  (segment (start 107.280612 114.344551) (end 107.285 114.383492) (width 0.109) (layer "In6.Cu") (net 47))
  (segment (start 109.739387 114.344551) (end 109.75233 114.307563) (width 0.109) (layer "In6.Cu") (net 47))
  (segment (start 107.617669 115.092437) (end 107.630612 115.055449) (width 0.109) (layer "In6.Cu") (net 47))
  (segment (start 109.635929 115.174177) (end 109.66911 115.153328) (width 0.109) (layer "In6.Cu") (net 47))
  (segment (start 110.789387 114.563942) (end 110.80233 114.60093) (width 0.109) (layer "In6.Cu") (net 47))
  (segment (start 106.25233 114.307563) (end 106.273179 114.274382) (width 0.109) (layer "In6.Cu") (net 47))
  (segment (start 108.667669 114.307563) (end 108.680612 114.344551) (width 0.109) (layer "In6.Cu") (net 47))
  (segment (start 106.585 115.016508) (end 106.589387 115.055449) (width 0.109) (layer "In6.Cu") (net 47))
  (segment (start 108.317669 115.092437) (end 108.330612 115.055449) (width 0.109) (layer "In6.Cu") (net 47))
  (segment (start 110.417669 115.092437) (end 110.430612 115.055449) (width 0.109) (layer "In6.Cu") (net 47))
  (segment (start 109.91 114.208492) (end 109.948941 114.21288) (width 0.109) (layer "In6.Cu") (net 47))
  (segment (start 107.630612 115.055449) (end 107.635 115.016508) (width 0.109) (layer "In6.Cu") (net 47))
  (segment (start 107.771058 114.21288) (end 107.81 114.208492) (width 0.109) (layer "In6.Cu") (net 47))
  (segment (start 104.835 114.383492) (end 104.839387 114.344551) (width 0.109) (layer "In6.Cu") (net 47))
  (segment (start 110.500889 114.246672) (end 110.53407 114.225823) (width 0.109) (layer "In6.Cu") (net 47))
  (segment (start 104.76911 115.153328) (end 104.79682 115.125618) (width 0.109) (layer "In6.Cu") (net 47))
  (segment (start 104.839387 114.344551) (end 104.85233 114.307563) (width 0.109) (layer "In6.Cu") (net 47))
  (segment (start 104.66 115.191508) (end 104.698941 115.18712) (width 0.109) (layer "In6.Cu") (net 47))
  (segment (start 108.548941 114.21288) (end 108.585929 114.225823) (width 0.109) (layer "In6.Cu") (net 47))
  (segment (start 105.14682 114.274382) (end 105.167669 114.307563) (width 0.109) (layer "In6.Cu") (net 47))
  (segment (start 109.385 115.016508) (end 109.389387 115.055449) (width 0.109) (layer "In6.Cu") (net 47))
  (segment (start 110.785 114.525) (end 110.789387 114.563942) (width 0.109) (layer "In6.Cu") (net 47))
  (segment (start 105.671058 114.21288) (end 105.71 114.208492) (width 0.109) (layer "In6.Cu") (net 47))
  (segment (start 106.973179 114.274382) (end 107.000889 114.246672) (width 0.109) (layer "In6.Cu") (net 47))
  (segment (start 109.871058 114.21288) (end 109.91 114.208492) (width 0.109) (layer "In6.Cu") (net 47))
  (segment (start 109.100889 114.246672) (end 109.13407 114.225823) (width 0.109) (layer "In6.Cu") (net 47))
  (segment (start 105.250889 115.153328) (end 105.28407 115.174177) (width 0.109) (layer "In6.Cu") (net 47))
  (segment (start 107.148941 114.21288) (end 107.185929 114.225823) (width 0.109) (layer "In6.Cu") (net 47))
  (segment (start 110.080612 114.344551) (end 110.085 114.383492) (width 0.109) (layer "In6.Cu") (net 47))
  (segment (start 110.88407 114.68267) (end 110.921058 114.695613) (width 0.109) (layer "In6.Cu") (net 47))
  (segment (start 109.423179 115.125618) (end 109.450889 115.153328) (width 0.109) (layer "In6.Cu") (net 47))
  (segment (start 105.63407 114.225823) (end 105.671058 114.21288) (width 0.109) (layer "In6.Cu") (net 47))
  (segment (start 105.223179 115.125618) (end 105.250889 115.153328) (width 0.109) (layer "In6.Cu") (net 47))
  (segment (start 110.780612 114.344551) (end 110.785 114.383492) (width 0.109) (layer "In6.Cu") (net 47))
  (segment (start 108.750889 115.153328) (end 108.78407 115.174177) (width 0.109) (layer "In6.Cu") (net 47))
  (segment (start 106.60233 115.092437) (end 106.623179 115.125618) (width 0.109) (layer "In6.Cu") (net 47))
  (segment (start 109.017669 115.092437) (end 109.030612 115.055449) (width 0.109) (layer "In6.Cu") (net 47))
  (segment (start 110.085 114.383492) (end 110.085 115.016508) (width 0.109) (layer "In6.Cu") (net 47))
  (segment (start 106.239387 114.344551) (end 106.25233 114.307563) (width 0.109) (layer "In6.Cu") (net 47))
  (segment (start 105.950889 115.153328) (end 105.98407 115.174177) (width 0.109) (layer "In6.Cu") (net 47))
  (segment (start 107.639387 114.344551) (end 107.65233 114.307563) (width 0.109) (layer "In6.Cu") (net 47))
  (segment (start 104.79682 115.125618) (end 104.817669 115.092437) (width 0.109) (layer "In6.Cu") (net 47))
  (segment (start 106.917669 115.092437) (end 106.930612 115.055449) (width 0.109) (layer "In6.Cu") (net 47))
  (segment (start 105.98407 115.174177) (end 106.021058 115.18712) (width 0.109) (layer "In6.Cu") (net 47))
  (segment (start 109.800889 114.246672) (end 109.83407 114.225823) (width 0.109) (layer "In6.Cu") (net 47))
  (segment (start 105.189387 115.055449) (end 105.20233 115.092437) (width 0.109) (layer "In6.Cu") (net 47))
  (segment (start 104.830612 115.055449) (end 104.835 115.016508) (width 0.109) (layer "In6.Cu") (net 47))
  (segment (start 105.539387 114.344551) (end 105.55233 114.307563) (width 0.109) (layer "In6.Cu") (net 47))
  (segment (start 106.371058 114.21288) (end 106.41 114.208492) (width 0.109) (layer "In6.Cu") (net 47))
  (segment (start 108.198941 115.18712) (end 108.235929 115.174177) (width 0.109) (layer "In6.Cu") (net 47))
  (segment (start 109.69682 115.125618) (end 109.717669 115.092437) (width 0.109) (layer "In6.Cu") (net 47))
  (segment (start 106.51911 114.246672) (end 106.54682 114.274382) (width 0.109) (layer "In6.Cu") (net 47))
  (segment (start 110.335929 115.174177) (end 110.36911 115.153328) (width 0.109) (layer "In6.Cu") (net 47))
  (segment (start 108.08407 115.174177) (end 108.121058 115.18712) (width 0.109) (layer "In6.Cu") (net 47))
  (segment (start 104.50233 115.092437) (end 104.523179 115.125618) (width 0.109) (layer "In6.Cu") (net 47))
  (segment (start 106.19682 115.125618) (end 106.217669 115.092437) (width 0.109) (layer "In6.Cu") (net 47))
  (segment (start 106.798941 115.18712) (end 106.835929 115.174177) (width 0.109) (layer "In6.Cu") (net 47))
  (segment (start 105.46911 115.153328) (end 105.49682 115.125618) (width 0.109) (layer "In6.Cu") (net 47))
  (segment (start 110.123179 115.125618) (end 110.150889 115.153328) (width 0.109) (layer "In6.Cu") (net 47))
  (segment (start 107.967669 114.307563) (end 107.980612 114.344551) (width 0.109) (layer "In6.Cu") (net 47))
  (segment (start 110.04682 114.274382) (end 110.067669 114.307563) (width 0.109) (layer "In6.Cu") (net 47))
  (segment (start 110.36911 115.153328) (end 110.39682 115.125618) (width 0.109) (layer "In6.Cu") (net 47))
  (segment (start 125.3 101.49) (end 124.855 101.045) (width 0.109) (layer "In6.Cu") (net 47))
  (segment (start 106.939387 114.344551) (end 106.95233 114.307563) (width 0.109) (layer "In6.Cu") (net 47))
  (segment (start 104.621058 115.18712) (end 104.66 115.191508) (width 0.109) (layer "In6.Cu") (net 47))
  (segment (start 109.248941 114.21288) (end 109.285929 114.225823) (width 0.109) (layer "In6.Cu") (net 47))
  (segment (start 104.85233 114.307563) (end 104.873179 114.274382) (width 0.109) (layer "In6.Cu") (net 47))
  (segment (start 108.585929 114.225823) (end 108.61911 114.246672) (width 0.109) (layer "In6.Cu") (net 47))
  (segment (start 104.480612 114.836058) (end 104.485 114.875) (width 0.109) (layer "In6.Cu") (net 47))
  (segment (start 109.367669 114.307563) (end 109.380612 114.344551) (width 0.109) (layer "In6.Cu") (net 47))
  (segment (start 109.285929 114.225823) (end 109.31911 114.246672) (width 0.109) (layer "In6.Cu") (net 47))
  (segment (start 109.34682 114.274382) (end 109.367669 114.307563) (width 0.109) (layer "In6.Cu") (net 47))
  (segment (start 106.835929 115.174177) (end 106.86911 115.153328) (width 0.109) (layer "In6.Cu") (net 47))
  (segment (start 105.573179 114.274382) (end 105.600889 114.246672) (width 0.109) (layer "In6.Cu") (net 47))
  (segment (start 105.11911 114.246672) (end 105.14682 114.274382) (width 0.109) (layer "In6.Cu") (net 47))
  (segment (start 106.06 115.191508) (end 106.098941 115.18712) (width 0.109) (layer "In6.Cu") (net 47))
  (segment (start 104.971058 114.21288) (end 105.01 114.208492) (width 0.109) (layer "In6.Cu") (net 47))
  (segment (start 109.56 115.191508) (end 109.598941 115.18712) (width 0.109) (layer "In6.Cu") (net 47))
  (segment (start 105.785929 114.225823) (end 105.81911 114.246672) (width 0.109) (layer "In6.Cu") (net 47))
  (segment (start 105.885 114.383492) (end 105.885 115.016508) (width 0.109) (layer "In6.Cu") (net 47))
  (segment (start 108.121058 115.18712) (end 108.16 115.191508) (width 0.109) (layer "In6.Cu") (net 47))
  (segment (start 106.135929 115.174177) (end 106.16911 115.153328) (width 0.109) (layer "In6.Cu") (net 47))
  (segment (start 107.24682 114.274382) (end 107.267669 114.307563) (width 0.109) (layer "In6.Cu") (net 47))
  (segment (start 108.339387 114.344551) (end 108.35233 114.307563) (width 0.109) (layer "In6.Cu") (net 47))
  (segment (start 108.471058 114.21288) (end 108.51 114.208492) (width 0.109) (layer "In6.Cu") (net 47))
  (segment (start 106.485929 114.225823) (end 106.51911 114.246672) (width 0.109) (layer "In6.Cu") (net 47))
  (segment (start 110.571058 114.21288) (end 110.61 114.208492) (width 0.109) (layer "In6.Cu") (net 47))
  (segment (start 109.730612 115.055449) (end 109.735 115.016508) (width 0.109) (layer "In6.Cu") (net 47))
  (segment (start 110.61 114.208492) (end 110.648941 114.21288) (width 0.109) (layer "In6.Cu") (net 47))
  (segment (start 109.735 114.383492) (end 109.739387 114.344551) (width 0.109) (layer "In6.Cu") (net 47))
  (segment (start 105.55233 114.307563) (end 105.573179 114.274382) (width 0.109) (layer "In6.Cu") (net 47))
  (segment (start 110.823179 114.634111) (end 110.850889 114.661821) (width 0.109) (layer "In6.Cu") (net 47))
  (segment (start 105.889387 115.055449) (end 105.90233 115.092437) (width 0.109) (layer "In6.Cu") (net 47))
  (segment (start 106.567669 114.307563) (end 106.580612 114.344551) (width 0.109) (layer "In6.Cu") (net 47))
  (segment (start 108.51 114.208492) (end 108.548941 114.21288) (width 0.109) (layer "In6.Cu") (net 47))
  (segment (start 104.41911 114.738179) (end 104.44682 114.765889) (width 0.109) (layer "In6.Cu") (net 47))
  (segment (start 110.298941 115.18712) (end 110.335929 115.174177) (width 0.109) (layer "In6.Cu") (net 47))
  (segment (start 110.10233 115.092437) (end 110.123179 115.125618) (width 0.109) (layer "In6.Cu") (net 47))
  (segment (start 105.71 114.208492) (end 105.748941 114.21288) (width 0.109) (layer "In6.Cu") (net 47))
  (segment (start 108.235929 115.174177) (end 108.26911 115.153328) (width 0.109) (layer "In6.Cu") (net 47))
  (segment (start 108.00233 115.092437) (end 108.023179 115.125618) (width 0.109) (layer "In6.Cu") (net 47))
  (segment (start 107.848941 114.21288) (end 107.885929 114.225823) (width 0.109) (layer "In6.Cu") (net 47))
  (segment (start 109.948941 114.21288) (end 109.985929 114.225823) (width 0.109) (layer "In6.Cu") (net 47))
  (segment (start 110.71911 114.246672) (end 110.74682 114.274382) (width 0.109) (layer "In6.Cu") (net 47))
  (segment (start 104.485 114.875) (end 104.485 115.016508) (width 0.109) (layer "In6.Cu") (net 47))
  (segment (start 106.935 115.016508) (end 106.935 114.383492) (width 0.109) (layer "In6.Cu") (net 47))
  (segment (start 107.700889 114.246672) (end 107.73407 114.225823) (width 0.109) (layer "In6.Cu") (net 47))
  (segment (start 105.49682 115.125618) (end 105.517669 115.092437) (width 0.109) (layer "In6.Cu") (net 47))
  (segment (start 105.923179 115.125618) (end 105.950889 115.153328) (width 0.109) (layer "In6.Cu") (net 47))
  (segment (start 110.785 114.383492) (end 110.785 114.525) (width 0.109) (layer "In6.Cu") (net 47))
  (segment (start 104.385929 114.71733) (end 104.41911 114.738179) (width 0.109) (layer "In6.Cu") (net 47))
  (segment (start 105.535 115.016508) (end 105.535 114.383492) (width 0.109) (layer "In6.Cu") (net 47))
  (segment (start 105.01 114.208492) (end 105.048941 114.21288) (width 0.109) (layer "In6.Cu") (net 47))
  (segment (start 107.323179 115.125618) (end 107.350889 115.153328) (width 0.109) (layer "In6.Cu") (net 47))
  (segment (start 106.230612 115.055449) (end 106.235 115.016508) (width 0.109) (layer "In6.Cu") (net 47))
  (segment (start 104.44682 114.765889) (end 104.467669 114.79907) (width 0.109) (layer "In6.Cu") (net 47))
  (segment (start 109.380612 114.344551) (end 109.385 114.383492) (width 0.109) (layer "In6.Cu") (net 47))
  (segment (start 108.99682 115.125618) (end 109.017669 115.092437) (width 0.109) (layer "In6.Cu") (net 47))
  (segment (start 107.673179 114.274382) (end 107.700889 114.246672) (width 0.109) (layer "In6.Cu") (net 47))
  (segment (start 104.873179 114.274382) (end 104.900889 114.246672) (width 0.109) (layer "In6.Cu") (net 47))
  (segment (start 105.398941 115.18712) (end 105.435929 115.174177) (width 0.109) (layer "In6.Cu") (net 47))
  (segment (start 105.517669 115.092437) (end 105.530612 115.055449) (width 0.109) (layer "In6.Cu") (net 47))
  (segment (start 108.43407 114.225823) (end 108.471058 114.21288) (width 0.109) (layer "In6.Cu") (net 47))
  (segment (start 109.385 114.383492) (end 109.385 115.016508) (width 0.109) (layer "In6.Cu") (net 47))
  (segment (start 104.817669 115.092437) (end 104.830612 115.055449) (width 0.109) (layer "In6.Cu") (net 47))
  (segment (start 104.523179 115.125618) (end 104.550889 115.153328) (width 0.109) (layer "In6.Cu") (net 47))
  (segment (start 106.021058 115.18712) (end 106.06 115.191508) (width 0.109) (layer "In6.Cu") (net 47))
  (segment (start 110.067669 114.307563) (end 110.080612 114.344551) (width 0.109) (layer "In6.Cu") (net 47))
  (segment (start 110.439387 114.344551) (end 110.45233 114.307563) (width 0.109) (layer "In6.Cu") (net 47))
  (segment (start 107.000889 114.246672) (end 107.03407 114.225823) (width 0.109) (layer "In6.Cu") (net 47))
  (segment (start 106.935 114.383492) (end 106.939387 114.344551) (width 0.109) (layer "In6.Cu") (net 47))
  (segment (start 107.30233 115.092437) (end 107.323179 115.125618) (width 0.109) (layer "In6.Cu") (net 47))
  (segment (start 110.921058 114.695613) (end 110.96 114.7) (width 0.109) (layer "In6.Cu") (net 47))
  (segment (start 106.41 114.208492) (end 106.448941 114.21288) (width 0.109) (layer "In6.Cu") (net 47))
  (segment (start 105.84682 114.274382) (end 105.867669 114.307563) (width 0.109) (layer "In6.Cu") (net 47))
  (segment (start 106.585 114.383492) (end 106.585 115.016508) (width 0.109) (layer "In6.Cu") (net 47))
  (segment (start 107.071058 114.21288) (end 107.11 114.208492) (width 0.109) (layer "In6.Cu") (net 47))
  (segment (start 107.46 115.191508) (end 107.498941 115.18712) (width 0.109) (layer "In6.Cu") (net 47))
  (segment (start 109.030612 115.055449) (end 109.035 115.016508) (width 0.109) (layer "In6.Cu") (net 47))
  (segment (start 106.217669 115.092437) (end 106.230612 115.055449) (width 0.109) (layer "In6.Cu") (net 47))
  (segment (start 109.985929 114.225823) (end 110.01911 114.246672) (width 0.109) (layer "In6.Cu") (net 47))
  (segment (start 122.5 106.78) (end 123.18 106.1) (width 0.109) (layer "In6.Cu") (net 47))
  (segment (start 109.521058 115.18712) (end 109.56 115.191508) (width 0.109) (layer "In6.Cu") (net 47))
  (segment (start 108.26911 115.153328) (end 108.29682 115.125618) (width 0.109) (layer "In6.Cu") (net 47))
  (segment (start 110.767669 114.307563) (end 110.780612 114.344551) (width 0.109) (layer "In6.Cu") (net 47))
  (segment (start 104.550889 115.153328) (end 104.58407 115.174177) (width 0.109) (layer "In6.Cu") (net 47))
  (segment (start 107.635 115.016508) (end 107.635 114.383492) (width 0.109) (layer "In6.Cu") (net 47))
  (segment (start 109.598941 115.18712) (end 109.635929 115.174177) (width 0.109) (layer "In6.Cu") (net 47))
  (segment (start 108.723179 115.125618) (end 108.750889 115.153328) (width 0.109) (layer "In6.Cu") (net 47))
  (segment (start 108.689387 115.055449) (end 108.70233 115.092437) (width 0.109) (layer "In6.Cu") (net 47))
  (segment (start 107.498941 115.18712) (end 107.535929 115.174177) (width 0.109) (layer "In6.Cu") (net 47))
  (segment (start 107.350889 115.153328) (end 107.38407 115.174177) (width 0.109) (layer "In6.Cu") (net 47))
  (segment (start 110.45233 114.307563) (end 110.473179 114.274382) (width 0.109) (layer "In6.Cu") (net 47))
  (segment (start 110.435 114.383492) (end 110.439387 114.344551) (width 0.109) (layer "In6.Cu") (net 47))
  (segment (start 108.680612 114.344551) (end 108.685 114.383492) (width 0.109) (layer "In6.Cu") (net 47))
  (segment (start 89.4415 113.804) (end 89.8625 114.225) (width 0.109) (layer "In6.Cu") (net 47))
  (segment (start 107.267669 114.307563) (end 107.280612 114.344551) (width 0.109) (layer "In6.Cu") (net 47))
  (segment (start 108.821058 115.18712) (end 108.86 115.191508) (width 0.109) (layer "In6.Cu") (net 47))
  (segment (start 109.039387 114.344551) (end 109.05233 114.307563) (width 0.109) (layer "In6.Cu") (net 47))
  (segment (start 106.86911 115.153328) (end 106.89682 115.125618) (width 0.109) (layer "In6.Cu") (net 47))
  (segment (start 108.96911 115.153328) (end 108.99682 115.125618) (width 0.109) (layer "In6.Cu") (net 47))
  (segment (start 110.221058 115.18712) (end 110.26 115.191508) (width 0.109) (layer "In6.Cu") (net 47))
  (segment (start 107.11 114.208492) (end 107.148941 114.21288) (width 0.109) (layer "In6.Cu") (net 47))
  (segment (start 106.930612 115.055449) (end 106.935 115.016508) (width 0.109) (layer "In6.Cu") (net 47))
  (segment (start 106.098941 115.18712) (end 106.135929 115.174177) (width 0.109) (layer "In6.Cu") (net 47))
  (segment (start 105.36 115.191508) (end 105.398941 115.18712) (width 0.109) (layer "In6.Cu") (net 47))
  (segment (start 106.33407 114.225823) (end 106.371058 114.21288) (width 0.109) (layer "In6.Cu") (net 47))
  (segment (start 104.348941 114.704387) (end 104.385929 114.71733) (width 0.109) (layer "In6.Cu") (net 47))
  (segment (start 93.275 114.225) (end 93.45 114.05) (width 0.109) (layer "In6.Cu") (net 47))
  (segment (start 104.900889 114.246672) (end 104.93407 114.225823) (width 0.109) (layer "In6.Cu") (net 47))
  (segment (start 123.18 106.1) (end 123.86 106.1) (width 0.109) (layer "In6.Cu") (net 47))
  (segment (start 125.3 104.66) (end 125.3 101.49) (width 0.109) (layer "In6.Cu") (net 47))
  (segment (start 104.835 115.016508) (end 104.835 114.383492) (width 0.109) (layer "In6.Cu") (net 47))
  (segment (start 110.26 115.191508) (end 110.298941 115.18712) (width 0.109) (layer "In6.Cu") (net 47))
  (segment (start 110.435 115.016508) (end 110.435 114.383492) (width 0.109) (layer "In6.Cu") (net 47))
  (segment (start 105.167669 114.307563) (end 105.180612 114.344551) (width 0.109) (layer "In6.Cu") (net 47))
  (segment (start 105.885 115.016508) (end 105.889387 115.055449) (width 0.109) (layer "In6.Cu") (net 47))
  (segment (start 107.73407 114.225823) (end 107.771058 114.21288) (width 0.109) (layer "In6.Cu") (net 47))
  (segment (start 120.231417 102.036907) (end 120.191683 102.027837) (width 0.182) (layer "F.Cu") (net 48))
  (segment (start 120.612337 102.08) (end 120.3 102.08) (width 0.182) (layer "F.Cu") (net 48))
  (segment (start 120.3 102.08) (end 120.268136 102.05459) (width 0.182) (layer "F.Cu") (net 48))
  (segment (start 119.785226 101.822613) (end 119.810635 101.790749) (width 0.182) (layer "F.Cu") (net 48))
  (segment (start 119.904976 102.161483) (end 119.864221 102.161483) (width 0.182) (layer "F.Cu") (net 48))
  (segment (start 120.042613 102.08) (end 120.013292 102.109321) (width 0.182) (layer "F.Cu") (net 48))
  (segment (start 119.725 101.53049) (end 119.725 101.43) (width 0.182) (layer "F.Cu") (net 48))
  (segment (start 119.755905 102.109321) (end 119.730495 102.077457) (width 0.182) (layer "F.Cu") (net 48))
  (segment (start 120.268136 102.05459) (end 120.231417 102.036907) (width 0.182) (layer "F.Cu") (net 48))
  (segment (start 119.944709 102.152414) (end 119.904976 102.161483) (width 0.182) (layer "F.Cu") (net 48))
  (segment (start 120.150928 102.027837) (end 120.111195 102.036907) (width 0.182) (layer "F.Cu") (net 48))
  (segment (start 119.837388 101.673542) (end 119.828319 101.633809) (width 0.182) (layer "F.Cu") (net 48))
  (segment (start 119.730495 101.883798) (end 119.755905 101.851934) (width 0.182) (layer "F.Cu") (net 48))
  (segment (start 120.191683 102.027837) (end 120.150928 102.027837) (width 0.182) (layer "F.Cu") (net 48))
  (segment (start 120.013292 102.109321) (end 119.981428 102.134731) (width 0.182) (layer "F.Cu") (net 48))
  (segment (start 120.111195 102.036907) (end 120.074476 102.05459) (width 0.182) (layer "F.Cu") (net 48))
  (segment (start 119.730495 102.077457) (end 119.712811 102.040739) (width 0.182) (layer "F.Cu") (net 48))
  (segment (start 120.64185 102.109513) (end 120.612337 102.08) (width 0.182) (layer "F.Cu") (net 48))
  (segment (start 89.4415 113.169) (end 89.8265 112.859) (width 0.182) (layer "F.Cu") (net 48))
  (segment (start 119.703742 102.001005) (end 119.703742 101.96025) (width 0.182) (layer "F.Cu") (net 48))
  (segment (start 120.074476 102.05459) (end 120.042613 102.08) (width 0.182) (layer "F.Cu") (net 48))
  (segment (start 119.864221 102.161483) (end 119.824487 102.152414) (width 0.182) (layer "F.Cu") (net 48))
  (segment (start 119.712811 102.040739) (end 119.703742 102.001005) (width 0.182) (layer "F.Cu") (net 48))
  (segment (start 119.725 101.43) (end 119.879 101.276) (width 0.182) (layer "F.Cu") (net 48))
  (segment (start 119.828319 101.754031) (end 119.837388 101.714297) (width 0.182) (layer "F.Cu") (net 48))
  (segment (start 119.837388 101.714297) (end 119.837388 101.673542) (width 0.182) (layer "F.Cu") (net 48))
  (segment (start 119.981428 102.134731) (end 119.944709 102.152414) (width 0.182) (layer "F.Cu") (net 48))
  (segment (start 119.703742 101.96025) (end 119.712811 101.920516) (width 0.182) (layer "F.Cu") (net 48))
  (segment (start 119.755905 101.851934) (end 119.785226 101.822613) (width 0.182) (layer "F.Cu") (net 48))
  (segment (start 119.828319 101.633809) (end 119.725 101.53049) (width 0.182) (layer "F.Cu") (net 48))
  (segment (start 119.879 101.276) (end 119.879 100.6951) (width 0.182) (layer "F.Cu") (net 48))
  (segment (start 119.810635 101.790749) (end 119.828319 101.754031) (width 0.182) (layer "F.Cu") (net 48))
  (segment (start 119.712811 101.920516) (end 119.730495 101.883798) (width 0.182) (layer "F.Cu") (net 48))
  (segment (start 119.824487 102.152414) (end 119.787768 102.134731) (width 0.182) (layer "F.Cu") (net 48))
  (segment (start 119.787768 102.134731) (end 119.755905 102.109321) (width 0.182) (layer "F.Cu") (net 48))
  (via (at 120.64185 102.109513) (size 0.45) (drill 0.1) (layers "F.Cu" "B.Cu") (net 48))
  (via (at 89.4415 113.169) (size 0.45) (drill 0.1) (layers "F.Cu" "B.Cu") (net 48))
  (segment (start 102.729387 115.783723) (end 102.74233 115.820711) (width 0.109) (layer "In6.Cu") (net 48))
  (segment (start 104.125 115.275218) (end 104.125 115.335) (width 0.109) (layer "In6.Cu") (net 48))
  (segment (start 104.08682 115.166108) (end 104.107669 115.199289) (width 0.109) (layer "In6.Cu") (net 48))
  (segment (start 103.840889 115.138398) (end 103.87407 115.117549) (width 0.109) (layer "In6.Cu") (net 48))
  (segment (start 103.638941 115.915394) (end 103.675929 115.902451) (width 0.109) (layer "In6.Cu") (net 48))
  (segment (start 104.125 115.335) (end 104.129387 115.373942) (width 0.109) (layer "In6.Cu") (net 48))
  (segment (start 102.707669 115.60907) (end 102.720612 115.646058) (width 0.109) (layer "In6.Cu") (net 48))
  (segment (start 103.463179 115.853892) (end 103.490889 115.881602) (width 0.109) (layer "In6.Cu") (net 48))
  (segment (start 104.14233 115.41093) (end 104.163179 115.444111) (width 0.109) (layer "In6.Cu") (net 48))
  (segment (start 103.911058 115.104606) (end 103.95 115.100218) (width 0.109) (layer "In6.Cu") (net 48))
  (segment (start 104.163179 115.444111) (end 104.190889 115.471821) (width 0.109) (layer "In6.Cu") (net 48))
  (segment (start 104.190889 115.471821) (end 104.22407 115.49267) (width 0.109) (layer "In6.Cu") (net 48))
  (segment (start 103.00911 115.881602) (end 103.03682 115.853892) (width 0.109) (layer "In6.Cu") (net 48))
  (segment (start 103.779387 115.236277) (end 103.79233 115.199289) (width 0.109) (layer "In6.Cu") (net 48))
  (segment (start 103.44233 115.820711) (end 103.463179 115.853892) (width 0.109) (layer "In6.Cu") (net 48))
  (segment (start 123.9 106.78) (end 124.5 106.78) (width 0.109) (layer "In6.Cu") (net 48))
  (segment (start 103.38682 115.166108) (end 103.407669 115.199289) (width 0.109) (layer "In6.Cu") (net 48))
  (segment (start 102.31 115.51) (end 102.55 115.51) (width 0.109) (layer "In6.Cu") (net 48))
  (segment (start 104.3 115.51) (end 118.45 115.51) (width 0.109) (layer "In6.Cu") (net 48))
  (segment (start 123.225 102.305) (end 123.225 102.825) (width 0.109) (layer "In6.Cu") (net 48))
  (segment (start 103.95 115.100218) (end 103.988941 115.104606) (width 0.109) (layer "In6.Cu") (net 48))
  (segment (start 102.588941 115.514387) (end 102.625929 115.52733) (width 0.109) (layer "In6.Cu") (net 48))
  (segment (start 126 100.795586) (end 124.904414 99.7) (width 0.109) (layer "In6.Cu") (net 48))
  (segment (start 102.625929 115.52733) (end 102.65911 115.548179) (width 0.109) (layer "In6.Cu") (net 48))
  (segment (start 103.425 115.744782) (end 103.429387 115.783723) (width 0.109) (layer "In6.Cu") (net 48))
  (segment (start 103.52407 115.902451) (end 103.561058 115.915394) (width 0.109) (layer "In6.Cu") (net 48))
  (segment (start 103.288941 115.104606) (end 103.325929 115.117549) (width 0.109) (layer "In6.Cu") (net 48))
  (segment (start 94.8 114.65) (end 101.45 114.65) (width 0.109) (layer "In6.Cu") (net 48))
  (segment (start 103.490889 115.881602) (end 103.52407 115.902451) (width 0.109) (layer "In6.Cu") (net 48))
  (segment (start 124.5 106.78) (end 126 105.28) (width 0.109) (layer "In6.Cu") (net 48))
  (segment (start 126 105.28) (end 126 100.795586) (width 0.109) (layer "In6.Cu") (net 48))
  (segment (start 102.725 115.744782) (end 102.729387 115.783723) (width 0.109) (layer "In6.Cu") (net 48))
  (segment (start 101.45 114.65) (end 102.31 115.51) (width 0.109) (layer "In6.Cu") (net 48))
  (segment (start 102.82407 115.902451) (end 102.861058 115.915394) (width 0.109) (layer "In6.Cu") (net 48))
  (segment (start 103.775 115.275218) (end 103.779387 115.236277) (width 0.109) (layer "In6.Cu") (net 48))
  (segment (start 103.25 115.100218) (end 103.288941 115.104606) (width 0.109) (layer "In6.Cu") (net 48))
  (segment (start 88.992 114.059) (end 89.383 114.45) (width 0.109) (layer "In6.Cu") (net 48))
  (segment (start 104.120612 115.236277) (end 104.125 115.275218) (width 0.109) (layer "In6.Cu") (net 48))
  (segment (start 88.992 113.6185) (end 88.992 114.059) (width 0.109) (layer "In6.Cu") (net 48))
  (segment (start 103.140889 115.138398) (end 103.17407 115.117549) (width 0.109) (layer "In6.Cu") (net 48))
  (segment (start 103.73682 115.853892) (end 103.757669 115.820711) (width 0.109) (layer "In6.Cu") (net 48))
  (segment (start 103.075 115.275218) (end 103.079387 115.236277) (width 0.109) (layer "In6.Cu") (net 48))
  (segment (start 102.68682 115.575889) (end 102.707669 115.60907) (width 0.109) (layer "In6.Cu") (net 48))
  (segment (start 103.6 115.919782) (end 103.638941 115.915394) (width 0.109) (layer "In6.Cu") (net 48))
  (segment (start 103.420612 115.236277) (end 103.425 115.275218) (width 0.109) (layer "In6.Cu") (net 48))
  (segment (start 103.057669 115.820711) (end 103.070612 115.783723) (width 0.109) (layer "In6.Cu") (net 48))
  (segment (start 89.383 114.45) (end 94.6 114.45) (width 0.109) (layer "In6.Cu") (net 48))
  (segment (start 94.6 114.45) (end 94.8 114.65) (width 0.109) (layer "In6.Cu") (net 48))
  (segment (start 103.429387 115.783723) (end 103.44233 115.820711) (width 0.109) (layer "In6.Cu") (net 48))
  (segment (start 103.70911 115.881602) (end 103.73682 115.853892) (width 0.109) (layer "In6.Cu") (net 48))
  (segment (start 103.407669 115.199289) (end 103.420612 115.236277) (width 0.109) (layer "In6.Cu") (net 48))
  (segment (start 102.763179 115.853892) (end 102.790889 115.881602) (width 0.109) (layer "In6.Cu") (net 48))
  (segment (start 103.075 115.744782) (end 103.075 115.275218) (width 0.109) (layer "In6.Cu") (net 48))
  (segment (start 103.35911 115.138398) (end 103.38682 115.166108) (width 0.109) (layer "In6.Cu") (net 48))
  (segment (start 103.79233 115.199289) (end 103.813179 115.166108) (width 0.109) (layer "In6.Cu") (net 48))
  (segment (start 121.739513 102.109513) (end 120.64185 102.109513) (width 0.109) (layer "In6.Cu") (net 48))
  (segment (start 102.74233 115.820711) (end 102.763179 115.853892) (width 0.109) (layer "In6.Cu") (net 48))
  (segment (start 123.6 99.7) (end 123.1 100.2) (width 0.109) (layer "In6.Cu") (net 48))
  (segment (start 123.02 103.03) (end 122.66 103.03) (width 0.109) (layer "In6.Cu") (net 48))
  (segment (start 103.113179 115.166108) (end 103.140889 115.138398) (width 0.109) (layer "In6.Cu") (net 48))
  (segment (start 103.675929 115.902451) (end 103.70911 115.881602) (width 0.109) (layer "In6.Cu") (net 48))
  (segment (start 124.904414 99.7) (end 123.6 99.7) (width 0.109) (layer "In6.Cu") (net 48))
  (segment (start 102.65911 115.548179) (end 102.68682 115.575889) (width 0.109) (layer "In6.Cu") (net 48))
  (segment (start 102.725 115.685) (end 102.725 115.744782) (width 0.109) (layer "In6.Cu") (net 48))
  (segment (start 102.720612 115.646058) (end 102.725 115.685) (width 0.109) (layer "In6.Cu") (net 48))
  (segment (start 104.129387 115.373942) (end 104.14233 115.41093) (width 0.109) (layer "In6.Cu") (net 48))
  (segment (start 103.17407 115.117549) (end 103.211058 115.104606) (width 0.109) (layer "In6.Cu") (net 48))
  (segment (start 103.87407 115.117549) (end 103.911058 115.104606) (width 0.109) (layer "In6.Cu") (net 48))
  (segment (start 103.03682 115.853892) (end 103.057669 115.820711) (width 0.109) (layer "In6.Cu") (net 48))
  (segment (start 103.561058 115.915394) (end 103.6 115.919782) (width 0.109) (layer "In6.Cu") (net 48))
  (segment (start 118.45 115.51) (end 123.2 110.76) (width 0.109) (layer "In6.Cu") (net 48))
  (segment (start 123.1 102.18) (end 123.225 102.305) (width 0.109) (layer "In6.Cu") (net 48))
  (segment (start 89.4415 113.169) (end 88.992 113.6185) (width 0.109) (layer "In6.Cu") (net 48))
  (segment (start 103.211058 115.104606) (end 103.25 115.100218) (width 0.109) (layer "In6.Cu") (net 48))
  (segment (start 104.107669 115.199289) (end 104.120612 115.236277) (width 0.109) (layer "In6.Cu") (net 48))
  (segment (start 103.425 115.275218) (end 103.425 115.744782) (width 0.109) (layer "In6.Cu") (net 48))
  (segment (start 103.079387 115.236277) (end 103.09233 115.199289) (width 0.109) (layer "In6.Cu") (net 48))
  (segment (start 104.025929 115.117549) (end 104.05911 115.138398) (width 0.109) (layer "In6.Cu") (net 48))
  (segment (start 102.55 115.51) (end 102.588941 115.514387) (width 0.109) (layer "In6.Cu") (net 48))
  (segment (start 102.938941 115.915394) (end 102.975929 115.902451) (width 0.109) (layer "In6.Cu") (net 48))
  (segment (start 103.070612 115.783723) (end 103.075 115.744782) (width 0.109) (layer "In6.Cu") (net 48))
  (segment (start 123.225 102.825) (end 123.02 103.03) (width 0.109) (layer "In6.Cu") (net 48))
  (segment (start 123.2 107.48) (end 123.9 106.78) (width 0.109) (layer "In6.Cu") (net 48))
  (segment (start 103.09233 115.199289) (end 103.113179 115.166108) (width 0.109) (layer "In6.Cu") (net 48))
  (segment (start 123.2 110.76) (end 123.2 107.48) (width 0.109) (layer "In6.Cu") (net 48))
  (segment (start 122.66 103.03) (end 121.739513 102.109513) (width 0.109) (layer "In6.Cu") (net 48))
  (segment (start 104.261058 115.505613) (end 104.3 115.51) (width 0.109) (layer "In6.Cu") (net 48))
  (segment (start 123.1 100.2) (end 123.1 102.18) (width 0.109) (layer "In6.Cu") (net 48))
  (segment (start 103.775 115.744782) (end 103.775 115.275218) (width 0.109) (layer "In6.Cu") (net 48))
  (segment (start 103.770612 115.783723) (end 103.775 115.744782) (width 0.109) (layer "In6.Cu") (net 48))
  (segment (start 102.861058 115.915394) (end 102.9 115.919782) (width 0.109) (layer "In6.Cu") (net 48))
  (segment (start 103.757669 115.820711) (end 103.770612 115.783723) (width 0.109) (layer "In6.Cu") (net 48))
  (segment (start 103.813179 115.166108) (end 103.840889 115.138398) (width 0.109) (layer "In6.Cu") (net 48))
  (segment (start 104.05911 115.138398) (end 104.08682 115.166108) (width 0.109) (layer "In6.Cu") (net 48))
  (segment (start 102.975929 115.902451) (end 103.00911 115.881602) (width 0.109) (layer "In6.Cu") (net 48))
  (segment (start 102.9 115.919782) (end 102.938941 115.915394) (width 0.109) (layer "In6.Cu") (net 48))
  (segment (start 103.325929 115.117549) (end 103.35911 115.138398) (width 0.109) (layer "In6.Cu") (net 48))
  (segment (start 102.790889 115.881602) (end 102.82407 115.902451) (width 0.109) (layer "In6.Cu") (net 48))
  (segment (start 103.988941 115.104606) (end 104.025929 115.117549) (width 0.109) (layer "In6.Cu") (net 48))
  (segment (start 104.22407 115.49267) (end 104.261058 115.505613) (width 0.109) (layer "In6.Cu") (net 48))
  (segment (start 144.648424 87.464035) (end 145.44591 87.464035) (width 0.182) (layer "F.Cu") (net 49))
  (segment (start 144.033898 87.424328) (end 143.99939 87.446011) (width 0.182) (layer "F.Cu") (net 49))
  (segment (start 144.170948 86.957397) (end 144.142129 86.986215) (width 0.182) (layer "F.Cu") (net 49))
  (segment (start 144.102423 87.282035) (end 144.09786 87.322534) (width 0.182) (layer "F.Cu") (net 49))
  (segment (start 144.09786 87.322534) (end 144.084399 87.361002) (width 0.182) (layer "F.Cu") (net 49))
  (segment (start 144.243924 86.922254) (end 144.205456 86.935714) (width 0.182) (layer "F.Cu") (net 49))
  (segment (start 144.106986 87.059192) (end 144.102423 87.099691) (width 0.182) (layer "F.Cu") (net 49))
  (segment (start 144.46186 87.059192) (end 144.4484 87.020724) (width 0.182) (layer "F.Cu") (net 49))
  (segment (start 144.120446 87.020724) (end 144.106986 87.059192) (width 0.182) (layer "F.Cu") (net 49))
  (segment (start 144.397898 86.957398) (end 144.363391 86.935714) (width 0.182) (layer "F.Cu") (net 49))
  (segment (start 144.142129 86.986215) (end 144.120446 87.020724) (width 0.182) (layer "F.Cu") (net 49))
  (segment (start 144.062716 87.39551) (end 144.033898 87.424328) (width 0.182) (layer "F.Cu") (net 49))
  (segment (start 144.205456 86.935714) (end 144.170948 86.957397) (width 0.182) (layer "F.Cu") (net 49))
  (segment (start 144.648424 87.464035) (end 144.607925 87.459472) (width 0.182) (layer "F.Cu") (net 49))
  (segment (start 144.102423 87.099691) (end 144.102423 87.282035) (width 0.182) (layer "F.Cu") (net 49))
  (segment (start 144.50613 87.395511) (end 144.484447 87.361002) (width 0.182) (layer "F.Cu") (net 49))
  (segment (start 144.324923 86.922254) (end 144.284423 86.917691) (width 0.182) (layer "F.Cu") (net 49))
  (segment (start 144.426717 86.986216) (end 144.397898 86.957398) (width 0.182) (layer "F.Cu") (net 49))
  (segment (start 144.607925 87.459472) (end 144.569457 87.446011) (width 0.182) (layer "F.Cu") (net 49))
  (segment (start 144.284423 86.917691) (end 144.243924 86.922254) (width 0.182) (layer "F.Cu") (net 49))
  (segment (start 144.363391 86.935714) (end 144.324923 86.922254) (width 0.182) (layer "F.Cu") (net 49))
  (segment (start 144.569457 87.446011) (end 144.534948 87.424329) (width 0.182) (layer "F.Cu") (net 49))
  (segment (start 144.084399 87.361002) (end 144.062716 87.39551) (width 0.182) (layer "F.Cu") (net 49))
  (segment (start 144.534948 87.424329) (end 144.50613 87.395511) (width 0.182) (layer "F.Cu") (net 49))
  (segment (start 143.99939 87.446011) (end 143.960922 87.459472) (width 0.182) (layer "F.Cu") (net 49))
  (segment (start 144.466424 87.282035) (end 144.466423 87.099691) (width 0.182) (layer "F.Cu") (net 49))
  (segment (start 144.484447 87.361002) (end 144.470986 87.322534) (width 0.182) (layer "F.Cu") (net 49))
  (segment (start 144.4484 87.020724) (end 144.426717 86.986216) (width 0.182) (layer "F.Cu") (net 49))
  (segment (start 144.470986 87.322534) (end 144.466424 87.282035) (width 0.182) (layer "F.Cu") (net 49))
  (segment (start 144.466423 87.099691) (end 144.46186 87.059192) (width 0.182) (layer "F.Cu") (net 49))
  (segment (start 143.960922 87.459472) (end 143.920424 87.464035) (width 0.182) (layer "F.Cu") (net 49))
  (segment (start 143.621073 87.464) (end 143.920389 87.464) (width 0.182) (layer "F.Cu") (net 49))
  (segment (start 143.920389 87.464) (end 143.920424 87.464035) (width 0.182) (layer "F.Cu") (net 49))
  (segment (start 89.4415 109.359) (end 89.8265 109.049) (width 0.182) (layer "F.Cu") (net 49))
  (segment (start 143.342789 87.742284) (end 143.621073 87.464) (width 0.182) (layer "F.Cu") (net 49))
  (via (at 143.342789 87.742284) (size 0.45) (drill 0.1) (layers "F.Cu" "B.Cu") (net 49))
  (via (at 89.4415 109.359) (size 0.45) (drill 0.1) (layers "F.Cu" "B.Cu") (net 49))
  (segment (start 129.75529 99.094834) (end 129.777478 99.158243) (width 0.109) (layer "In4.Cu") (net 49))
  (segment (start 131.154834 99.785636) (end 131.218243 99.807824) (width 0.109) (layer "In4.Cu") (net 49))
  (segment (start 130.45045 98.147608) (end 130.497953 98.100105) (width 0.109) (layer "In4.Cu") (net 49))
  (segment (start 130.151756 99.807824) (end 130.215165 99.785636) (width 0.109) (layer "In4.Cu") (net 49))
  (segment (start 129.897953 99.749895) (end 129.954834 99.785636) (width 0.109) (layer "In4.Cu") (net 49))
  (segment (start 130.018243 99.807824) (end 130.085 99.815346) (width 0.109) (layer "In4.Cu") (net 49))
  (segment (start 129.792521 99.582102) (end 129.814709 99.645511) (width 0.109) (layer "In4.Cu") (net 49))
  (segment (start 130.497953 98.100105) (end 130.554834 98.064364) (width 0.109) (layer "In4.Cu") (net 49))
  (segment (start 130.385 98.334654) (end 130.392521 98.267898) (width 0.109) (layer "In4.Cu") (net 49))
  (segment (start 130.377478 99.582102) (end 130.385 99.515346) (width 0.109) (layer "In4.Cu") (net 49))
  (segment (start 131.577478 99.582102) (end 131.585 99.515346) (width 0.109) (layer "In4.Cu") (net 49))
  (segment (start 130.392521 98.267898) (end 130.414709 98.204489) (width 0.109) (layer "In4.Cu") (net 49))
  (segment (start 129.551756 98.932521) (end 129.615165 98.954709) (width 0.109) (layer "In4.Cu") (net 49))
  (segment (start 131.592521 99.158243) (end 131.614709 99.094834) (width 0.109) (layer "In4.Cu") (net 49))
  (segment (start 130.992521 99.582102) (end 131.014709 99.645511) (width 0.109) (layer "In4.Cu") (net 49))
  (segment (start 96.95 110.025) (end 111.2 110.025) (width 0.109) (layer "In4.Cu") (net 49))
  (segment (start 120.4625 107.525) (end 129.0625 98.925) (width 0.109) (layer "In4.Cu") (net 49))
  (segment (start 130.985 99.515346) (end 130.992521 99.582102) (width 0.109) (layer "In4.Cu") (net 49))
  (segment (start 131.285 99.815346) (end 131.351756 99.807824) (width 0.109) (layer "In4.Cu") (net 49))
  (segment (start 131.585 99.515346) (end 131.585 99.225) (width 0.109) (layer "In4.Cu") (net 49))
  (segment (start 144.191317 88.590812) (end 143.342789 87.742284) (width 0.109) (layer "In4.Cu") (net 49))
  (segment (start 129.785 99.225) (end 129.785 99.515346) (width 0.109) (layer "In4.Cu") (net 49))
  (segment (start 131.818243 98.932521) (end 131.885 98.925) (width 0.109) (layer "In4.Cu") (net 49))
  (segment (start 130.685 98.034654) (end 130.751756 98.042176) (width 0.109) (layer "In4.Cu") (net 49))
  (segment (start 131.097953 99.749895) (end 131.154834 99.785636) (width 0.109) (layer "In4.Cu") (net 49))
  (segment (start 113.7 107.525) (end 120.4625 107.525) (width 0.109) (layer "In4.Cu") (net 49))
  (segment (start 89.4415 109.359) (end 90.230511 108.569989) (width 0.109) (layer "In4.Cu") (net 49))
  (segment (start 131.05045 99.702392) (end 131.097953 99.749895) (width 0.109) (layer "In4.Cu") (net 49))
  (segment (start 131.65045 99.037953) (end 131.697953 98.99045) (width 0.109) (layer "In4.Cu") (net 49))
  (segment (start 130.919549 98.147608) (end 130.95529 98.204489) (width 0.109) (layer "In4.Cu") (net 49))
  (segment (start 129.777478 99.158243) (end 129.785 99.225) (width 0.109) (layer "In4.Cu") (net 49))
  (segment (start 129.0625 98.925) (end 129.485 98.925) (width 0.109) (layer "In4.Cu") (net 49))
  (segment (start 129.615165 98.954709) (end 129.672046 98.99045) (width 0.109) (layer "In4.Cu") (net 49))
  (segment (start 130.554834 98.064364) (end 130.618243 98.042176) (width 0.109) (layer "In4.Cu") (net 49))
  (segment (start 131.885 98.925) (end 141.45 98.925) (width 0.109) (layer "In4.Cu") (net 49))
  (segment (start 131.519549 99.702392) (end 131.55529 99.645511) (width 0.109) (layer "In4.Cu") (net 49))
  (segment (start 144.191317 96.183683) (end 144.191317 88.590812) (width 0.109) (layer "In4.Cu") (net 49))
  (segment (start 131.55529 99.645511) (end 131.577478 99.582102) (width 0.109) (layer "In4.Cu") (net 49))
  (segment (start 130.414709 98.204489) (end 130.45045 98.147608) (width 0.109) (layer "In4.Cu") (net 49))
  (segment (start 130.385 99.515346) (end 130.385 98.334654) (width 0.109) (layer "In4.Cu") (net 49))
  (segment (start 131.218243 99.807824) (end 131.285 99.815346) (width 0.109) (layer "In4.Cu") (net 49))
  (segment (start 130.751756 98.042176) (end 130.815165 98.064364) (width 0.109) (layer "In4.Cu") (net 49))
  (segment (start 95.494989 108.569989) (end 96.95 110.025) (width 0.109) (layer "In4.Cu") (net 49))
  (segment (start 131.697953 98.99045) (end 131.754834 98.954709) (width 0.109) (layer "In4.Cu") (net 49))
  (segment (start 131.754834 98.954709) (end 131.818243 98.932521) (width 0.109) (layer "In4.Cu") (net 49))
  (segment (start 130.35529 99.645511) (end 130.377478 99.582102) (width 0.109) (layer "In4.Cu") (net 49))
  (segment (start 130.985 98.334654) (end 130.985 99.515346) (width 0.109) (layer "In4.Cu") (net 49))
  (segment (start 131.614709 99.094834) (end 131.65045 99.037953) (width 0.109) (layer "In4.Cu") (net 49))
  (segment (start 130.872046 98.100105) (end 130.919549 98.147608) (width 0.109) (layer "In4.Cu") (net 49))
  (segment (start 129.485 98.925) (end 129.551756 98.932521) (width 0.109) (layer "In4.Cu") (net 49))
  (segment (start 129.954834 99.785636) (end 130.018243 99.807824) (width 0.109) (layer "In4.Cu") (net 49))
  (segment (start 129.814709 99.645511) (end 129.85045 99.702392) (width 0.109) (layer "In4.Cu") (net 49))
  (segment (start 131.014709 99.645511) (end 131.05045 99.702392) (width 0.109) (layer "In4.Cu") (net 49))
  (segment (start 130.319549 99.702392) (end 130.35529 99.645511) (width 0.109) (layer "In4.Cu") (net 49))
  (segment (start 131.415165 99.785636) (end 131.472046 99.749895) (width 0.109) (layer "In4.Cu") (net 49))
  (segment (start 130.95529 98.204489) (end 130.977478 98.267898) (width 0.109) (layer "In4.Cu") (net 49))
  (segment (start 111.2 110.025) (end 113.7 107.525) (width 0.109) (layer "In4.Cu") (net 49))
  (segment (start 130.272046 99.749895) (end 130.319549 99.702392) (width 0.109) (layer "In4.Cu") (net 49))
  (segment (start 141.45 98.925) (end 144.191317 96.183683) (width 0.109) (layer "In4.Cu") (net 49))
  (segment (start 130.815165 98.064364) (end 130.872046 98.100105) (width 0.109) (layer "In4.Cu") (net 49))
  (segment (start 131.472046 99.749895) (end 131.519549 99.702392) (width 0.109) (layer "In4.Cu") (net 49))
  (segment (start 130.977478 98.267898) (end 130.985 98.334654) (width 0.109) (layer "In4.Cu") (net 49))
  (segment (start 129.85045 99.702392) (end 129.897953 99.749895) (width 0.109) (layer "In4.Cu") (net 49))
  (segment (start 129.672046 98.99045) (end 129.719549 99.037953) (width 0.109) (layer "In4.Cu") (net 49))
  (segment (start 131.585 99.225) (end 131.592521 99.158243) (width 0.109) (layer "In4.Cu") (net 49))
  (segment (start 130.085 99.815346) (end 130.151756 99.807824) (width 0.109) (layer "In4.Cu") (net 49))
  (segment (start 131.351756 99.807824) (end 131.415165 99.785636) (width 0.109) (layer "In4.Cu") (net 49))
  (segment (start 130.215165 99.785636) (end 130.272046 99.749895) (width 0.109) (layer "In4.Cu") (net 49))
  (segment (start 130.618243 98.042176) (end 130.685 98.034654) (width 0.109) (layer "In4.Cu") (net 49))
  (segment (start 90.230511 108.569989) (end 95.494989 108.569989) (width 0.109) (layer "In4.Cu") (net 49))
  (segment (start 129.785 99.515346) (end 129.792521 99.582102) (width 0.109) (layer "In4.Cu") (net 49))
  (segment (start 129.719549 99.037953) (end 129.75529 99.094834) (width 0.109) (layer "In4.Cu") (net 49))
  (segment (start 89.8265 108.414) (end 90.3 108.1) (width 0.182) (layer "F.Cu") (net 50))
  (segment (start 144.109336 87.967764) (end 144.145514 87.963688) (width 0.182) (layer "F.Cu") (net 50))
  (segment (start 144.22052 87.967765) (end 144.254884 87.979789) (width 0.182) (layer "F.Cu") (net 50))
  (segment (start 143.97885 88.162453) (end 143.987004 88.090095) (width 0.182) (layer "F.Cu") (net 50))
  (segment (start 144.363029 88.196819) (end 144.382399 88.227647) (width 0.182) (layer "F.Cu") (net 50))
  (segment (start 142.915937 88.288862) (end 143.82034 88.288862) (width 0.182) (layer "F.Cu") (net 50))
  (segment (start 143.82034 88.288862) (end 143.856519 88.284784) (width 0.182) (layer "F.Cu") (net 50))
  (segment (start 143.947455 88.227646) (end 143.966825 88.196818) (width 0.182) (layer "F.Cu") (net 50))
  (segment (start 142.89683 88.307969) (end 142.915937 88.288862) (width 0.182) (layer "F.Cu") (net 50))
  (segment (start 144.044143 87.999159) (end 144.074971 87.979789) (width 0.182) (layer "F.Cu") (net 50))
  (segment (start 143.987004 88.090095) (end 143.999029 88.055731) (width 0.182) (layer "F.Cu") (net 50))
  (segment (start 144.018399 88.024904) (end 144.044143 87.999159) (width 0.182) (layer "F.Cu") (net 50))
  (segment (start 144.074971 87.979789) (end 144.109336 87.967764) (width 0.182) (layer "F.Cu") (net 50))
  (segment (start 144.382399 88.227647) (end 144.408143 88.253391) (width 0.182) (layer "F.Cu") (net 50))
  (segment (start 144.351005 88.162454) (end 144.363029 88.196819) (width 0.182) (layer "F.Cu") (net 50))
  (segment (start 144.473336 88.284786) (end 144.509516 88.288862) (width 0.182) (layer "F.Cu") (net 50))
  (segment (start 143.856519 88.284784) (end 143.890883 88.27276) (width 0.182) (layer "F.Cu") (net 50))
  (segment (start 144.145514 87.963688) (end 144.184341 87.963688) (width 0.182) (layer "F.Cu") (net 50))
  (segment (start 144.438971 88.272761) (end 144.473336 88.284786) (width 0.182) (layer "F.Cu") (net 50))
  (segment (start 144.254884 87.979789) (end 144.285712 87.999159) (width 0.182) (layer "F.Cu") (net 50))
  (segment (start 144.408143 88.253391) (end 144.438971 88.272761) (width 0.182) (layer "F.Cu") (net 50))
  (segment (start 144.311456 88.024904) (end 144.330826 88.055731) (width 0.182) (layer "F.Cu") (net 50))
  (segment (start 144.634688 88.288862) (end 144.959513 87.964037) (width 0.182) (layer "F.Cu") (net 50))
  (segment (start 144.285712 87.999159) (end 144.311456 88.024904) (width 0.182) (layer "F.Cu") (net 50))
  (segment (start 143.921711 88.25339) (end 143.947455 88.227646) (width 0.182) (layer "F.Cu") (net 50))
  (segment (start 144.342851 88.090097) (end 144.351005 88.162454) (width 0.182) (layer "F.Cu") (net 50))
  (segment (start 144.184341 87.963688) (end 144.22052 87.967765) (width 0.182) (layer "F.Cu") (net 50))
  (segment (start 143.890883 88.27276) (end 143.921711 88.25339) (width 0.182) (layer "F.Cu") (net 50))
  (segment (start 144.959513 87.964037) (end 145.44591 87.964037) (width 0.182) (layer "F.Cu") (net 50))
  (segment (start 144.509516 88.288862) (end 144.634688 88.288862) (width 0.182) (layer "F.Cu") (net 50))
  (segment (start 143.999029 88.055731) (end 144.018399 88.024904) (width 0.182) (layer "F.Cu") (net 50))
  (segment (start 142.272154 88.307969) (end 142.89683 88.307969) (width 0.182) (layer "F.Cu") (net 50))
  (segment (start 143.966825 88.196818) (end 143.97885 88.162453) (width 0.182) (layer "F.Cu") (net 50))
  (segment (start 144.330826 88.055731) (end 144.342851 88.090097) (width 0.182) (layer "F.Cu") (net 50))
  (via (at 90.3 108.1) (size 0.45) (drill 0.1) (layers "F.Cu" "B.Cu") (net 50))
  (via (at 142.915937 88.288862) (size 0.45) (drill 0.1) (layers "F.Cu" "B.Cu") (net 50))
  (segment (start 132.050003 102.125) (end 133.287435 100.887568) (width 0.109) (layer "In2.Cu") (net 50))
  (segment (start 134.296048 100.863571) (end 134.310997 100.798077) (width 0.109) (layer "In2.Cu") (net 50))
  (segment (start 134.310997 100.730898) (end 134.296048 100.665404) (width 0.109) (layer "In2.Cu") (net 50))
  (segment (start 133.586966 99.872295) (end 133.572017 99.806801) (width 0.109) (layer "In2.Cu") (net 50))
  (segment (start 133.572018 99.739621) (end 133.586966 99.674127) (width 0.109) (layer "In2.Cu") (net 50))
  (segment (start 134.381684 99.700761) (end 134.447179 99.685812) (width 0.109) (layer "In2.Cu") (net 50))
  (segment (start 134.296048 100.665404) (end 134.266901 100.604878) (width 0.109) (layer "In2.Cu") (net 50))
  (segment (start 133.710521 99.519195) (end 133.771048 99.490047) (width 0.109) (layer "In2.Cu") (net 50))
  (segment (start 134.225016 100.97662) (end 134.266901 100.924097) (width 0.109) (layer "In2.Cu") (net 50))
  (segment (start 133.616113 99.932821) (end 133.586966 99.872295) (width 0.109) (layer "In2.Cu") (net 50))
  (segment (start 133.800752 100.97662) (end 133.853275 101.018505) (width 0.109) (layer "In2.Cu") (net 50))
  (segment (start 133.59865 100.816534) (end 133.659176 100.845682) (width 0.109) (layer "In2.Cu") (net 50))
  (segment (start 134.135962 99.614778) (end 134.188485 99.656664) (width 0.109) (layer "In2.Cu") (net 50))
  (segment (start 133.616114 99.613601) (end 133.657998 99.56108) (width 0.109) (layer "In2.Cu") (net 50))
  (segment (start 134.172494 101.018505) (end 134.225016 100.97662) (width 0.109) (layer "In2.Cu") (net 50))
  (segment (start 134.507705 99.656664) (end 134.560226 99.614778) (width 0.109) (layer "In2.Cu") (net 50))
  (segment (start 134.560226 99.614778) (end 136.0275 98.1475) (width 0.109) (layer "In2.Cu") (net 50))
  (segment (start 134.314506 99.700761) (end 134.381684 99.700761) (width 0.109) (layer "In2.Cu") (net 50))
  (segment (start 134.266901 100.924097) (end 134.296048 100.863571) (width 0.109) (layer "In2.Cu") (net 50))
  (segment (start 133.657998 99.56108) (end 133.710521 99.519195) (width 0.109) (layer "In2.Cu") (net 50))
  (segment (start 148.009693 95.710307) (end 148.009693 94.106245) (width 0.109) (layer "In2.Cu") (net 50))
  (segment (start 133.658 99.985342) (end 133.616113 99.932821) (width 0.109) (layer "In2.Cu") (net 50))
  (segment (start 133.658 99.985342) (end 134.225015 100.552355) (width 0.109) (layer "In2.Cu") (net 50))
  (segment (start 134.447179 99.685812) (end 134.507705 99.656664) (width 0.109) (layer "In2.Cu") (net 50))
  (segment (start 134.188485 99.656664) (end 134.249011 99.685812) (width 0.109) (layer "In2.Cu") (net 50))
  (segment (start 133.586966 99.674127) (end 133.616114 99.613601) (width 0.109) (layer "In2.Cu") (net 50))
  (segment (start 136.0275 98.1475) (end 145.5725 98.1475) (width 0.109) (layer "In2.Cu") (net 50))
  (segment (start 133.969214 99.490046) (end 134.029741 99.519194) (width 0.109) (layer "In2.Cu") (net 50))
  (segment (start 133.836541 99.475099) (end 133.903721 99.475098) (width 0.109) (layer "In2.Cu") (net 50))
  (segment (start 133.853275 101.018505) (end 133.913801 101.047653) (width 0.109) (layer "In2.Cu") (net 50))
  (segment (start 133.465977 100.801586) (end 133.533156 100.801586) (width 0.109) (layer "In2.Cu") (net 50))
  (segment (start 134.266901 100.604878) (end 134.225015 100.552355) (width 0.109) (layer "In2.Cu") (net 50))
  (segment (start 126.45 102.125) (end 132.050003 102.125) (width 0.109) (layer "In2.Cu") (net 50))
  (segment (start 133.711699 100.887567) (end 133.800752 100.97662) (width 0.109) (layer "In2.Cu") (net 50))
  (segment (start 133.659176 100.845682) (end 133.711699 100.887567) (width 0.109) (layer "In2.Cu") (net 50))
  (segment (start 134.082263 99.561079) (end 134.135962 99.614778) (width 0.109) (layer "In2.Cu") (net 50))
  (segment (start 133.339957 100.845682) (end 133.400483 100.816534) (width 0.109) (layer "In2.Cu") (net 50))
  (segment (start 133.913801 101.047653) (end 133.979295 101.062602) (width 0.109) (layer "In2.Cu") (net 50))
  (segment (start 134.046474 101.062602) (end 134.111968 101.047653) (width 0.109) (layer "In2.Cu") (net 50))
  (segment (start 133.287435 100.887568) (end 133.339957 100.845682) (width 0.109) (layer "In2.Cu") (net 50))
  (segment (start 133.533156 100.801586) (end 133.59865 100.816534) (width 0.109) (layer "In2.Cu") (net 50))
  (segment (start 121.58 106.995) (end 126.45 102.125) (width 0.109) (layer "In2.Cu") (net 50))
  (segment (start 90.3 108.1) (end 91.15 107.25) (width 0.109) (layer "In2.Cu") (net 50))
  (segment (start 134.029741 99.519194) (end 134.082263 99.561079) (width 0.109) (layer "In2.Cu") (net 50))
  (segment (start 91.15 107.25) (end 94.61 107.25) (width 0.109) (layer "In2.Cu") (net 50))
  (segment (start 145.5725 98.1475) (end 148.009693 95.710307) (width 0.109) (layer "In2.Cu") (net 50))
  (segment (start 134.111968 101.047653) (end 134.172494 101.018505) (width 0.109) (layer "In2.Cu") (net 50))
  (segment (start 133.903721 99.475098) (end 133.969214 99.490046) (width 0.109) (layer "In2.Cu") (net 50))
  (segment (start 133.771048 99.490047) (end 133.836541 99.475099) (width 0.109) (layer "In2.Cu") (net 50))
  (segment (start 134.249011 99.685812) (end 134.314506 99.700761) (width 0.109) (layer "In2.Cu") (net 50))
  (segment (start 133.979295 101.062602) (end 134.046474 101.062602) (width 0.109) (layer "In2.Cu") (net 50))
  (segment (start 142.915937 89.012488) (end 142.915937 88.288862) (width 0.109) (layer "In2.Cu") (net 50))
  (segment (start 133.572017 99.806801) (end 133.572018 99.739621) (width 0.109) (layer "In2.Cu") (net 50))
  (segment (start 94.865 106.995) (end 121.58 106.995) (width 0.109) (layer "In2.Cu") (net 50))
  (segment (start 148.009693 94.106245) (end 142.915937 89.012488) (width 0.109) (layer "In2.Cu") (net 50))
  (segment (start 133.400483 100.816534) (end 133.465977 100.801586) (width 0.109) (layer "In2.Cu") (net 50))
  (segment (start 94.61 107.25) (end 94.865 106.995) (width 0.109) (layer "In2.Cu") (net 50))
  (segment (start 134.310997 100.798077) (end 134.310997 100.730898) (width 0.109) (layer "In2.Cu") (net 50))
  (segment (start 152.12 71.152) (end 152.12 70.752) (width 0.182) (layer "F.Cu") (net 51))
  (segment (start 153.39 86.801946) (end 153.39 76.91) (width 0.182) (layer "F.Cu") (net 51))
  (segment (start 152.245912 87.464035) (end 152.727911 87.464035) (width 0.182) (layer "F.Cu") (net 51))
  (segment (start 153.39 76.91) (end 154.85 75.45) (width 0.182) (layer "F.Cu") (net 51))
  (segment (start 154.38 72.2) (end 153.168 72.2) (width 0.182) (layer "F.Cu") (net 51))
  (segment (start 154.85 72.67) (end 154.38 72.2) (width 0.182) (layer "F.Cu") (net 51))
  (segment (start 152.727911 87.464035) (end 153.39 86.801946) (width 0.182) (layer "F.Cu") (net 51))
  (segment (start 153.168 72.2) (end 152.12 71.152) (width 0.182) (layer "F.Cu") (net 51))
  (segment (start 154.85 75.45) (end 154.85 72.67) (width 0.182) (layer "F.Cu") (net 51))
  (segment (start 123.318942 90.323661) (end 123.318942 90.727261) (width 0.182) (layer "F.Cu") (net 52))
  (segment (start 123.318942 90.727261) (end 123.329942 90.738261) (width 0.182) (layer "F.Cu") (net 52))
  (segment (start 123.329942 90.738261) (end 123.329942 91.015653) (width 0.182) (layer "F.Cu") (net 52))
  (segment (start 122.998883 91.346712) (end 122.998883 92.164) (width 0.182) (layer "F.Cu") (net 52))
  (segment (start 123.329942 91.015653) (end 122.998883 91.346712) (width 0.182) (layer "F.Cu") (net 52))
  (segment (start 122.998883 92.164) (end 122.737883 92.425) (width 0.182) (layer "F.Cu") (net 52))
  (segment (start 123.707941 91.17223) (end 123.376883 91.503288) (width 0.182) (layer "F.Cu") (net 53))
  (segment (start 123.707941 90.738261) (end 123.707941 91.17223) (width 0.182) (layer "F.Cu") (net 53))
  (segment (start 123.718941 90.727261) (end 123.707941 90.738261) (width 0.182) (layer "F.Cu") (net 53))
  (segment (start 123.718941 90.323661) (end 123.718941 90.727261) (width 0.182) (layer "F.Cu") (net 53))
  (segment (start 123.376883 92.164) (end 123.637883 92.425) (width 0.182) (layer "F.Cu") (net 53))
  (segment (start 123.376883 91.503288) (end 123.376883 92.164) (width 0.182) (layer "F.Cu") (net 53))
  (segment (start 123.387776 92.159079) (end 123.648776 92.420079) (width 0.182) (layer "F.Cu") (net 53))
  (segment (start 123.648776 92.420079) (end 123.648777 92.420079) (width 0.182) (layer "F.Cu") (net 53))
  (segment (start 122.91894 90.323661) (end 122.91894 89.565261) (width 0.182) (layer "F.Cu") (net 54))
  (segment (start 122.907941 89.331937) (end 123.016941 89.222937) (width 0.182) (layer "F.Cu") (net 54))
  (segment (start 122.90794 89.554261) (end 122.907941 89.331937) (width 0.182) (layer "F.Cu") (net 54))
  (segment (start 122.91894 89.565261) (end 122.90794 89.554261) (width 0.182) (layer "F.Cu") (net 54))
  (segment (start 120.322 96.6979) (end 120.322 95.630277) (width 0.182) (layer "F.Cu") (net 54))
  (segment (start 120.322 95.630277) (end 120.402691 95.549586) (width 0.182) (layer "F.Cu") (net 54))
  (segment (start 120.387 96.7629) (end 120.322 96.6979) (width 0.182) (layer "F.Cu") (net 54))
  (via (at 123.016941 89.222937) (size 0.45) (drill 0.1) (layers "F.Cu" "B.Cu") (net 54))
  (via (at 120.402691 95.549586) (size 0.45) (drill 0.1) (layers "F.Cu" "B.Cu") (net 54))
  (segment (start 123.4275 92.402814) (end 123.4275 90.487186) (width 0.109) (layer "In2.Cu") (net 54))
  (segment (start 122.846441 89.393437) (end 123.016941 89.222937) (width 0.109) (layer "In2.Cu") (net 54))
  (segment (start 120.402691 95.549586) (end 120.255817 95.402712) (width 0.109) (layer "In2.Cu") (net 54))
  (segment (start 122.846441 89.906127) (end 122.846441 89.393437) (width 0.109) (layer "In2.Cu") (net 54))
  (segment (start 120.255817 94.744497) (end 121.742814 93.2575) (width 0.109) (layer "In2.Cu") (net 54))
  (segment (start 121.742814 93.2575) (end 122.572814 93.2575) (width 0.109) (layer "In2.Cu") (net 54))
  (segment (start 120.255817 95.402712) (end 120.255817 94.744497) (width 0.109) (layer "In2.Cu") (net 54))
  (segment (start 123.4275 90.487186) (end 122.846441 89.906127) (width 0.109) (layer "In2.Cu") (net 54))
  (segment (start 122.572814 93.2575) (end 123.4275 92.402814) (width 0.109) (layer "In2.Cu") (net 54))
  (segment (start 122.529941 89.331937) (end 122.420941 89.222937) (width 0.182) (layer "F.Cu") (net 55))
  (segment (start 122.518941 89.565261) (end 122.529941 89.554261) (width 0.182) (layer "F.Cu") (net 55))
  (segment (start 122.529941 89.554261) (end 122.529941 89.331937) (width 0.182) (layer "F.Cu") (net 55))
  (segment (start 122.518941 90.323661) (end 122.518941 89.565261) (width 0.182) (layer "F.Cu") (net 55))
  (segment (start 119.879 96.7629) (end 119.879 96.1569) (width 0.182) (layer "F.Cu") (net 55))
  (segment (start 119.82959 95.573939) (end 119.944 95.688349) (width 0.182) (layer "F.Cu") (net 55))
  (segment (start 119.879 96.1569) (end 119.944 96.0919) (width 0.182) (layer "F.Cu") (net 55))
  (segment (start 119.944 96.0919) (end 119.944 95.688349) (width 0.182) (layer "F.Cu") (net 55))
  (via (at 122.420941 89.222937) (size 0.45) (drill 0.1) (layers "F.Cu" "B.Cu") (net 55))
  (via (at 119.82959 95.573939) (size 0.45) (drill 0.1) (layers "F.Cu" "B.Cu") (net 55))
  (segment (start 122.591441 89.393437) (end 122.420941 89.222937) (width 0.109) (layer "In2.Cu") (net 55))
  (segment (start 123.1725 90.592814) (end 122.591441 90.011755) (width 0.109) (layer "In2.Cu") (net 55))
  (segment (start 123.1725 92.297186) (end 123.1725 90.592814) (width 0.109) (layer "In2.Cu") (net 55))
  (segment (start 119.82959 95.573939) (end 120.000817 95.402712) (width 0.109) (layer "In2.Cu") (net 55))
  (segment (start 122.467186 93.0025) (end 123.1725 92.297186) (width 0.109) (layer "In2.Cu") (net 55))
  (segment (start 122.591441 90.011755) (end 122.591441 89.393437) (width 0.109) (layer "In2.Cu") (net 55))
  (segment (start 120.000817 95.402712) (end 120.000817 94.638869) (width 0.109) (layer "In2.Cu") (net 55))
  (segment (start 120.000817 94.638869) (end 121.637186 93.0025) (width 0.109) (layer "In2.Cu") (net 55))
  (segment (start 121.637186 93.0025) (end 122.467186 93.0025) (width 0.109) (layer "In2.Cu") (net 55))
  (segment (start 92.3665 103.334) (end 92.846 103.023) (width 0.182) (layer "F.Cu") (net 56))
  (segment (start 122.748776 93.390079) (end 123.009776 93.651079) (width 0.182) (layer "F.Cu") (net 56))
  (segment (start 123.009776 93.651079) (end 123.009776 93.965999) (width 0.182) (layer "F.Cu") (net 56))
  (segment (start 123.009776 93.965999) (end 122.900775 94.075) (width 0.182) (layer "F.Cu") (net 56))
  (via (at 122.900775 94.075) (size 0.45) (drill 0.1) (layers "F.Cu" "B.Cu") (net 56))
  (via (at 92.846 103.023) (size 0.45) (drill 0.1) (layers "F.Cu" "B.Cu") (net 56))
  (segment (start 110.621481 99.705155) (end 110.599063 99.606934) (width 0.109) (layer "In4.Cu") (net 56))
  (segment (start 92.846 103.023) (end 92.583 103.023) (width 0.109) (layer "In4.Cu") (net 56))
  (segment (start 108.692159 99.616922) (end 108.661095 99.577968) (width 0.109) (layer "In4.Cu") (net 56))
  (segment (start 109.912928 98.259628) (end 109.957818 98.281246) (width 0.109) (layer "In4.Cu") (net 56))
  (segment (start 96.412814 101.6675) (end 107.612811 101.6675) (width 0.109) (layer "In4.Cu") (net 56))
  (segment (start 108.874403 99.238491) (end 108.922978 99.249578) (width 0.109) (layer "In4.Cu") (net 56))
  (segment (start 122.597734 93.427953) (end 122.618952 93.406735) (width 0.109) (layer "In4.Cu") (net 56))
  (segment (start 94.4845 102.5615) (end 94.487232 102.537245) (width 0.109) (layer "In4.Cu") (net 56))
  (segment (start 111.074957 99.251681) (end 111.175705 99.251681) (width 0.109) (layer "In4.Cu") (net 56))
  (segment (start 94.525539 102.47628) (end 94.546206 102.463294) (width 0.109) (layer "In4.Cu") (net 56))
  (segment (start 110.492535 100.073663) (end 110.55535 99.994896) (width 0.109) (layer "In4.Cu") (net 56))
  (segment (start 110.885965 99.18555) (end 110.976735 99.229262) (width 0.109) (layer "In4.Cu") (net 56))
  (segment (start 122.555229 93.682309) (end 122.56514 93.653986) (width 0.109) (layer "In4.Cu") (net 56))
  (segment (start 111.315004 97.965303) (end 112.275077 97.005238) (width 0.109) (layer "In4.Cu") (net 56))
  (segment (start 122.196317 93.38086) (end 122.22464 93.390771) (width 0.109) (layer "In4.Cu") (net 56))
  (segment (start 122.303859 93.653986) (end 122.31377 93.682309) (width 0.109) (layer "In4.Cu") (net 56))
  (segment (start 94.277294 102.633564) (end 94.29028 102.654231) (width 0.109) (layer "In4.Cu") (net 56))
  (segment (start 111.443465 99.122734) (end 111.482485 99.083713) (width 0.109) (layer "In4.Cu") (net 56))
  (segment (start 109.61834 98.444729) (end 109.629427 98.396154) (width 0.109) (layer "In4.Cu") (net 56))
  (segment (start 94.255705 102.514206) (end 94.263767 102.537245) (width 0.109) (layer "In4.Cu") (net 56))
  (segment (start 108.824579 99.238491) (end 108.874403 99.238491) (width 0.109) (layer "In4.Cu") (net 56))
  (segment (start 110.453515 100.112684) (end 110.492535 100.073663) (width 0.109) (layer "In4.Cu") (net 56))
  (segment (start 122.5685 93.5115) (end 122.571859 93.481683) (width 0.109) (layer "In4.Cu") (net 56))
  (segment (start 94.263767 102.537245) (end 94.2665 102.5615) (width 0.109) (layer "In4.Cu") (net 56))
  (segment (start 122.49264 93.744898) (end 122.518047 93.728934) (width 0.109) (layer "In4.Cu") (net 56))
  (segment (start 107.612811 101.6675) (end 108.345155 100.935153) (width 0.109) (layer "In4.Cu") (net 56))
  (segment (start 109.087617 100.01238) (end 108.692159 99.616922) (width 0.109) (layer "In4.Cu") (net 56))
  (segment (start 122.22464 93.390771) (end 122.250047 93.406735) (width 0.109) (layer "In4.Cu") (net 56))
  (segment (start 108.428999 100.882471) (end 108.477574 100.871384) (width 0.109) (layer "In4.Cu") (net 56))
  (segment (start 94.269232 102.610525) (end 94.277294 102.633564) (width 0.109) (layer "In4.Cu") (net 56))
  (segment (start 122.376359 93.744898) (end 122.404682 93.754809) (width 0.109) (layer "In4.Cu") (net 56))
  (segment (start 108.731114 99.271196) (end 108.776004 99.249578) (width 0.109) (layer "In4.Cu") (net 56))
  (segment (start 122.287229 93.45336) (end 122.29714 93.481683) (width 0.109) (layer "In4.Cu") (net 56))
  (segment (start 109.651045 98.588018) (end 109.629427 98.543128) (width 0.109) (layer "In4.Cu") (net 56))
  (segment (start 122.618952 93.406735) (end 122.644359 93.390771) (width 0.109) (layer "In4.Cu") (net 56))
  (segment (start 108.620862 100.904089) (end 108.659816 100.935153) (width 0.109) (layer "In4.Cu") (net 56))
  (segment (start 110.599063 99.606934) (end 110.55535 99.516163) (width 0.109) (layer "In4.Cu") (net 56))
  (segment (start 108.922978 99.249578) (end 108.967868 99.271196) (width 0.109) (layer "In4.Cu") (net 56))
  (segment (start 109.095056 101.23158) (end 109.195804 101.23158) (width 0.109) (layer "In4.Cu") (net 56))
  (segment (start 123.071276 93.55159) (end 123.071276 93.904499) (width 0.109) (layer "In4.Cu") (net 56))
  (segment (start 94.204793 102.463294) (end 94.22546 102.47628) (width 0.109) (layer "In4.Cu") (net 56))
  (segment (start 122.644359 93.390771) (end 122.672682 93.38086) (width 0.109) (layer "In4.Cu") (net 56))
  (segment (start 110.085007 100.241631) (end 110.185755 100.241631) (width 0.109) (layer "In4.Cu") (net 56))
  (segment (start 110.077567 99.022427) (end 110.077567 99.02243) (width 0.109) (layer "In4.Cu") (net 56))
  (segment (start 94.5935 102.4525) (end 95.627814 102.4525) (width 0.109) (layer "In4.Cu") (net 56))
  (segment (start 109.63153 100.795852) (end 109.63153 100.695104) (width 0.109) (layer "In4.Cu") (net 56))
  (segment (start 109.896015 100.1755) (end 109.986785 100.219212) (width 0.109) (layer "In4.Cu") (net 56))
  (segment (start 109.651046 98.351264) (end 109.68211 98.31231) (width 0.109) (layer "In4.Cu") (net 56))
  (segment (start 122.271265 93.427953) (end 122.287229 93.45336) (width 0.109) (layer "In4.Cu") (net 56))
  (segment (start 108.575973 100.882471) (end 108.620862 100.904089) (width 0.109) (layer "In4.Cu") (net 56))
  (segment (start 122.464317 93.754809) (end 122.49264 93.744898) (width 0.109) (layer "In4.Cu") (net 56))
  (segment (start 110.807197 99.122734) (end 110.885965 99.18555) (width 0.109) (layer "In4.Cu") (net 56))
  (segment (start 110.55535 99.994896) (end 110.599063 99.904125) (width 0.109) (layer "In4.Cu") (net 56))
  (segment (start 122.4345 93.758168) (end 122.464317 93.754809) (width 0.109) (layer "In4.Cu") (net 56))
  (segment (start 108.384109 100.904089) (end 108.428999 100.882471) (width 0.109) (layer "In4.Cu") (net 56))
  (segment (start 122.56514 93.653986) (end 122.5685 93.624168) (width 0.109) (layer "In4.Cu") (net 56))
  (segment (start 109.957818 98.281246) (end 109.996772 98.31231) (width 0.109) (layer "In4.Cu") (net 56))
  (segment (start 94.422793 102.684476) (end 94.44346 102.67149) (width 0.109) (layer "In4.Cu") (net 56))
  (segment (start 109.986785 100.219212) (end 110.085007 100.241631) (width 0.109) (layer "In4.Cu") (net 56))
  (segment (start 94.22546 102.47628) (end 94.242719 102.493539) (width 0.109) (layer "In4.Cu") (net 56))
  (segment (start 109.195804 101.23158) (end 109.294026 101.209161) (width 0.109) (layer "In4.Cu") (net 56))
  (segment (start 94.460719 102.654231) (end 94.473705 102.633564) (width 0.109) (layer "In4.Cu") (net 56))
  (segment (start 122.58177 93.45336) (end 122.597734 93.427953) (width 0.109) (layer "In4.Cu") (net 56))
  (segment (start 111.364697 99.18555) (end 111.443465 99.122734) (width 0.109) (layer "In4.Cu") (net 56))
  (segment (start 109.384797 101.165448) (end 109.463564 101.102633) (width 0.109) (layer "In4.Cu") (net 56))
  (segment (start 94.44346 102.67149) (end 94.460719 102.654231) (width 0.109) (layer "In4.Cu") (net 56))
  (segment (start 109.721064 98.281246) (end 109.765954 98.259628) (width 0.109) (layer "In4.Cu") (net 56))
  (segment (start 94.50828 102.493539) (end 94.525539 102.47628) (width 0.109) (layer "In4.Cu") (net 56))
  (segment (start 108.827296 101.102633) (end 108.906064 101.165448) (width 0.109) (layer "In4.Cu") (net 56))
  (segment (start 108.639477 99.533078) (end 108.62839 99.484503) (width 0.109) (layer "In4.Cu") (net 56))
  (segment (start 92.687814 102.4525) (end 94.1575 102.4525) (width 0.109) (layer "In4.Cu") (net 56))
  (segment (start 94.2665 102.586271) (end 94.269232 102.610525) (width 0.109) (layer "In4.Cu") (net 56))
  (segment (start 110.599063 99.904125) (end 110.621481 99.805903) (width 0.109) (layer "In4.Cu") (net 56))
  (segment (start 109.61834 98.494553) (end 109.61834 98.444729) (width 0.109) (layer "In4.Cu") (net 56))
  (segment (start 111.589013 98.914175) (end 111.611431 98.815953) (width 0.109) (layer "In4.Cu") (net 56))
  (segment (start 108.776004 99.249578) (end 108.824579 99.238491) (width 0.109) (layer "In4.Cu") (net 56))
  (segment (start 111.482485 98.447445) (end 111.315004 98.279964) (width 0.109) (layer "In4.Cu") (net 56))
  (segment (start 110.185755 100.241631) (end 110.283976 100.219212) (width 0.109) (layer "In4.Cu") (net 56))
  (segment (start 122.897186 93.3775) (end 123.071276 93.55159) (width 0.109) (layer "In4.Cu") (net 56))
  (segment (start 111.611431 98.815953) (end 111.611431 98.715205) (width 0.109) (layer "In4.Cu") (net 56))
  (segment (start 110.621481 99.805903) (end 110.621481 99.705155) (width 0.109) (layer "In4.Cu") (net 56))
  (segment (start 111.262321 98.049147) (end 111.283939 98.004257) (width 0.109) (layer "In4.Cu") (net 56))
  (segment (start 122.1665 93.3775) (end 122.196317 93.38086) (width 0.109) (layer "In4.Cu") (net 56))
  (segment (start 95.627814 102.4525) (end 96.412814 101.6675) (width 0.109) (layer "In4.Cu") (net 56))
  (segment (start 111.482485 99.083713) (end 111.5453 99.004946) (width 0.109) (layer "In4.Cu") (net 56))
  (segment (start 94.481767 102.610525) (end 94.4845 102.586271) (width 0.109) (layer "In4.Cu") (net 56))
  (segment (start 94.181754 102.455232) (end 94.204793 102.463294) (width 0.109) (layer "In4.Cu") (net 56))
  (segment (start 108.62839 99.434679) (end 108.639477 99.386104) (width 0.109) (layer "In4.Cu") (net 56))
  (segment (start 109.565399 100.984845) (end 109.609112 100.894074) (width 0.109) (layer "In4.Cu") (net 56))
  (segment (start 122.5685 93.624168) (end 122.5685 93.5115) (width 0.109) (layer "In4.Cu") (net 56))
  (segment (start 123.071276 93.904499) (end 122.900775 94.075) (width 0.109) (layer "In4.Cu") (net 56))
  (segment (start 108.661095 99.577968) (end 108.639477 99.533078) (width 0.109) (layer "In4.Cu") (net 56))
  (segment (start 109.996772 98.31231) (end 110.807197 99.122734) (width 0.109) (layer "In4.Cu") (net 56))
  (segment (start 109.006822 99.30226) (end 109.817247 100.112684) (width 0.109) (layer "In4.Cu") (net 56))
  (segment (start 122.350952 93.728934) (end 122.376359 93.744898) (width 0.109) (layer "In4.Cu") (net 56))
  (segment (start 92.4905 102.649814) (end 92.687814 102.4525) (width 0.109) (layer "In4.Cu") (net 56))
  (segment (start 94.242719 102.493539) (end 94.255705 102.514206) (width 0.109) (layer "In4.Cu") (net 56))
  (segment (start 122.3005 93.5115) (end 122.3005 93.624168) (width 0.109) (layer "In4.Cu") (net 56))
  (segment (start 110.976735 99.229262) (end 111.074957 99.251681) (width 0.109) (layer "In4.Cu") (net 56))
  (segment (start 122.571859 93.481683) (end 122.58177 93.45336) (width 0.109) (layer "In4.Cu") (net 56))
  (segment (start 115.172814 94.1075) (end 121.082814 94.1075) (width 0.109) (layer "In4.Cu") (net 56))
  (segment (start 109.565399 100.506112) (end 109.502584 100.427344) (width 0.109) (layer "In4.Cu") (net 56))
  (segment (start 92.583 103.023) (end 92.4905 102.9305) (width 0.109) (layer "In4.Cu") (net 56))
  (segment (start 92.4905 102.9305) (end 92.4905 102.649814) (width 0.109) (layer "In4.Cu") (net 56))
  (segment (start 110.283976 100.219212) (end 110.374747 100.1755) (width 0.109) (layer "In4.Cu") (net 56))
  (segment (start 94.4845 102.586271) (end 94.4845 102.5615) (width 0.109) (layer "In4.Cu") (net 56))
  (segment (start 108.527398 100.871384) (end 108.575973 100.882471) (width 0.109) (layer "In4.Cu") (net 56))
  (segment (start 111.5453 99.004946) (end 111.589013 98.914175) (width 0.109) (layer "In4.Cu") (net 56))
  (segment (start 109.682109 98.626972) (end 109.651045 98.588018) (width 0.109) (layer "In4.Cu") (net 56))
  (segment (start 109.629427 98.543128) (end 109.61834 98.494553) (width 0.109) (layer "In4.Cu") (net 56))
  (segment (start 111.273926 99.229262) (end 111.364697 99.18555) (width 0.109) (layer "In4.Cu") (net 56))
  (segment (start 94.2665 102.5615) (end 94.2665 102.586271) (width 0.109) (layer "In4.Cu") (net 56))
  (segment (start 122.518047 93.728934) (end 122.539265 93.707716) (width 0.109) (layer "In4.Cu") (net 56))
  (segment (start 111.5453 98.526213) (end 111.482485 98.447445) (width 0.109) (layer "In4.Cu") (net 56))
  (segment (start 122.29714 93.481683) (end 122.3005 93.5115) (width 0.109) (layer "In4.Cu") (net 56))
  (segment (start 108.69216 99.30226) (end 108.731114 99.271196) (width 0.109) (layer "In4.Cu") (net 56))
  (segment (start 122.7025 93.3775) (end 122.897186 93.3775) (width 0.109) (layer "In4.Cu") (net 56))
  (segment (start 111.611431 98.715205) (end 111.589013 98.616984) (width 0.109) (layer "In4.Cu") (net 56))
  (segment (start 94.328206 102.684476) (end 94.351245 102.692538) (width 0.109) (layer "In4.Cu") (net 56))
  (segment (start 108.996835 101.209161) (end 109.095056 101.23158) (width 0.109) (layer "In4.Cu") (net 56))
  (segment (start 109.463564 101.102633) (end 109.502584 101.063612) (width 0.109) (layer "In4.Cu") (net 56))
  (segment (start 110.492535 99.437395) (end 110.077567 99.022427) (width 0.109) (layer "In4.Cu") (net 56))
  (segment (start 109.629427 98.396154) (end 109.651046 98.351264) (width 0.109) (layer "In4.Cu") (net 56))
  (segment (start 111.283939 98.24101) (end 111.262321 98.19612) (width 0.109) (layer "In4.Cu") (net 56))
  (segment (start 109.294026 101.209161) (end 109.384797 101.165448) (width 0.109) (layer "In4.Cu") (net 56))
  (segment (start 111.315004 98.279964) (end 111.283939 98.24101) (width 0.109) (layer "In4.Cu") (net 56))
  (segment (start 111.175705 99.251681) (end 111.273926 99.229262) (width 0.109) (layer "In4.Cu") (net 56))
  (segment (start 122.539265 93.707716) (end 122.555229 93.682309) (width 0.109) (layer "In4.Cu") (net 56))
  (segment (start 109.502584 100.427344) (end 109.087616 100.012376) (width 0.109) (layer "In4.Cu") (net 56))
  (segment (start 109.817247 100.112684) (end 109.896015 100.1755) (width 0.109) (layer "In4.Cu") (net 56))
  (segment (start 108.639477 99.386104) (end 108.661096 99.341214) (width 0.109) (layer "In4.Cu") (net 56))
  (segment (start 121.082814 94.1075) (end 121.812814 93.3775) (width 0.109) (layer "In4.Cu") (net 56))
  (segment (start 94.351245 102.692538) (end 94.3755 102.695271) (width 0.109) (layer "In4.Cu") (net 56))
  (segment (start 94.399754 102.692538) (end 94.422793 102.684476) (width 0.109) (layer "In4.Cu") (net 56))
  (segment (start 109.864353 98.248541) (end 109.912928 98.259628) (width 0.109) (layer "In4.Cu") (net 56))
  (segment (start 109.814529 98.248541) (end 109.864353 98.248541) (width 0.109) (layer "In4.Cu") (net 56))
  (segment (start 109.765954 98.259628) (end 109.814529 98.248541) (width 0.109) (layer "In4.Cu") (net 56))
  (segment (start 108.345155 100.935153) (end 108.384109 100.904089) (width 0.109) (layer "In4.Cu") (net 56))
  (segment (start 112.275077 97.005238) (end 115.172814 94.1075) (width 0.109) (layer "In4.Cu") (net 56))
  (segment (start 94.495294 102.514206) (end 94.50828 102.493539) (width 0.109) (layer "In4.Cu") (net 56))
  (segment (start 121.812814 93.3775) (end 122.1665 93.3775) (width 0.109) (layer "In4.Cu") (net 56))
  (segment (start 111.283939 98.004257) (end 111.315004 97.965303) (width 0.109) (layer "In4.Cu") (net 56))
  (segment (start 94.487232 102.537245) (end 94.495294 102.514206) (width 0.109) (layer "In4.Cu") (net 56))
  (segment (start 94.546206 102.463294) (end 94.569245 102.455232) (width 0.109) (layer "In4.Cu") (net 56))
  (segment (start 108.906064 101.165448) (end 108.996835 101.209161) (width 0.109) (layer "In4.Cu") (net 56))
  (segment (start 109.502584 101.063612) (end 109.565399 100.984845) (width 0.109) (layer "In4.Cu") (net 56))
  (segment (start 122.250047 93.406735) (end 122.271265 93.427953) (width 0.109) (layer "In4.Cu") (net 56))
  (segment (start 108.62839 99.484503) (end 108.62839 99.434679) (width 0.109) (layer "In4.Cu") (net 56))
  (segment (start 108.967868 99.271196) (end 109.006822 99.30226) (width 0.109) (layer "In4.Cu") (net 56))
  (segment (start 94.569245 102.455232) (end 94.5935 102.4525) (width 0.109) (layer "In4.Cu") (net 56))
  (segment (start 122.329734 93.707716) (end 122.350952 93.728934) (width 0.109) (layer "In4.Cu") (net 56))
  (segment (start 110.077567 99.02243) (end 109.682109 98.626972) (width 0.109) (layer "In4.Cu") (net 56))
  (segment (start 122.3005 93.624168) (end 122.303859 93.653986) (width 0.109) (layer "In4.Cu") (net 56))
  (segment (start 108.477574 100.871384) (end 108.527398 100.871384) (width 0.109) (layer "In4.Cu") (net 56))
  (segment (start 94.1575 102.4525) (end 94.181754 102.455232) (width 0.109) (layer "In4.Cu") (net 56))
  (segment (start 111.251234 98.097721) (end 111.262321 98.049147) (width 0.109) (layer "In4.Cu") (net 56))
  (segment (start 111.262321 98.19612) (end 111.251234 98.147545) (width 0.109) (layer "In4.Cu") (net 56))
  (segment (start 109.087616 100.012376) (end 109.087617 100.01238) (width 0.109) (layer "In4.Cu") (net 56))
  (segment (start 109.609112 100.596883) (end 109.565399 100.506112) (width 0.109) (layer "In4.Cu") (net 56))
  (segment (start 110.55535 99.516163) (end 110.492535 99.437395) (width 0.109) (layer "In4.Cu") (net 56))
  (segment (start 110.374747 100.1755) (end 110.453515 100.112684) (width 0.109) (layer "In4.Cu") (net 56))
  (segment (start 108.659816 100.935153) (end 108.827296 101.102633) (width 0.109) (layer "In4.Cu") (net 56))
  (segment (start 122.672682 93.38086) (end 122.7025 93.3775) (width 0.109) (layer "In4.Cu") (net 56))
  (segment (start 94.3755 102.695271) (end 94.399754 102.692538) (width 0.109) (layer "In4.Cu") (net 56))
  (segment (start 122.404682 93.754809) (end 122.4345 93.758168) (width 0.109) (layer "In4.Cu") (net 56))
  (segment (start 122.31377 93.682309) (end 122.329734 93.707716) (width 0.109) (layer "In4.Cu") (net 56))
  (segment (start 94.473705 102.633564) (end 94.481767 102.610525) (width 0.109) (layer "In4.Cu") (net 56))
  (segment (start 109.63153 100.695104) (end 109.609112 100.596883) (width 0.109) (layer "In4.Cu") (net 56))
  (segment (start 109.609112 100.894074) (end 109.63153 100.795852) (width 0.109) (layer "In4.Cu") (net 56))
  (segment (start 94.29028 102.654231) (end 94.307539 102.67149) (width 0.109) (layer "In4.Cu") (net 56))
  (segment (start 94.307539 102.67149) (end 94.328206 102.684476) (width 0.109) (layer "In4.Cu") (net 56))
  (segment (start 108.661096 99.341214) (end 108.69216 99.30226) (width 0.109) (layer "In4.Cu") (net 56))
  (segment (start 111.251234 98.147545) (end 111.251234 98.097721) (width 0.109) (layer "In4.Cu") (net 56))
  (segment (start 109.68211 98.31231) (end 109.721064 98.281246) (width 0.109) (layer "In4.Cu") (net 56))
  (segment (start 111.589013 98.616984) (end 111.5453 98.526213) (width 0.109) (layer "In4.Cu") (net 56))
  (segment (start 91.89 103.013) (end 92.3665 102.699) (width 0.182) (layer "F.Cu") (net 57))
  (segment (start 123.387776 93.965999) (end 123.496777 94.075) (width 0.182) (layer "F.Cu") (net 57))
  (segment (start 123.648776 93.390079) (end 123.387776 93.651079) (width 0.182) (layer "F.Cu") (net 57))
  (segment (start 123.387776 93.651079) (end 123.387776 93.965999) (width 0.182) (layer "F.Cu") (net 57))
  (via (at 123.496777 94.075) (size 0.45) (drill 0.1) (layers "F.Cu" "B.Cu") (net 57))
  (via (at 91.89 103.013) (size 0.45) (drill 0.1) (layers "F.Cu" "B.Cu") (net 57))
  (segment (start 92.582186 102.1975) (end 95.522186 102.1975) (width 0.109) (layer "In4.Cu") (net 57))
  (segment (start 110.986233 98.173008) (end 110.986233 98.07226) (width 0.109) (layer "In4.Cu") (net 57))
  (segment (start 112.094763 96.824924) (end 115.067186 93.8525) (width 0.109) (layer "In4.Cu") (net 57))
  (segment (start 109.37576 98.618235) (end 109.35334 98.520014) (width 0.109) (layer "In4.Cu") (net 57))
  (segment (start 110.157576 98.112486) (end 110.968 98.922911) (width 0.109) (layer "In4.Cu") (net 57))
  (segment (start 109.263807 100.933875) (end 109.302761 100.90281) (width 0.109) (layer "In4.Cu") (net 57))
  (segment (start 109.333825 100.627102) (end 109.302761 100.588148) (width 0.109) (layer "In4.Cu") (net 57))
  (segment (start 92.2355 102.9245) (end 92.2355 102.544186) (width 0.109) (layer "In4.Cu") (net 57))
  (segment (start 111.243707 98.953975) (end 111.282661 98.922911) (width 0.109) (layer "In4.Cu") (net 57))
  (segment (start 109.482288 98.787773) (end 109.419472 98.709005) (width 0.109) (layer "In4.Cu") (net 57))
  (segment (start 108.42952 99.220225) (end 108.492336 99.141457) (width 0.109) (layer "In4.Cu") (net 57))
  (segment (start 111.150243 98.98668) (end 111.198818 98.975593) (width 0.109) (layer "In4.Cu") (net 57))
  (segment (start 110.208868 99.965543) (end 110.253757 99.943925) (width 0.109) (layer "In4.Cu") (net 57))
  (segment (start 91.89 103.013) (end 92.147 103.013) (width 0.109) (layer "In4.Cu") (net 57))
  (segment (start 96.307186 101.4125) (end 107.507183 101.4125) (width 0.109) (layer "In4.Cu") (net 57))
  (segment (start 110.017004 99.943925) (end 110.061894 99.965543) (width 0.109) (layer "In4.Cu") (net 57))
  (segment (start 95.522186 102.1975) (end 96.307186 101.4125) (width 0.109) (layer "In4.Cu") (net 57))
  (segment (start 109.41947 98.230275) (end 109.482286 98.151507) (width 0.109) (layer "In4.Cu") (net 57))
  (segment (start 108.899866 98.97349) (end 108.998086 98.995909) (width 0.109) (layer "In4.Cu") (net 57))
  (segment (start 110.323775 99.873907) (end 110.345393 99.829017) (width 0.109) (layer "In4.Cu") (net 57))
  (segment (start 109.482286 98.151507) (end 109.521308 98.112486) (width 0.109) (layer "In4.Cu") (net 57))
  (segment (start 108.184352 100.735329) (end 108.26312 100.672514) (width 0.109) (layer "In4.Cu") (net 57))
  (segment (start 110.292711 99.598199) (end 109.897253 99.202741) (width 0.109) (layer "In4.Cu") (net 57))
  (segment (start 108.700896 98.995908) (end 108.799118 98.97349) (width 0.109) (layer "In4.Cu") (net 57))
  (segment (start 92.147 103.013) (end 92.2355 102.9245) (width 0.109) (layer "In4.Cu") (net 57))
  (segment (start 109.120519 100.96658) (end 109.170343 100.96658) (width 0.109) (layer "In4.Cu") (net 57))
  (segment (start 108.998086 98.995909) (end 109.088857 99.039622) (width 0.109) (layer "In4.Cu") (net 57))
  (segment (start 110.292711 99.912861) (end 110.323775 99.873907) (width 0.109) (layer "In4.Cu") (net 57))
  (segment (start 111.335343 98.839067) (end 111.34643 98.790492) (width 0.109) (layer "In4.Cu") (net 57))
  (segment (start 109.36653 100.720567) (end 109.355443 100.671992) (width 0.109) (layer "In4.Cu") (net 57))
  (segment (start 108.492336 99.141457) (end 108.531358 99.102436) (width 0.109) (layer "In4.Cu") (net 57))
  (segment (start 111.11518 97.8045) (end 111.13469 97.78499) (width 0.109) (layer "In4.Cu") (net 57))
  (segment (start 120.977186 93.8525) (end 121.707186 93.1225) (width 0.109) (layer "In4.Cu") (net 57))
  (segment (start 109.170343 100.96658) (end 109.218917 100.955493) (width 0.109) (layer "In4.Cu") (net 57))
  (segment (start 108.82062 100.735329) (end 108.84013 100.75484) (width 0.109) (layer "In4.Cu") (net 57))
  (segment (start 109.35334 98.520014) (end 109.35334 98.419266) (width 0.109) (layer "In4.Cu") (net 57))
  (segment (start 111.100419 98.98668) (end 111.150243 98.98668) (width 0.109) (layer "In4.Cu") (net 57))
  (segment (start 108.84013 100.75484) (end 108.9881 100.90281) (width 0.109) (layer "In4.Cu") (net 57))
  (segment (start 110.968 98.922911) (end 111.006954 98.953975) (width 0.109) (layer "In4.Cu") (net 57))
  (segment (start 109.897256 99.202741) (end 109.482288 98.787773) (width 0.109) (layer "In4.Cu") (net 57))
  (segment (start 107.507183 101.4125) (end 108.184352 100.735329) (width 0.109) (layer "In4.Cu") (net 57))
  (segment (start 111.34643 98.740668) (end 111.335343 98.692093) (width 0.109) (layer "In4.Cu") (net 57))
  (segment (start 109.302761 100.588148) (end 108.492338 99.777723) (width 0.109) (layer "In4.Cu") (net 57))
  (segment (start 110.345393 99.682043) (end 110.323775 99.637153) (width 0.109) (layer "In4.Cu") (net 57))
  (segment (start 109.355443 100.671992) (end 109.333825 100.627102) (width 0.109) (layer "In4.Cu") (net 57))
  (segment (start 110.35648 99.780442) (end 110.35648 99.730618) (width 0.109) (layer "In4.Cu") (net 57))
  (segment (start 110.986233 98.07226) (end 111.008652 97.974038) (width 0.109) (layer "In4.Cu") (net 57))
  (segment (start 111.008652 98.271229) (end 110.986233 98.173008) (width 0.109) (layer "In4.Cu") (net 57))
  (segment (start 109.897253 99.202741) (end 109.897256 99.202741) (width 0.109) (layer "In4.Cu") (net 57))
  (segment (start 108.741852 100.672514) (end 108.82062 100.735329) (width 0.109) (layer "In4.Cu") (net 57))
  (segment (start 111.282661 98.922911) (end 111.313725 98.883957) (width 0.109) (layer "In4.Cu") (net 57))
  (segment (start 109.375759 98.321045) (end 109.41947 98.230275) (width 0.109) (layer "In4.Cu") (net 57))
  (segment (start 109.97805 99.912861) (end 110.017004 99.943925) (width 0.109) (layer "In4.Cu") (net 57))
  (segment (start 111.34643 98.790492) (end 111.34643 98.740668) (width 0.109) (layer "In4.Cu") (net 57))
  (segment (start 111.313725 98.647203) (end 111.282661 98.608249) (width 0.109) (layer "In4.Cu") (net 57))
  (segment (start 115.067186 93.8525) (end 120.977186 93.8525) (width 0.109) (layer "In4.Cu") (net 57))
  (segment (start 108.35389 100.628801) (end 108.452112 100.606383) (width 0.109) (layer "In4.Cu") (net 57))
  (segment (start 111.051844 98.975593) (end 111.100419 98.98668) (width 0.109) (layer "In4.Cu") (net 57))
  (segment (start 110.253757 99.943925) (end 110.292711 99.912861) (width 0.109) (layer "In4.Cu") (net 57))
  (segment (start 108.452112 100.606383) (end 108.55286 100.606383) (width 0.109) (layer "In4.Cu") (net 57))
  (segment (start 110.078807 98.049672) (end 110.157576 98.112486) (width 0.109) (layer "In4.Cu") (net 57))
  (segment (start 108.55286 100.606383) (end 108.651082 100.628801) (width 0.109) (layer "In4.Cu") (net 57))
  (segment (start 111.198818 98.975593) (end 111.243707 98.953975) (width 0.109) (layer "In4.Cu") (net 57))
  (segment (start 109.071944 100.955493) (end 109.120519 100.96658) (width 0.109) (layer "In4.Cu") (net 57))
  (segment (start 109.988036 98.005959) (end 110.078807 98.049672) (width 0.109) (layer "In4.Cu") (net 57))
  (segment (start 108.651082 100.628801) (end 108.741852 100.672514) (width 0.109) (layer "In4.Cu") (net 57))
  (segment (start 109.333825 100.863856) (end 109.355443 100.818966) (width 0.109) (layer "In4.Cu") (net 57))
  (segment (start 123.326276 93.445962) (end 123.326276 93.904499) (width 0.109) (layer "In4.Cu") (net 57))
  (segment (start 108.610125 99.039621) (end 108.700896 98.995908) (width 0.109) (layer "In4.Cu") (net 57))
  (segment (start 108.492338 99.777723) (end 108.429522 99.698955) (width 0.109) (layer "In4.Cu") (net 57))
  (segment (start 109.419472 98.709005) (end 109.37576 98.618235) (width 0.109) (layer "In4.Cu") (net 57))
  (segment (start 108.36339 99.509964) (end 108.36339 99.409216) (width 0.109) (layer "In4.Cu") (net 57))
  (segment (start 92.2355 102.544186) (end 92.582186 102.1975) (width 0.109) (layer "In4.Cu") (net 57))
  (segment (start 108.429522 99.698955) (end 108.38581 99.608185) (width 0.109) (layer "In4.Cu") (net 57))
  (segment (start 108.36339 99.409216) (end 108.385809 99.310995) (width 0.109) (layer "In4.Cu") (net 57))
  (segment (start 110.061894 99.965543) (end 110.110469 99.97663) (width 0.109) (layer "In4.Cu") (net 57))
  (segment (start 109.521308 98.112486) (end 109.600075 98.049671) (width 0.109) (layer "In4.Cu") (net 57))
  (segment (start 109.088857 99.039622) (end 109.167626 99.102436) (width 0.109) (layer "In4.Cu") (net 57))
  (segment (start 111.13469 97.78499) (end 112.094763 96.824924) (width 0.109) (layer "In4.Cu") (net 57))
  (segment (start 110.323775 99.637153) (end 110.292711 99.598199) (width 0.109) (layer "In4.Cu") (net 57))
  (segment (start 109.690846 98.005958) (end 109.789068 97.98354) (width 0.109) (layer "In4.Cu") (net 57))
  (segment (start 111.335343 98.692093) (end 111.313725 98.647203) (width 0.109) (layer "In4.Cu") (net 57))
  (segment (start 109.167626 99.102436) (end 109.97805 99.912861) (width 0.109) (layer "In4.Cu") (net 57))
  (segment (start 109.889816 97.98354) (end 109.988036 98.005959) (width 0.109) (layer "In4.Cu") (net 57))
  (segment (start 109.36653 100.770391) (end 109.36653 100.720567) (width 0.109) (layer "In4.Cu") (net 57))
  (segment (start 109.218917 100.955493) (end 109.263807 100.933875) (width 0.109) (layer "In4.Cu") (net 57))
  (segment (start 111.11518 98.440768) (end 111.052365 98.362) (width 0.109) (layer "In4.Cu") (net 57))
  (segment (start 109.302761 100.90281) (end 109.333825 100.863856) (width 0.109) (layer "In4.Cu") (net 57))
  (segment (start 123.326276 93.904499) (end 123.496777 94.075) (width 0.109) (layer "In4.Cu") (net 57))
  (segment (start 108.38581 99.608185) (end 108.36339 99.509964) (width 0.109) (layer "In4.Cu") (net 57))
  (segment (start 111.282661 98.608249) (end 111.11518 98.440768) (width 0.109) (layer "In4.Cu") (net 57))
  (segment (start 111.313725 98.883957) (end 111.335343 98.839067) (width 0.109) (layer "In4.Cu") (net 57))
  (segment (start 109.355443 100.818966) (end 109.36653 100.770391) (width 0.109) (layer "In4.Cu") (net 57))
  (segment (start 108.385809 99.310995) (end 108.42952 99.220225) (width 0.109) (layer "In4.Cu") (net 57))
  (segment (start 121.707186 93.1225) (end 123.002814 93.1225) (width 0.109) (layer "In4.Cu") (net 57))
  (segment (start 108.9881 100.90281) (end 109.027054 100.933875) (width 0.109) (layer "In4.Cu") (net 57))
  (segment (start 109.35334 98.419266) (end 109.375759 98.321045) (width 0.109) (layer "In4.Cu") (net 57))
  (segment (start 108.531358 99.102436) (end 108.610125 99.039621) (width 0.109) (layer "In4.Cu") (net 57))
  (segment (start 109.789068 97.98354) (end 109.889816 97.98354) (width 0.109) (layer "In4.Cu") (net 57))
  (segment (start 109.600075 98.049671) (end 109.690846 98.005958) (width 0.109) (layer "In4.Cu") (net 57))
  (segment (start 108.799118 98.97349) (end 108.899866 98.97349) (width 0.109) (layer "In4.Cu") (net 57))
  (segment (start 111.006954 98.953975) (end 111.051844 98.975593) (width 0.109) (layer "In4.Cu") (net 57))
  (segment (start 110.160293 99.97663) (end 110.208868 99.965543) (width 0.109) (layer "In4.Cu") (net 57))
  (segment (start 109.027054 100.933875) (end 109.071944 100.955493) (width 0.109) (layer "In4.Cu") (net 57))
  (segment (start 111.052365 97.883267) (end 111.11518 97.8045) (width 0.109) (layer "In4.Cu") (net 57))
  (segment (start 123.002814 93.1225) (end 123.326276 93.445962) (width 0.109) (layer "In4.Cu") (net 57))
  (segment (start 111.008652 97.974038) (end 111.052365 97.883267) (width 0.109) (layer "In4.Cu") (net 57))
  (segment (start 108.26312 100.672514) (end 108.35389 100.628801) (width 0.109) (layer "In4.Cu") (net 57))
  (segment (start 110.345393 99.829017) (end 110.35648 99.780442) (width 0.109) (layer "In4.Cu") (net 57))
  (segment (start 110.35648 99.730618) (end 110.345393 99.682043) (width 0.109) (layer "In4.Cu") (net 57))
  (segment (start 111.052365 98.362) (end 111.008652 98.271229) (width 0.109) (layer "In4.Cu") (net 57))
  (segment (start 110.110469 99.97663) (end 110.160293 99.97663) (width 0.109) (layer "In4.Cu") (net 57))
  (segment (start 89.8265 100.794) (end 90.306 100.483) (width 0.182) (layer "F.Cu") (net 58))
  (segment (start 124.860999 93.656001) (end 124.860999 93.970921) (width 0.182) (layer "F.Cu") (net 58))
  (segment (start 124.6 93.395) (end 124.860999 93.656001) (width 0.182) (layer "F.Cu") (net 58))
  (segment (start 124.860999 93.970921) (end 124.751999 94.079921) (width 0.182) (layer "F.Cu") (net 58))
  (via (at 124.751999 94.079921) (size 0.45) (drill 0.1) (layers "F.Cu" "B.Cu") (net 58))
  (via (at 90.306 100.483) (size 0.45) (drill 0.1) (layers "F.Cu" "B.Cu") (net 58))
  (segment (start 94.499121 100.210371) (end 94.5325 100.214132) (width 0.109) (layer "In4.Cu") (net 58))
  (segment (start 124.420539 91.012671) (end 124.449794 91.019348) (width 0.109) (layer "In4.Cu") (net 58))
  (segment (start 124.331639 90.901192) (end 124.338316 90.930447) (width 0.109) (layer "In4.Cu") (net 58))
  (segment (start 124.425831 90.735651) (end 124.370044 90.791437) (width 0.109) (layer "In4.Cu") (net 58))
  (segment (start 124.464236 90.655902) (end 124.457558 90.685155) (width 0.109) (layer "In4.Cu") (net 58))
  (segment (start 124.754347 90.89343) (end 124.781382 90.906448) (width 0.109) (layer "In4.Cu") (net 58))
  (segment (start 124.44454 90.569605) (end 124.457559 90.596641) (width 0.109) (layer "In4.Cu") (net 58))
  (segment (start 94.467417 100.199277) (end 94.499121 100.210371) (width 0.109) (layer "In4.Cu") (net 58))
  (segment (start 124.227186 90.3475) (end 124.425834 90.546147) (width 0.109) (layer "In4.Cu") (net 58))
  (segment (start 94.649774 100.157655) (end 94.667645 100.129214) (width 0.109) (layer "In4.Cu") (net 58))
  (segment (start 124.509055 91.01267) (end 124.53609 90.999653) (width 0.109) (layer "In4.Cu") (net 58))
  (segment (start 94.626023 100.181406) (end 94.649774 100.157655) (width 0.109) (layer "In4.Cu") (net 58))
  (segment (start 124.457558 90.685155) (end 124.444539 90.71219) (width 0.109) (layer "In4.Cu") (net 58))
  (segment (start 94.438976 100.181406) (end 94.467417 100.199277) (width 0.109) (layer "In4.Cu") (net 58))
  (segment (start 124.804841 90.925157) (end 124.922499 91.042815) (width 0.109) (layer "In4.Cu") (net 58))
  (segment (start 116.512814 90.3475) (end 124.227186 90.3475) (width 0.109) (layer "In4.Cu") (net 58))
  (segment (start 94.2325 99.8975) (end 94.265878 99.90126) (width 0.109) (layer "In4.Cu") (net 58))
  (segment (start 124.425834 90.546147) (end 124.44454 90.569605) (width 0.109) (layer "In4.Cu") (net 58))
  (segment (start 124.331639 90.871186) (end 124.331639 90.901192) (width 0.109) (layer "In4.Cu") (net 58))
  (segment (start 124.665833 90.893429) (end 124.695086 90.886753) (width 0.109) (layer "In4.Cu") (net 58))
  (segment (start 94.6825 100.064132) (end 94.6825 100.0475) (width 0.109) (layer "In4.Cu") (net 58))
  (segment (start 94.367645 99.982417) (end 94.378739 100.014121) (width 0.109) (layer "In4.Cu") (net 58))
  (segment (start 94.265878 99.90126) (end 94.297582 99.912354) (width 0.109) (layer "In4.Cu") (net 58))
  (segment (start 94.738976 99.930225) (end 94.767417 99.912354) (width 0.109) (layer "In4.Cu") (net 58))
  (segment (start 89.954 100.066314) (end 90.122814 99.8975) (width 0.109) (layer "In4.Cu") (net 58))
  (segment (start 124.53609 90.999653) (end 124.559549 90.980943) (width 0.109) (layer "In4.Cu") (net 58))
  (segment (start 124.615337 90.925158) (end 124.638798 90.906448) (width 0.109) (layer "In4.Cu") (net 58))
  (segment (start 124.370044 90.791437) (end 124.351336 90.814898) (width 0.109) (layer "In4.Cu") (net 58))
  (segment (start 94.565878 100.210371) (end 94.597582 100.199277) (width 0.109) (layer "In4.Cu") (net 58))
  (segment (start 94.397354 100.129214) (end 94.415225 100.157655) (width 0.109) (layer "In4.Cu") (net 58))
  (segment (start 94.715225 99.953976) (end 94.738976 99.930225) (width 0.109) (layer "In4.Cu") (net 58))
  (segment (start 124.351336 90.814898) (end 124.338317 90.841933) (width 0.109) (layer "In4.Cu") (net 58))
  (segment (start 94.68626 100.014121) (end 94.697354 99.982417) (width 0.109) (layer "In4.Cu") (net 58))
  (segment (start 90.306 100.483) (end 90.053 100.483) (width 0.109) (layer "In4.Cu") (net 58))
  (segment (start 94.678739 100.09751) (end 94.6825 100.064132) (width 0.109) (layer "In4.Cu") (net 58))
  (segment (start 124.781382 90.906448) (end 124.804841 90.925157) (width 0.109) (layer "In4.Cu") (net 58))
  (segment (start 94.799121 99.90126) (end 94.8325 99.8975) (width 0.109) (layer "In4.Cu") (net 58))
  (segment (start 124.922499 91.042815) (end 124.922499 93.909421) (width 0.109) (layer "In4.Cu") (net 58))
  (segment (start 90.053 100.483) (end 89.954 100.384) (width 0.109) (layer "In4.Cu") (net 58))
  (segment (start 124.449794 91.019348) (end 124.4798 91.019348) (width 0.109) (layer "In4.Cu") (net 58))
  (segment (start 94.8325 99.8975) (end 106.962814 99.8975) (width 0.109) (layer "In4.Cu") (net 58))
  (segment (start 94.667645 100.129214) (end 94.678739 100.09751) (width 0.109) (layer "In4.Cu") (net 58))
  (segment (start 124.393506 90.999651) (end 124.420539 91.012671) (width 0.109) (layer "In4.Cu") (net 58))
  (segment (start 90.122814 99.8975) (end 94.2325 99.8975) (width 0.109) (layer "In4.Cu") (net 58))
  (segment (start 124.4798 91.019348) (end 124.509055 91.01267) (width 0.109) (layer "In4.Cu") (net 58))
  (segment (start 94.349774 99.953976) (end 94.367645 99.982417) (width 0.109) (layer "In4.Cu") (net 58))
  (segment (start 124.444539 90.71219) (end 124.425831 90.735651) (width 0.109) (layer "In4.Cu") (net 58))
  (segment (start 124.457559 90.596641) (end 124.464237 90.625894) (width 0.109) (layer "In4.Cu") (net 58))
  (segment (start 124.338316 90.930447) (end 124.351335 90.957483) (width 0.109) (layer "In4.Cu") (net 58))
  (segment (start 94.597582 100.199277) (end 94.626023 100.181406) (width 0.109) (layer "In4.Cu") (net 58))
  (segment (start 124.922499 93.909421) (end 124.751999 94.079921) (width 0.109) (layer "In4.Cu") (net 58))
  (segment (start 124.338317 90.841933) (end 124.331639 90.871186) (width 0.109) (layer "In4.Cu") (net 58))
  (segment (start 124.638798 90.906448) (end 124.665833 90.893429) (width 0.109) (layer "In4.Cu") (net 58))
  (segment (start 106.962814 99.8975) (end 116.512814 90.3475) (width 0.109) (layer "In4.Cu") (net 58))
  (segment (start 94.697354 99.982417) (end 94.715225 99.953976) (width 0.109) (layer "In4.Cu") (net 58))
  (segment (start 124.559549 90.980943) (end 124.615337 90.925158) (width 0.109) (layer "In4.Cu") (net 58))
  (segment (start 94.767417 99.912354) (end 94.799121 99.90126) (width 0.109) (layer "In4.Cu") (net 58))
  (segment (start 94.3825 100.0475) (end 94.3825 100.064132) (width 0.109) (layer "In4.Cu") (net 58))
  (segment (start 89.954 100.384) (end 89.954 100.066314) (width 0.109) (layer "In4.Cu") (net 58))
  (segment (start 94.5325 100.214132) (end 94.565878 100.210371) (width 0.109) (layer "In4.Cu") (net 58))
  (segment (start 94.38626 100.09751) (end 94.397354 100.129214) (width 0.109) (layer "In4.Cu") (net 58))
  (segment (start 124.351335 90.957483) (end 124.370045 90.980942) (width 0.109) (layer "In4.Cu") (net 58))
  (segment (start 94.415225 100.157655) (end 94.438976 100.181406) (width 0.109) (layer "In4.Cu") (net 58))
  (segment (start 94.326023 99.930225) (end 94.349774 99.953976) (width 0.109) (layer "In4.Cu") (net 58))
  (segment (start 94.6825 100.0475) (end 94.68626 100.014121) (width 0.109) (layer "In4.Cu") (net 58))
  (segment (start 124.464237 90.625894) (end 124.464236 90.655902) (width 0.109) (layer "In4.Cu") (net 58))
  (segment (start 124.725092 90.886753) (end 124.754347 90.89343) (width 0.109) (layer "In4.Cu") (net 58))
  (segment (start 94.378739 100.014121) (end 94.3825 100.0475) (width 0.109) (layer "In4.Cu") (net 58))
  (segment (start 124.695086 90.886753) (end 124.725092 90.886753) (width 0.109) (layer "In4.Cu") (net 58))
  (segment (start 94.3825 100.064132) (end 94.38626 100.09751) (width 0.109) (layer "In4.Cu") (net 58))
  (segment (start 94.297582 99.912354) (end 94.326023 99.930225) (width 0.109) (layer "In4.Cu") (net 58))
  (segment (start 124.370045 90.980942) (end 124.393506 90.999651) (width 0.109) (layer "In4.Cu") (net 58))
  (segment (start 89.35 100.473) (end 89.8265 100.159) (width 0.182) (layer "F.Cu") (net 59))
  (segment (start 125.238999 93.656001) (end 125.238999 93.970921) (width 0.182) (layer "F.Cu") (net 59))
  (segment (start 125.238999 93.970921) (end 125.347999 94.079921) (width 0.182) (layer "F.Cu") (net 59))
  (segment (start 125.5 93.395) (end 125.238999 93.656001) (width 0.182) (layer "F.Cu") (net 59))
  (segment (start 125.347999 94.079921) (end 125.348 94.079921) (width 0.182) (layer "F.Cu") (net 59))
  (via (at 125.348 94.079921) (size 0.45) (drill 0.1) (layers "F.Cu" "B.Cu") (net 59))
  (via (at 89.35 100.473) (size 0.45) (drill 0.1) (layers "F.Cu" "B.Cu") (net 59))
  (segment (start 125.1775 93.909421) (end 125.348 94.079921) (width 0.109) (layer "In4.Cu") (net 59))
  (segment (start 125.177499 90.937187) (end 125.1775 93.909421) (width 0.109) (layer "In4.Cu") (net 59))
  (segment (start 89.607 100.473) (end 89.699 100.381) (width 0.109) (layer "In4.Cu") (net 59))
  (segment (start 124.332814 90.0925) (end 125.177499 90.937187) (width 0.109) (layer "In4.Cu") (net 59))
  (segment (start 106.857186 99.6425) (end 116.407186 90.0925) (width 0.109) (layer "In4.Cu") (net 59))
  (segment (start 90.017186 99.6425) (end 106.857186 99.6425) (width 0.109) (layer "In4.Cu") (net 59))
  (segment (start 89.699 100.381) (end 89.699 99.960686) (width 0.109) (layer "In4.Cu") (net 59))
  (segment (start 89.35 100.473) (end 89.607 100.473) (width 0.109) (layer "In4.Cu") (net 59))
  (segment (start 116.407186 90.0925) (end 124.332814 90.0925) (width 0.109) (layer "In4.Cu") (net 59))
  (segment (start 89.699 99.960686) (end 90.017186 99.6425) (width 0.109) (layer "In4.Cu") (net 59))
  (segment (start 129.644803 86.736801) (end 129.753803 86.627801) (width 0.182) (layer "F.Cu") (net 60))
  (segment (start 128.66315 86.545862) (end 128.854089 86.736801) (width 0.182) (layer "F.Cu") (net 60))
  (segment (start 128.311342 86.534862) (end 128.322342 86.545862) (width 0.182) (layer "F.Cu") (net 60))
  (segment (start 129.753803 86.627801) (end 129.753803 86.6278) (width 0.182) (layer "F.Cu") (net 60))
  (segment (start 127.907742 86.534862) (end 128.311342 86.534862) (width 0.182) (layer "F.Cu") (net 60))
  (segment (start 128.322342 86.545862) (end 128.66315 86.545862) (width 0.182) (layer "F.Cu") (net 60))
  (segment (start 128.854089 86.736801) (end 129.644803 86.736801) (width 0.182) (layer "F.Cu") (net 60))
  (via (at 129.753803 86.6278) (size 0.45) (drill 0.1) (layers "F.Cu" "B.Cu") (net 60))
  (via (at 129.528999 77.375001) (size 0.45) (drill 0.1) (layers "F.Cu" "B.Cu") (net 60))
  (segment (start 131.196385 86.798301) (end 131.864868 86.129817) (width 0.109) (layer "In2.Cu") (net 60))
  (segment (start 131.831503 85.65655) (end 131.814501 85.691856) (width 0.109) (layer "In2.Cu") (net 60))
  (segment (start 132.103424 85.625912) (end 132.072786 85.601479) (width 0.109) (layer "In2.Cu") (net 60))
  (segment (start 131.915023 86.025666) (end 131.906302 86.063871) (width 0.109) (layer "In2.Cu") (net 60))
  (segment (start 131.814501 85.691856) (end 131.805781 85.730061) (width 0.109) (layer "In2.Cu") (net 60))
  (segment (start 132.142993 85.659276) (end 132.112355 85.634843) (width 0.109) (layer "In2.Cu") (net 60))
  (segment (start 131.8893 85.912967) (end 131.906302 85.948273) (width 0.109) (layer "In2.Cu") (net 60))
  (segment (start 131.855937 85.873399) (end 131.864867 85.882329) (width 0.109) (layer "In2.Cu") (net 60))
  (segment (start 131.864867 85.882329) (end 131.8893 85.912967) (width 0.109) (layer "In2.Cu") (net 60))
  (segment (start 132.255693 85.684998) (end 132.216505 85.684998) (width 0.109) (layer "In2.Cu") (net 60))
  (segment (start 132.072786 85.601479) (end 132.03748 85.584477) (width 0.109) (layer "In2.Cu") (net 60))
  (segment (start 131.855937 85.625912) (end 131.831503 85.65655) (width 0.109) (layer "In2.Cu") (net 60))
  (segment (start 129.699499 78.149813) (end 130.177186 78.6275) (width 0.109) (layer "In2.Cu") (net 60))
  (segment (start 131.814501 85.807454) (end 131.831503 85.842761) (width 0.109) (layer "In2.Cu") (net 60))
  (segment (start 131.886575 85.601479) (end 131.855937 85.625912) (width 0.109) (layer "In2.Cu") (net 60))
  (segment (start 131.196385 86.798301) (end 129.924303 86.798301) (width 0.109) (layer "In2.Cu") (net 60))
  (segment (start 132.1783 85.676278) (end 132.142993 85.659276) (width 0.109) (layer "In2.Cu") (net 60))
  (segment (start 132.329204 85.659276) (end 132.293898 85.676278) (width 0.109) (layer "In2.Cu") (net 60))
  (segment (start 132.293898 85.676278) (end 132.255693 85.684998) (width 0.109) (layer "In2.Cu") (net 60))
  (segment (start 131.831503 85.842761) (end 131.855937 85.873399) (width 0.109) (layer "In2.Cu") (net 60))
  (segment (start 129.528999 77.375001) (end 129.699499 77.545501) (width 0.109) (layer "In2.Cu") (net 60))
  (segment (start 131.347186 78.6275) (end 132.9475 80.227814) (width 0.109) (layer "In2.Cu") (net 60))
  (segment (start 129.753803 86.627801) (end 129.753803 86.6278) (width 0.109) (layer "In2.Cu") (net 60))
  (segment (start 129.699499 77.545501) (end 129.699499 78.149813) (width 0.109) (layer "In2.Cu") (net 60))
  (segment (start 132.216505 85.684998) (end 132.1783 85.676278) (width 0.109) (layer "In2.Cu") (net 60))
  (segment (start 131.906302 86.063871) (end 131.8893 86.099178) (width 0.109) (layer "In2.Cu") (net 60))
  (segment (start 132.359843 85.634843) (end 132.329204 85.659276) (width 0.109) (layer "In2.Cu") (net 60))
  (segment (start 131.906302 85.948273) (end 131.915023 85.986478) (width 0.109) (layer "In2.Cu") (net 60))
  (segment (start 131.915023 85.986478) (end 131.915023 86.025666) (width 0.109) (layer "In2.Cu") (net 60))
  (segment (start 131.805781 85.769249) (end 131.814501 85.807454) (width 0.109) (layer "In2.Cu") (net 60))
  (segment (start 131.999275 85.575756) (end 131.960087 85.575756) (width 0.109) (layer "In2.Cu") (net 60))
  (segment (start 131.960087 85.575756) (end 131.921882 85.584477) (width 0.109) (layer "In2.Cu") (net 60))
  (segment (start 131.805781 85.730061) (end 131.805781 85.769249) (width 0.109) (layer "In2.Cu") (net 60))
  (segment (start 131.8893 86.099178) (end 131.864868 86.129817) (width 0.109) (layer "In2.Cu") (net 60))
  (segment (start 129.924303 86.798301) (end 129.753803 86.627801) (width 0.109) (layer "In2.Cu") (net 60))
  (segment (start 130.177186 78.6275) (end 131.347186 78.6275) (width 0.109) (layer "In2.Cu") (net 60))
  (segment (start 132.112355 85.634843) (end 132.103424 85.625912) (width 0.109) (layer "In2.Cu") (net 60))
  (segment (start 132.9475 85.047186) (end 132.359843 85.634843) (width 0.109) (layer "In2.Cu") (net 60))
  (segment (start 132.03748 85.584477) (end 131.999275 85.575756) (width 0.109) (layer "In2.Cu") (net 60))
  (segment (start 132.9475 80.227814) (end 132.9475 85.047186) (width 0.109) (layer "In2.Cu") (net 60))
  (segment (start 131.921882 85.584477) (end 131.886575 85.601479) (width 0.109) (layer "In2.Cu") (net 60))
  (segment (start 130.311 76.021712) (end 129.638 76.694712) (width 0.182) (layer "B.Cu") (net 60))
  (segment (start 130.05 75.59) (end 130.311 75.851) (width 0.182) (layer "B.Cu") (net 60))
  (segment (start 130.311 75.851) (end 130.311 76.021712) (width 0.182) (layer "B.Cu") (net 60))
  (segment (start 129.638 76.694712) (end 129.638 77.266) (width 0.182) (layer "B.Cu") (net 60))
  (segment (start 129.638 77.266) (end 129.528999 77.375001) (width 0.182) (layer "B.Cu") (net 60))
  (segment (start 128.311342 86.934861) (end 128.322342 86.923861) (width 0.182) (layer "F.Cu") (net 61))
  (segment (start 127.907742 86.934861) (end 128.311342 86.934861) (width 0.182) (layer "F.Cu") (net 61))
  (segment (start 128.506573 86.923861) (end 128.697513 87.114801) (width 0.182) (layer "F.Cu") (net 61))
  (segment (start 129.644803 87.114801) (end 129.753803 87.223801) (width 0.182) (layer "F.Cu") (net 61))
  (segment (start 128.697513 87.114801) (end 129.644803 87.114801) (width 0.182) (layer "F.Cu") (net 61))
  (segment (start 128.322342 86.923861) (end 128.506573 86.923861) (width 0.182) (layer "F.Cu") (net 61))
  (via (at 129.753803 87.223801) (size 0.45) (drill 0.1) (layers "F.Cu" "B.Cu") (net 61))
  (via (at 130.125 77.375) (size 0.45) (drill 0.1) (layers "F.Cu" "B.Cu") (net 61))
  (segment (start 130.282814 78.3725) (end 131.452814 78.3725) (width 0.109) (layer "In2.Cu") (net 61))
  (segment (start 133.2025 80.122186) (end 133.2025 85.152814) (width 0.109) (layer "In2.Cu") (net 61))
  (segment (start 131.452814 78.3725) (end 133.2025 80.122186) (width 0.109) (layer "In2.Cu") (net 61))
  (segment (start 131.302013 87.053301) (end 129.924303 87.053301) (width 0.109) (layer "In2.Cu") (net 61))
  (segment (start 130.125 77.375) (end 129.954499 77.545501) (width 0.109) (layer "In2.Cu") (net 61))
  (segment (start 129.924303 87.053301) (end 129.753803 87.223801) (width 0.109) (layer "In2.Cu") (net 61))
  (segment (start 129.954499 78.044185) (end 130.282814 78.3725) (width 0.109) (layer "In2.Cu") (net 61))
  (segment (start 133.2025 85.152814) (end 131.302013 87.053301) (width 0.109) (layer "In2.Cu") (net 61))
  (segment (start 129.954499 77.545501) (end 129.954499 78.044185) (width 0.109) (layer "In2.Cu") (net 61))
  (segment (start 130.95 75.59) (end 130.689 75.851) (width 0.182) (layer "B.Cu") (net 61))
  (segment (start 130.016 77.266) (end 130.125 77.375) (width 0.182) (layer "B.Cu") (net 61))
  (segment (start 130.689 76.178288) (end 130.016 76.851288) (width 0.182) (layer "B.Cu") (net 61))
  (segment (start 130.016 76.851288) (end 130.016 77.266) (width 0.182) (layer "B.Cu") (net 61))
  (segment (start 130.689 75.851) (end 130.689 76.178288) (width 0.182) (layer "B.Cu") (net 61))
  (segment (start 125.329942 78.33146) (end 125.329941 77.990654) (width 0.182) (layer "F.Cu") (net 62))
  (segment (start 125.520883 77.799712) (end 125.520883 77.009) (width 0.182) (layer "F.Cu") (net 62))
  (segment (start 125.329941 77.990654) (end 125.520883 77.799712) (width 0.182) (layer "F.Cu") (net 62))
  (segment (start 130.311 76.158288) (end 130.9852 76.832488) (width 0.182) (layer "F.Cu") (net 62))
  (segment (start 130.311 75.856) (end 130.311 76.158288) (width 0.182) (layer "F.Cu") (net 62))
  (segment (start 130.311 75.856) (end 130.05 75.595) (width 0.182) (layer "F.Cu") (net 62))
  (segment (start 125.411883 76.9) (end 125.520883 77.009) (width 0.182) (layer "F.Cu") (net 62))
  (segment (start 130.9852 76.832488) (end 130.9852 77.259803) (width 0.182) (layer "F.Cu") (net 62))
  (segment (start 125.318941 78.342461) (end 125.329942 78.33146) (width 0.182) (layer "F.Cu") (net 62))
  (segment (start 130.9852 77.259803) (end 130.876199 77.368804) (width 0.182) (layer "F.Cu") (net 62))
  (segment (start 125.318941 78.746061) (end 125.318941 78.342461) (width 0.182) (layer "F.Cu") (net 62))
  (via (at 125.411882 76.9) (size 0.45) (drill 0.1) (layers "F.Cu" "B.Cu") (net 62))
  (via (at 130.876199 77.368804) (size 0.45) (drill 0.1) (layers "F.Cu" "B.Cu") (net 62))
  (segment locked (start 129.052814 75.9775) (end 127.002814 78.0275) (width 0.109) (layer "In4.Cu") (net 62))
  (segment (start 127.002814 78.0275) (end 125.972186 78.0275) (width 0.109) (layer "In4.Cu") (net 62))
  (segment (start 131.0467 76.677014) (end 130.347186 75.9775) (width 0.109) (layer "In4.Cu") (net 62))
  (segment (start 131.0467 77.198303) (end 131.0467 76.677014) (width 0.109) (layer "In4.Cu") (net 62))
  (segment (start 125.411883 76.9) (end 125.411882 76.9) (width 0.109) (layer "In4.Cu") (net 62))
  (segment (start 130.876199 77.368804) (end 131.0467 77.198303) (width 0.109) (layer "In4.Cu") (net 62))
  (segment (start 130.347186 75.9775) (end 129.052814 75.9775) (width 0.109) (layer "In4.Cu") (net 62))
  (segment (start 125.582383 77.637697) (end 125.582383 77.0705) (width 0.109) (layer "In4.Cu") (net 62))
  (segment (start 125.582383 77.0705) (end 125.411883 76.9) (width 0.109) (layer "In4.Cu") (net 62))
  (segment (start 125.972186 78.0275) (end 125.582383 77.637697) (width 0.109) (layer "In4.Cu") (net 62))
  (segment (start 125.707942 78.33146) (end 125.707942 78.14723) (width 0.182) (layer "F.Cu") (net 63))
  (segment (start 125.718943 78.342461) (end 125.707942 78.33146) (width 0.182) (layer "F.Cu") (net 63))
  (segment (start 125.898883 77.956289) (end 125.898883 77.008999) (width 0.182) (layer "F.Cu") (net 63))
  (segment (start 125.707942 78.14723) (end 125.898883 77.956289) (width 0.182) (layer "F.Cu") (net 63))
  (segment (start 125.718943 78.746061) (end 125.718943 78.342461) (width 0.182) (layer "F.Cu") (net 63))
  (segment (start 126.007883 76.9) (end 125.898883 77.008999) (width 0.182) (layer "F.Cu") (net 63))
  (segment (start 130.689 75.856) (end 130.689 76.001712) (width 0.182) (layer "F.Cu") (net 63))
  (segment (start 131.3632 77.259803) (end 131.4722 77.368803) (width 0.182) (layer "F.Cu") (net 63))
  (segment (start 130.689 76.001712) (end 131.3632 76.675912) (width 0.182) (layer "F.Cu") (net 63))
  (segment (start 130.689 75.856) (end 130.95 75.595) (width 0.182) (layer "F.Cu") (net 63))
  (segment (start 131.3632 76.675912) (end 131.3632 77.259803) (width 0.182) (layer "F.Cu") (net 63))
  (via (at 126.007883 76.9) (size 0.45) (drill 0.1) (layers "F.Cu" "B.Cu") (net 63))
  (via (at 131.4722 77.368803) (size 0.45) (drill 0.1) (layers "F.Cu" "B.Cu") (net 63))
  (segment (start 125.837383 77.0705) (end 126.007883 76.9) (width 0.109) (layer "In4.Cu") (net 63))
  (segment (start 128.947186 75.7225) (end 126.897186 77.7725) (width 0.109) (layer "In4.Cu") (net 63))
  (segment (start 131.3017 76.571386) (end 130.452814 75.7225) (width 0.109) (layer "In4.Cu") (net 63))
  (segment (start 131.4722 77.368803) (end 131.3017 77.198303) (width 0.109) (layer "In4.Cu") (net 63))
  (segment (start 126.897186 77.7725) (end 126.077814 77.7725) (width 0.109) (layer "In4.Cu") (net 63))
  (segment (start 125.837383 77.532069) (end 125.837383 77.0705) (width 0.109) (layer "In4.Cu") (net 63))
  (segment (start 126.077814 77.7725) (end 125.837383 77.532069) (width 0.109) (layer "In4.Cu") (net 63))
  (segment (start 130.452814 75.7225) (end 128.947186 75.7225) (width 0.109) (layer "In4.Cu") (net 63))
  (segment (start 131.3017 77.198303) (end 131.3017 76.571386) (width 0.109) (layer "In4.Cu") (net 63))
  (segment (start 135.898428 74.051572) (end 135.9 74.05) (width 0.4) (layer "F.Cu") (net 64))
  (segment (start 136.95 73.575) (end 138.015 73.575) (width 0.4) (layer "F.Cu") (net 64))
  (segment (start 136.475 74.05) (end 136.95 73.575) (width 0.4) (layer "F.Cu") (net 64))
  (segment (start 135.9 74.05) (end 136.475 74.05) (width 0.4) (layer "F.Cu") (net 64))
  (segment (start 135.093449 74.051572) (end 135.898428 74.051572) (width 0.4) (layer "F.Cu") (net 64))
  (via (at 135.093449 74.051572) (size 0.45) (drill 0.1) (layers "F.Cu" "B.Cu") (net 64))
  (via (at 135.9 74.05) (size 0.45) (drill 0.1) (layers "F.Cu" "B.Cu") (net 64))
  (segment (start 135.102449 74.042572) (end 135.093449 74.051572) (width 0.182) (layer "B.Cu") (net 64))
  (segment (start 135.102449 73.474573) (end 135.102449 74.042572) (width 0.182) (layer "B.Cu") (net 64))
  (segment (start 130.338579 64.226421) (end 130.33 64.235) (width 0.182) (layer "B.Cu") (net 64))
  (segment (start 131.475736 64.226421) (end 132.375736 64.226421) (width 0.4) (layer "B.Cu") (net 64))
  (segment (start 133.4 64.2) (end 133.4 64.8) (width 0.4) (layer "B.Cu") (net 64))
  (segment (start 131.35 64.226421) (end 130.338579 64.226421) (width 0.182) (layer "B.Cu") (net 64))
  (segment (start 133.287157 64.2) (end 133.4 64.2) (width 0.4) (layer "B.Cu") (net 64))
  (segment (start 133.25 65.73) (end 133.25 64.95) (width 0.4) (layer "B.Cu") (net 64))
  (segment (start 132.375736 64.226421) (end 133.260736 64.226421) (width 0.4) (layer "B.Cu") (net 64))
  (segment (start 133.4 64.8) (end 133.25 64.95) (width 0.4) (layer "B.Cu") (net 64))
  (segment (start 133.260736 64.226421) (end 133.287157 64.2) (width 0.4) (layer "B.Cu") (net 64))
  (segment (start 122.532534 76.929) (end 122.532534 78.732468) (width 0.182) (layer "F.Cu") (net 65))
  (segment (start 122.423534 76.82) (end 122.532534 76.929) (width 0.182) (layer "F.Cu") (net 65))
  (segment (start 122.528604 78.736398) (end 122.518941 78.746061) (width 0.182) (layer "F.Cu") (net 65))
  (segment (start 122.532534 78.732468) (end 122.518941 78.746061) (width 0.182) (layer "F.Cu") (net 65))
  (segment (start 122.423533 76.82) (end 122.423534 76.82) (width 0.182) (layer "F.Cu") (net 65))
  (via (at 122.423533 76.82) (size 0.45) (drill 0.1) (layers "F.Cu" "B.Cu") (net 65))
  (via (at 110.1778 77.406197) (size 0.45) (drill 0.1) (layers "F.Cu" "B.Cu") (net 65))
  (segment (start 122.041006 74.774565) (end 122.019174 74.779548) (width 0.109) (layer "In2.Cu") (net 65))
  (segment (start 110.3483 77.576697) (end 110.1778 77.406197) (width 0.109) (layer "In2.Cu") (net 65))
  (segment (start 120.0735 74.28165) (end 120.070767 74.305905) (width 0.109) (layer "In2.Cu") (net 65))
  (segment (start 119.9645 74.39065) (end 119.940245 74.387918) (width 0.109) (layer "In2.Cu") (net 65))
  (segment (start 119.345094 74.1525) (end 114.920094 78.5775) (width 0.109) (layer "In2.Cu") (net 65))
  (segment (start 120.114539 74.176281) (end 120.09728 74.19354) (width 0.109) (layer "In2.Cu") (net 65))
  (segment (start 120.09728 74.19354) (end 120.084294 74.214207) (width 0.109) (layer "In2.Cu") (net 65))
  (segment (start 121.85102 74.545339) (end 121.841304 74.525164) (width 0.109) (layer "In2.Cu") (net 65))
  (segment (start 121.921978 74.831887) (end 121.899585 74.831887) (width 0.109) (layer "In2.Cu") (net 65))
  (segment (start 120.076232 74.237246) (end 120.0735 74.2615) (width 0.109) (layer "In2.Cu") (net 65))
  (segment (start 121.827343 74.507657) (end 121.472186 74.1525) (width 0.109) (layer "In2.Cu") (net 65))
  (segment (start 122.594034 76.6495) (end 122.594034 75.274348) (width 0.109) (layer "In2.Cu") (net 65))
  (segment (start 114.920094 78.5775) (end 110.647186 78.5775) (width 0.109) (layer "In2.Cu") (net 65))
  (segment (start 121.472186 74.1525) (end 120.1825 74.1525) (width 0.109) (layer "In2.Cu") (net 65))
  (segment (start 121.803665 74.752816) (end 121.798682 74.730985) (width 0.109) (layer "In2.Cu") (net 65))
  (segment (start 122.423534 76.82) (end 122.594034 76.6495) (width 0.109) (layer "In2.Cu") (net 65))
  (segment (start 119.844705 74.214207) (end 119.831719 74.19354) (width 0.109) (layer "In2.Cu") (net 65))
  (segment (start 119.940245 74.387918) (end 119.917206 74.379856) (width 0.109) (layer "In2.Cu") (net 65))
  (segment (start 121.841304 74.63157) (end 121.85102 74.611395) (width 0.109) (layer "In2.Cu") (net 65))
  (segment (start 119.917206 74.379856) (end 119.896539 74.36687) (width 0.109) (layer "In2.Cu") (net 65))
  (segment (start 119.8555 74.28165) (end 119.8555 74.2615) (width 0.109) (layer "In2.Cu") (net 65))
  (segment (start 120.158245 74.155233) (end 120.135206 74.163295) (width 0.109) (layer "In2.Cu") (net 65))
  (segment (start 120.1825 74.1525) (end 120.158245 74.155233) (width 0.109) (layer "In2.Cu") (net 65))
  (segment (start 122.423533 76.82) (end 122.423534 76.82) (width 0.109) (layer "In2.Cu") (net 65))
  (segment (start 119.8555 74.2615) (end 119.852767 74.237246) (width 0.109) (layer "In2.Cu") (net 65))
  (segment (start 122.063399 74.774565) (end 122.041006 74.774565) (width 0.109) (layer "In2.Cu") (net 65))
  (segment (start 121.803665 74.68676) (end 121.813381 74.666585) (width 0.109) (layer "In2.Cu") (net 65))
  (segment (start 119.831719 74.19354) (end 119.81446 74.176281) (width 0.109) (layer "In2.Cu") (net 65))
  (segment (start 119.87928 74.349611) (end 119.866294 74.328944) (width 0.109) (layer "In2.Cu") (net 65))
  (segment (start 120.0735 74.2615) (end 120.0735 74.28165) (width 0.109) (layer "In2.Cu") (net 65))
  (segment (start 121.813381 74.772991) (end 121.803665 74.752816) (width 0.109) (layer "In2.Cu") (net 65))
  (segment (start 120.011793 74.379856) (end 119.988754 74.387918) (width 0.109) (layer "In2.Cu") (net 65))
  (segment (start 119.793793 74.163295) (end 119.770754 74.155233) (width 0.109) (layer "In2.Cu") (net 65))
  (segment (start 119.852767 74.237246) (end 119.844705 74.214207) (width 0.109) (layer "In2.Cu") (net 65))
  (segment (start 120.03246 74.36687) (end 120.011793 74.379856) (width 0.109) (layer "In2.Cu") (net 65))
  (segment (start 122.122913 74.803226) (end 122.105405 74.789264) (width 0.109) (layer "In2.Cu") (net 65))
  (segment (start 120.084294 74.214207) (end 120.076232 74.237246) (width 0.109) (layer "In2.Cu") (net 65))
  (segment (start 110.647186 78.5775) (end 110.3483 78.278614) (width 0.109) (layer "In2.Cu") (net 65))
  (segment (start 121.899585 74.831887) (end 121.877753 74.826904) (width 0.109) (layer "In2.Cu") (net 65))
  (segment (start 121.998999 74.789264) (end 121.963984 74.817188) (width 0.109) (layer "In2.Cu") (net 65))
  (segment (start 119.866294 74.328944) (end 119.858232 74.305905) (width 0.109) (layer "In2.Cu") (net 65))
  (segment (start 121.85102 74.611395) (end 121.856003 74.589564) (width 0.109) (layer "In2.Cu") (net 65))
  (segment (start 121.943809 74.826904) (end 121.921978 74.831887) (width 0.109) (layer "In2.Cu") (net 65))
  (segment (start 121.856003 74.589564) (end 121.856003 74.567171) (width 0.109) (layer "In2.Cu") (net 65))
  (segment (start 122.594034 75.274348) (end 122.122913 74.803226) (width 0.109) (layer "In2.Cu") (net 65))
  (segment (start 119.81446 74.176281) (end 119.793793 74.163295) (width 0.109) (layer "In2.Cu") (net 65))
  (segment (start 121.84007 74.803226) (end 121.827343 74.790499) (width 0.109) (layer "In2.Cu") (net 65))
  (segment (start 121.813381 74.666585) (end 121.841304 74.63157) (width 0.109) (layer "In2.Cu") (net 65))
  (segment (start 122.019174 74.779548) (end 121.998999 74.789264) (width 0.109) (layer "In2.Cu") (net 65))
  (segment (start 121.856003 74.567171) (end 121.85102 74.545339) (width 0.109) (layer "In2.Cu") (net 65))
  (segment (start 121.827343 74.790499) (end 121.813381 74.772991) (width 0.109) (layer "In2.Cu") (net 65))
  (segment (start 120.062705 74.328944) (end 120.049719 74.349611) (width 0.109) (layer "In2.Cu") (net 65))
  (segment (start 121.798682 74.730985) (end 121.798682 74.708592) (width 0.109) (layer "In2.Cu") (net 65))
  (segment (start 121.798682 74.708592) (end 121.803665 74.68676) (width 0.109) (layer "In2.Cu") (net 65))
  (segment (start 122.08523 74.779548) (end 122.063399 74.774565) (width 0.109) (layer "In2.Cu") (net 65))
  (segment (start 120.135206 74.163295) (end 120.114539 74.176281) (width 0.109) (layer "In2.Cu") (net 65))
  (segment (start 120.070767 74.305905) (end 120.062705 74.328944) (width 0.109) (layer "In2.Cu") (net 65))
  (segment (start 121.857578 74.817188) (end 121.84007 74.803226) (width 0.109) (layer "In2.Cu") (net 65))
  (segment (start 120.049719 74.349611) (end 120.03246 74.36687) (width 0.109) (layer "In2.Cu") (net 65))
  (segment (start 119.770754 74.155233) (end 119.7465 74.1525) (width 0.109) (layer "In2.Cu") (net 65))
  (segment (start 119.7465 74.1525) (end 119.345094 74.1525) (width 0.109) (layer "In2.Cu") (net 65))
  (segment (start 119.988754 74.387918) (end 119.9645 74.39065) (width 0.109) (layer "In2.Cu") (net 65))
  (segment (start 110.3483 78.278614) (end 110.3483 77.576697) (width 0.109) (layer "In2.Cu") (net 65))
  (segment (start 119.858232 74.305905) (end 119.8555 74.28165) (width 0.109) (layer "In2.Cu") (net 65))
  (segment (start 121.877753 74.826904) (end 121.857578 74.817188) (width 0.109) (layer "In2.Cu") (net 65))
  (segment (start 121.963984 74.817188) (end 121.943809 74.826904) (width 0.109) (layer "In2.Cu") (net 65))
  (segment (start 119.896539 74.36687) (end 119.87928 74.349611) (width 0.109) (layer "In2.Cu") (net 65))
  (segment (start 121.841304 74.525164) (end 121.827343 74.507657) (width 0.109) (layer "In2.Cu") (net 65))
  (segment (start 122.105405 74.789264) (end 122.08523 74.779548) (width 0.109) (layer "In2.Cu") (net 65))
  (segment (start 110.959801 76.052908) (end 110.286801 76.725908) (width 0.182) (layer "B.Cu") (net 65))
  (segment (start 110.959801 75.882196) (end 110.959801 76.052908) (width 0.182) (layer "B.Cu") (net 65))
  (segment (start 110.286801 77.297196) (end 110.1778 77.406197) (width 0.182) (layer "B.Cu") (net 65))
  (segment (start 110.286801 76.725908) (end 110.286801 77.297196) (width 0.182) (layer "B.Cu") (net 65))
  (segment (start 110.698801 75.621196) (end 110.959801 75.882196) (width 0.182) (layer "B.Cu") (net 65))
  (segment (start 122.906604 78.733722) (end 122.918943 78.746061) (width 0.182) (layer "F.Cu") (net 66))
  (segment (start 123.019534 76.82) (end 122.910534 76.929) (width 0.182) (layer "F.Cu") (net 66))
  (segment (start 122.910534 78.737652) (end 122.918943 78.746061) (width 0.182) (layer "F.Cu") (net 66))
  (segment (start 122.910534 76.929) (end 122.910534 78.737652) (width 0.182) (layer "F.Cu") (net 66))
  (via (at 123.019534 76.82) (size 0.45) (drill 0.1) (layers "F.Cu" "B.Cu") (net 66))
  (via (at 110.773801 77.406196) (size 0.45) (drill 0.1) (layers "F.Cu" "B.Cu") (net 66))
  (segment (start 110.752814 78.3225) (end 112.8125 78.3225) (width 0.109) (layer "In2.Cu") (net 66))
  (segment (start 113.481858 78.043101) (end 113.4875 78.093168) (width 0.109) (layer "In2.Cu") (net 66))
  (segment (start 113.493141 78.147568) (end 113.509782 78.195124) (width 0.109) (layer "In2.Cu") (net 66))
  (segment (start 113.086587 77.952883) (end 113.122214 77.917256) (width 0.109) (layer "In2.Cu") (net 66))
  (segment (start 122.849034 75.16872) (end 122.849034 76.6495) (width 0.109) (layer "In2.Cu") (net 66))
  (segment (start 110.6033 77.576697) (end 110.6033 78.172986) (width 0.109) (layer "In2.Cu") (net 66))
  (segment (start 112.952785 78.273413) (end 112.988412 78.237786) (width 0.109) (layer "In2.Cu") (net 66))
  (segment (start 113.572214 78.273413) (end 113.614876 78.300218) (width 0.109) (layer "In2.Cu") (net 66))
  (segment (start 113.0375 78.093168) (end 113.043141 78.043101) (width 0.109) (layer "In2.Cu") (net 66))
  (segment (start 113.4875 78.0975) (end 113.493141 78.147568) (width 0.109) (layer "In2.Cu") (net 66))
  (segment (start 112.862567 78.316859) (end 112.910123 78.300218) (width 0.109) (layer "In2.Cu") (net 66))
  (segment (start 112.8125 78.3225) (end 112.862567 78.316859) (width 0.109) (layer "In2.Cu") (net 66))
  (segment (start 110.6033 78.172986) (end 110.752814 78.3225) (width 0.109) (layer "In2.Cu") (net 66))
  (segment (start 113.360123 77.890451) (end 113.402785 77.917256) (width 0.109) (layer "In2.Cu") (net 66))
  (segment (start 113.2625 77.868168) (end 113.312567 77.87381) (width 0.109) (layer "In2.Cu") (net 66))
  (segment (start 112.988412 78.237786) (end 113.015217 78.195124) (width 0.109) (layer "In2.Cu") (net 66))
  (segment (start 119.239466 73.8975) (end 121.577814 73.8975) (width 0.109) (layer "In2.Cu") (net 66))
  (segment (start 113.7125 78.3225) (end 114.814466 78.3225) (width 0.109) (layer "In2.Cu") (net 66))
  (segment (start 113.312567 77.87381) (end 113.360123 77.890451) (width 0.109) (layer "In2.Cu") (net 66))
  (segment (start 112.910123 78.300218) (end 112.952785 78.273413) (width 0.109) (layer "In2.Cu") (net 66))
  (segment (start 113.212432 77.87381) (end 113.2625 77.868168) (width 0.109) (layer "In2.Cu") (net 66))
  (segment (start 113.465217 77.995545) (end 113.481858 78.043101) (width 0.109) (layer "In2.Cu") (net 66))
  (segment (start 113.662432 78.316859) (end 113.7125 78.3225) (width 0.109) (layer "In2.Cu") (net 66))
  (segment (start 113.0375 78.0975) (end 113.0375 78.093168) (width 0.109) (layer "In2.Cu") (net 66))
  (segment (start 121.577814 73.8975) (end 122.849034 75.16872) (width 0.109) (layer "In2.Cu") (net 66))
  (segment (start 113.043141 78.043101) (end 113.059782 77.995545) (width 0.109) (layer "In2.Cu") (net 66))
  (segment (start 122.849034 76.6495) (end 123.019534 76.82) (width 0.109) (layer "In2.Cu") (net 66))
  (segment (start 113.402785 77.917256) (end 113.438412 77.952883) (width 0.109) (layer "In2.Cu") (net 66))
  (segment (start 113.164876 77.890451) (end 113.212432 77.87381) (width 0.109) (layer "In2.Cu") (net 66))
  (segment (start 113.509782 78.195124) (end 113.536587 78.237786) (width 0.109) (layer "In2.Cu") (net 66))
  (segment (start 110.773801 77.406196) (end 110.6033 77.576697) (width 0.109) (layer "In2.Cu") (net 66))
  (segment (start 113.031858 78.147568) (end 113.0375 78.0975) (width 0.109) (layer "In2.Cu") (net 66))
  (segment (start 113.059782 77.995545) (end 113.086587 77.952883) (width 0.109) (layer "In2.Cu") (net 66))
  (segment (start 113.122214 77.917256) (end 113.164876 77.890451) (width 0.109) (layer "In2.Cu") (net 66))
  (segment (start 113.015217 78.195124) (end 113.031858 78.147568) (width 0.109) (layer "In2.Cu") (net 66))
  (segment (start 114.814466 78.3225) (end 119.239466 73.8975) (width 0.109) (layer "In2.Cu") (net 66))
  (segment (start 113.614876 78.300218) (end 113.662432 78.316859) (width 0.109) (layer "In2.Cu") (net 66))
  (segment (start 113.4875 78.093168) (end 113.4875 78.0975) (width 0.109) (layer "In2.Cu") (net 66))
  (segment (start 113.536587 78.237786) (end 113.572214 78.273413) (width 0.109) (layer "In2.Cu") (net 66))
  (segment (start 113.438412 77.952883) (end 113.465217 77.995545) (width 0.109) (layer "In2.Cu") (net 66))
  (segment (start 111.596997 75.623) (end 111.337801 75.882196) (width 0.182) (layer "B.Cu") (net 66))
  (segment (start 110.664801 77.297196) (end 110.664801 76.882484) (width 0.182) (layer "B.Cu") (net 66))
  (segment (start 110.664801 76.882484) (end 111.337801 76.209484) (width 0.182) (layer "B.Cu") (net 66))
  (segment (start 111.337801 76.209484) (end 111.337801 75.882196) (width 0.182) (layer "B.Cu") (net 66))
  (segment (start 110.773801 77.406196) (end 110.664801 77.297196) (width 0.182) (layer "B.Cu") (net 66))
  (segment (start 127.149342 87.334861) (end 127.138342 87.345861) (width 0.182) (layer "F.Cu") (net 67))
  (segment (start 127.907742 87.334861) (end 127.149342 87.334861) (width 0.182) (layer "F.Cu") (net 67))
  (segment (start 126.916018 87.34586) (end 126.807018 87.23686) (width 0.182) (layer "F.Cu") (net 67))
  (segment (start 127.138342 87.345861) (end 126.916018 87.34586) (width 0.182) (layer "F.Cu") (net 67))
  (via (at 135.400449 76.500504) (size 0.45) (drill 0.1) (layers "F.Cu" "B.Cu") (net 67))
  (via (at 126.807018 87.23686) (size 0.45) (drill 0.1) (layers "F.Cu" "B.Cu") (net 67))
  (segment (start 135.229949 76.671004) (end 135.229949 79.725365) (width 0.109) (layer "In2.Cu") (net 67))
  (segment (start 132.107506 88.4525) (end 128.627814 88.4525) (width 0.109) (layer "In2.Cu") (net 67))
  (segment (start 125.0475 88.452814) (end 125.0475 87.972186) (width 0.109) (layer "In2.Cu") (net 67))
  (segment (start 135.400449 76.500504) (end 135.229949 76.671004) (width 0.109) (layer "In2.Cu") (net 67))
  (segment (start 125.947186 89.3525) (end 125.0475 88.452814) (width 0.109) (layer "In2.Cu") (net 67))
  (segment (start 135.229949 79.725365) (end 134.6025 80.352814) (width 0.109) (layer "In2.Cu") (net 67))
  (segment (start 128.627814 88.4525) (end 127.727814 89.3525) (width 0.109) (layer "In2.Cu") (net 67))
  (segment (start 127.727814 89.3525) (end 125.947186 89.3525) (width 0.109) (layer "In2.Cu") (net 67))
  (segment (start 126.636518 87.40736) (end 126.807018 87.23686) (width 0.109) (layer "In2.Cu") (net 67))
  (segment (start 134.6025 85.957506) (end 132.107506 88.4525) (width 0.109) (layer "In2.Cu") (net 67))
  (segment (start 125.612326 87.40736) (end 126.636518 87.40736) (width 0.109) (layer "In2.Cu") (net 67))
  (segment (start 134.6025 80.352814) (end 134.6025 85.957506) (width 0.109) (layer "In2.Cu") (net 67))
  (segment (start 125.0475 87.972186) (end 125.612326 87.40736) (width 0.109) (layer "In2.Cu") (net 67))
  (segment (start 135.400449 76.500504) (end 135.291449 76.391504) (width 0.182) (layer "B.Cu") (net 67))
  (segment (start 135.603449 75.196551) (end 135.603449 74.921573) (width 0.182) (layer "B.Cu") (net 67))
  (segment (start 135.291449 76.175254) (end 135.51845 75.948253) (width 0.182) (layer "B.Cu") (net 67))
  (segment (start 135.51845 75.28155) (end 135.603449 75.196551) (width 0.182) (layer "B.Cu") (net 67))
  (segment (start 135.51845 75.948253) (end 135.51845 75.28155) (width 0.182) (layer "B.Cu") (net 67))
  (segment (start 135.291449 76.391504) (end 135.291449 76.175254) (width 0.182) (layer "B.Cu") (net 67))
  (segment (start 127.907742 87.73486) (end 127.149342 87.73486) (width 0.182) (layer "F.Cu") (net 68))
  (segment (start 126.916018 87.72386) (end 126.807018 87.83286) (width 0.182) (layer "F.Cu") (net 68))
  (segment (start 127.149342 87.73486) (end 127.138342 87.72386) (width 0.182) (layer "F.Cu") (net 68))
  (segment (start 127.138342 87.72386) (end 126.916018 87.72386) (width 0.182) (layer "F.Cu") (net 68))
  (via (at 134.804449 76.500504) (size 0.45) (drill 0.1) (layers "F.Cu" "B.Cu") (net 68))
  (via (at 126.807018 87.83286) (size 0.45) (drill 0.1) (layers "F.Cu" "B.Cu") (net 68))
  (segment (start 125.3025 88.077814) (end 125.3025 88.347186) (width 0.109) (layer "In2.Cu") (net 68))
  (segment (start 132.800241 86.964383) (end 132.808838 86.926718) (width 0.109) (layer "In2.Cu") (net 68))
  (segment (start 126.535539 89.041024) (end 126.55929 89.064775) (width 0.109) (layer "In2.Cu") (net 68))
  (segment (start 132.849688 86.861705) (end 132.853184 86.85821) (width 0.109) (layer "In2.Cu") (net 68))
  (segment (start 126.807018 87.83286) (end 126.636518 87.66236) (width 0.109) (layer "In2.Cu") (net 68))
  (segment (start 132.918197 86.81736) (end 132.955862 86.808763) (width 0.109) (layer "In2.Cu") (net 68))
  (segment (start 133.162192 86.899062) (end 133.199857 86.90766) (width 0.109) (layer "In2.Cu") (net 68))
  (segment (start 133.06697 86.834123) (end 133.127383 86.8823) (width 0.109) (layer "In2.Cu") (net 68))
  (segment (start 125.32876 88.368127) (end 125.359024 88.382702) (width 0.109) (layer "In2.Cu") (net 68))
  (segment (start 126.417896 88.762355) (end 126.446337 88.780226) (width 0.109) (layer "In2.Cu") (net 68))
  (segment (start 126.502814 88.8975) (end 126.502814 88.9475) (width 0.109) (layer "In2.Cu") (net 68))
  (segment (start 125.691247 88.615841) (end 125.683772 88.648588) (width 0.109) (layer "In2.Cu") (net 68))
  (segment (start 125.783061 88.338091) (end 125.797634 88.368353) (width 0.109) (layer "In2.Cu") (net 68))
  (segment (start 126.117896 89.082646) (end 126.146337 89.064775) (width 0.109) (layer "In2.Cu") (net 68))
  (segment (start 132.955862 86.808763) (end 132.994498 86.808762) (width 0.109) (layer "In2.Cu") (net 68))
  (segment (start 132.001878 88.1975) (end 132.849689 87.349689) (width 0.109) (layer "In2.Cu") (net 68))
  (segment (start 125.797634 88.368353) (end 125.805109 88.401101) (width 0.109) (layer "In2.Cu") (net 68))
  (segment (start 134.974949 79.619737) (end 134.974949 76.671004) (width 0.109) (layer "In2.Cu") (net 68))
  (segment (start 132.849689 87.349689) (end 132.873778 87.319484) (width 0.109) (layer "In2.Cu") (net 68))
  (segment (start 126.502814 88.9475) (end 126.506574 88.980879) (width 0.109) (layer "In2.Cu") (net 68))
  (segment (start 125.549986 88.311829) (end 125.576248 88.290888) (width 0.109) (layer "In2.Cu") (net 68))
  (segment (start 126.052814 89.0975) (end 126.086192 89.09374) (width 0.109) (layer "In2.Cu") (net 68))
  (segment (start 132.808838 86.926718) (end 132.825601 86.891909) (width 0.109) (layer "In2.Cu") (net 68))
  (segment (start 126.652814 89.0975) (end 127.622186 89.0975) (width 0.109) (layer "In2.Cu") (net 68))
  (segment (start 126.587731 89.082646) (end 126.619435 89.09374) (width 0.109) (layer "In2.Cu") (net 68))
  (segment (start 126.506574 88.980879) (end 126.517668 89.012583) (width 0.109) (layer "In2.Cu") (net 68))
  (segment (start 126.170088 89.041024) (end 126.187959 89.012583) (width 0.109) (layer "In2.Cu") (net 68))
  (segment (start 126.086192 89.09374) (end 126.117896 89.082646) (width 0.109) (layer "In2.Cu") (net 68))
  (segment (start 125.60651 88.276313) (end 125.639257 88.268838) (width 0.109) (layer "In2.Cu") (net 68))
  (segment (start 126.499053 88.864122) (end 126.502814 88.8975) (width 0.109) (layer "In2.Cu") (net 68))
  (segment (start 126.470088 88.803977) (end 126.487959 88.832418) (width 0.109) (layer "In2.Cu") (net 68))
  (segment (start 134.974949 76.671004) (end 134.804449 76.500504) (width 0.109) (layer "In2.Cu") (net 68))
  (segment (start 125.576248 88.290888) (end 125.60651 88.276313) (width 0.109) (layer "In2.Cu") (net 68))
  (segment (start 126.319435 88.751261) (end 126.352814 88.7475) (width 0.109) (layer "In2.Cu") (net 68))
  (segment (start 126.199053 88.980879) (end 126.202814 88.9475) (width 0.109) (layer "In2.Cu") (net 68))
  (segment (start 127.622186 89.0975) (end 128.522186 88.1975) (width 0.109) (layer "In2.Cu") (net 68))
  (segment (start 125.726763 88.559317) (end 125.70582 88.585577) (width 0.109) (layer "In2.Cu") (net 68))
  (segment (start 126.352814 88.7475) (end 126.386192 88.751261) (width 0.109) (layer "In2.Cu") (net 68))
  (segment (start 125.683772 88.682178) (end 125.691247 88.714925) (width 0.109) (layer "In2.Cu") (net 68))
  (segment (start 132.808837 87.040684) (end 132.800241 87.003017) (width 0.109) (layer "In2.Cu") (net 68))
  (segment (start 133.127383 86.8823) (end 133.162192 86.899062) (width 0.109) (layer "In2.Cu") (net 68))
  (segment (start 125.639257 88.268838) (end 125.672847 88.268838) (width 0.109) (layer "In2.Cu") (net 68))
  (segment (start 132.89054 87.284676) (end 132.899136 87.247011) (width 0.109) (layer "In2.Cu") (net 68))
  (segment (start 125.735858 88.290888) (end 125.762118 88.311829) (width 0.109) (layer "In2.Cu") (net 68))
  (segment (start 126.287731 88.762355) (end 126.319435 88.751261) (width 0.109) (layer "In2.Cu") (net 68))
  (segment (start 126.386192 88.751261) (end 126.417896 88.762355) (width 0.109) (layer "In2.Cu") (net 68))
  (segment (start 133.276156 86.899063) (end 133.310965 86.8823) (width 0.109) (layer "In2.Cu") (net 68))
  (segment (start 132.994498 86.808762) (end 133.032163 86.817359) (width 0.109) (layer "In2.Cu") (net 68))
  (segment (start 126.636518 87.66236) (end 125.717954 87.66236) (width 0.109) (layer "In2.Cu") (net 68))
  (segment (start 132.883388 86.834123) (end 132.918197 86.81736) (width 0.109) (layer "In2.Cu") (net 68))
  (segment (start 134.3475 85.851878) (end 134.3475 80.247186) (width 0.109) (layer "In2.Cu") (net 68))
  (segment (start 126.187959 89.012583) (end 126.199053 88.980879) (width 0.109) (layer "In2.Cu") (net 68))
  (segment (start 126.487959 88.832418) (end 126.499053 88.864122) (width 0.109) (layer "In2.Cu") (net 68))
  (segment (start 125.717954 87.66236) (end 125.3025 88.077814) (width 0.109) (layer "In2.Cu") (net 68))
  (segment (start 126.25929 88.780226) (end 126.287731 88.762355) (width 0.109) (layer "In2.Cu") (net 68))
  (segment (start 126.206574 88.864122) (end 126.217668 88.832418) (width 0.109) (layer "In2.Cu") (net 68))
  (segment (start 126.202814 88.8975) (end 126.206574 88.864122) (width 0.109) (layer "In2.Cu") (net 68))
  (segment (start 125.683772 88.648588) (end 125.683772 88.682178) (width 0.109) (layer "In2.Cu") (net 68))
  (segment (start 126.55929 89.064775) (end 126.587731 89.082646) (width 0.109) (layer "In2.Cu") (net 68))
  (segment (start 126.235539 88.803977) (end 126.25929 88.780226) (width 0.109) (layer "In2.Cu") (net 68))
  (segment (start 125.48837 88.368128) (end 125.514632 88.347186) (width 0.109) (layer "In2.Cu") (net 68))
  (segment (start 125.70582 88.585577) (end 125.691247 88.615841) (width 0.109) (layer "In2.Cu") (net 68))
  (segment (start 128.522186 88.1975) (end 132.001878 88.1975) (width 0.109) (layer "In2.Cu") (net 68))
  (segment (start 126.517668 89.012583) (end 126.535539 89.041024) (width 0.109) (layer "In2.Cu") (net 68))
  (segment (start 125.762118 88.311829) (end 125.783061 88.338091) (width 0.109) (layer "In2.Cu") (net 68))
  (segment (start 125.805108 88.434689) (end 125.797635 88.467437) (width 0.109) (layer "In2.Cu") (net 68))
  (segment (start 125.3025 88.347186) (end 125.32876 88.368127) (width 0.109) (layer "In2.Cu") (net 68))
  (segment (start 132.873778 87.135902) (end 132.825601 87.075491) (width 0.109) (layer "In2.Cu") (net 68))
  (segment (start 126.446337 88.780226) (end 126.470088 88.803977) (width 0.109) (layer "In2.Cu") (net 68))
  (segment (start 132.825601 86.891909) (end 132.849688 86.861705) (width 0.109) (layer "In2.Cu") (net 68))
  (segment (start 125.458106 88.382701) (end 125.48837 88.368128) (width 0.109) (layer "In2.Cu") (net 68))
  (segment (start 125.78306 88.497699) (end 125.762118 88.523961) (width 0.109) (layer "In2.Cu") (net 68))
  (segment (start 125.672847 88.268838) (end 125.705594 88.276313) (width 0.109) (layer "In2.Cu") (net 68))
  (segment (start 133.341171 86.858211) (end 133.344663 86.854716) (width 0.109) (layer "In2.Cu") (net 68))
  (segment (start 132.853184 86.85821) (end 132.883388 86.834123) (width 0.109) (layer "In2.Cu") (net 68))
  (segment (start 125.762118 88.523961) (end 125.726763 88.559317) (width 0.109) (layer "In2.Cu") (net 68))
  (segment (start 125.726764 88.77145) (end 126.052814 89.0975) (width 0.109) (layer "In2.Cu") (net 68))
  (segment (start 126.619435 89.09374) (end 126.652814 89.0975) (width 0.109) (layer "In2.Cu") (net 68))
  (segment (start 126.146337 89.064775) (end 126.170088 89.041024) (width 0.109) (layer "In2.Cu") (net 68))
  (segment (start 133.238491 86.90766) (end 133.276156 86.899063) (width 0.109) (layer "In2.Cu") (net 68))
  (segment (start 125.705594 88.276313) (end 125.735858 88.290888) (width 0.109) (layer "In2.Cu") (net 68))
  (segment (start 132.825601 87.075491) (end 132.808837 87.040684) (width 0.109) (layer "In2.Cu") (net 68))
  (segment (start 133.344663 86.854716) (end 134.3475 85.851878) (width 0.109) (layer "In2.Cu") (net 68))
  (segment (start 132.899136 87.247011) (end 132.899136 87.208377) (width 0.109) (layer "In2.Cu") (net 68))
  (segment (start 126.217668 88.832418) (end 126.235539 88.803977) (width 0.109) (layer "In2.Cu") (net 68))
  (segment (start 125.805109 88.401101) (end 125.805108 88.434689) (width 0.109) (layer "In2.Cu") (net 68))
  (segment (start 125.39177 88.390175) (end 125.42536 88.390176) (width 0.109) (layer "In2.Cu") (net 68))
  (segment (start 132.873778 87.319484) (end 132.89054 87.284676) (width 0.109) (layer "In2.Cu") (net 68))
  (segment (start 132.800241 87.003017) (end 132.800241 86.964383) (width 0.109) (layer "In2.Cu") (net 68))
  (segment (start 125.359024 88.382702) (end 125.39177 88.390175) (width 0.109) (layer "In2.Cu") (net 68))
  (segment (start 133.310965 86.8823) (end 133.341171 86.858211) (width 0.109) (layer "In2.Cu") (net 68))
  (segment (start 125.514632 88.347186) (end 125.549986 88.311829) (width 0.109) (layer "In2.Cu") (net 68))
  (segment (start 125.797635 88.467437) (end 125.78306 88.497699) (width 0.109) (layer "In2.Cu") (net 68))
  (segment (start 134.3475 80.247186) (end 134.974949 79.619737) (width 0.109) (layer "In2.Cu") (net 68))
  (segment (start 132.899136 87.208377) (end 132.89054 87.17071) (width 0.109) (layer "In2.Cu") (net 68))
  (segment (start 133.199857 86.90766) (end 133.238491 86.90766) (width 0.109) (layer "In2.Cu") (net 68))
  (segment (start 125.691247 88.714925) (end 125.70582 88.745187) (width 0.109) (layer "In2.Cu") (net 68))
  (segment (start 133.032163 86.817359) (end 133.06697 86.834123) (width 0.109) (layer "In2.Cu") (net 68))
  (segment (start 125.70582 88.745187) (end 125.726764 88.77145) (width 0.109) (layer "In2.Cu") (net 68))
  (segment (start 125.42536 88.390176) (end 125.458106 88.382701) (width 0.109) (layer "In2.Cu") (net 68))
  (segment (start 126.202814 88.9475) (end 126.202814 88.8975) (width 0.109) (layer "In2.Cu") (net 68))
  (segment (start 132.89054 87.17071) (end 132.873778 87.135902) (width 0.109) (layer "In2.Cu") (net 68))
  (segment (start 134.913449 76.391504) (end 134.913449 76.175254) (width 0.182) (layer "B.Cu") (net 68))
  (segment (start 134.686448 75.276448) (end 134.603449 75.193449) (width 0.182) (layer "B.Cu") (net 68))
  (segment (start 134.686448 75.948253) (end 134.686448 75.276448) (width 0.182) (layer "B.Cu") (net 68))
  (segment (start 134.603449 75.193449) (end 134.603449 74.921573) (width 0.182) (layer "B.Cu") (net 68))
  (segment (start 134.804449 76.500504) (end 134.913449 76.391504) (width 0.182) (layer "B.Cu") (net 68))
  (segment (start 134.913449 76.175254) (end 134.686448 75.948253) (width 0.182) (layer "B.Cu") (net 68))
  (segment (start 132.748 76.439931) (end 132.748 76.223681) (width 0.182) (layer "F.Cu") (net 69))
  (segment (start 132.975001 75.329977) (end 133.06 75.244978) (width 0.182) (layer "F.Cu") (net 69))
  (segment (start 133.06 75.244978) (end 133.06 74.97) (width 0.182) (layer "F.Cu") (net 69))
  (segment (start 132.857 76.548931) (end 132.748 76.439931) (width 0.182) (layer "F.Cu") (net 69))
  (segment (start 132.748 76.223681) (end 132.975001 75.99668) (width 0.182) (layer "F.Cu") (net 69))
  (segment (start 132.975001 75.99668) (end 132.975001 75.329977) (width 0.182) (layer "F.Cu") (net 69))
  (segment (start 126.118942 79.504461) (end 126.129942 79.515461) (width 0.182) (layer "F.Cu") (net 69))
  (segment (start 126.129941 79.737785) (end 126.020941 79.846785) (width 0.182) (layer "F.Cu") (net 69))
  (segment (start 126.129942 79.515461) (end 126.129941 79.737785) (width 0.182) (layer "F.Cu") (net 69))
  (segment (start 126.118942 78.746061) (end 126.118942 79.504461) (width 0.182) (layer "F.Cu") (net 69))
  (via (at 132.857 76.548931) (size 0.45) (drill 0.1) (layers "F.Cu" "B.Cu") (net 69))
  (via (at 126.020941 79.846785) (size 0.45) (drill 0.1) (layers "F.Cu" "B.Cu") (net 69))
  (segment (start 126.020941 79.846785) (end 126.191441 80.017285) (width 0.109) (layer "In4.Cu") (net 69))
  (segment (start 132.857 76.548931) (end 132.6865 76.719431) (width 0.109) (layer "In4.Cu") (net 69))
  (segment (start 132.6865 76.719431) (end 132.6865 78.143814) (width 0.109) (layer "In4.Cu") (net 69))
  (segment (start 126.191441 80.017285) (end 126.191441 80.296755) (width 0.109) (layer "In4.Cu") (net 69))
  (segment (start 126.191441 80.296755) (end 126.572186 80.6775) (width 0.109) (layer "In4.Cu") (net 69))
  (segment (start 130.152814 80.6775) (end 126.572186 80.6775) (width 0.109) (layer "In4.Cu") (net 69))
  (segment (start 132.6865 78.143814) (end 130.152814 80.6775) (width 0.109) (layer "In4.Cu") (net 69))
  (segment (start 132.37 76.223681) (end 132.142999 75.99668) (width 0.182) (layer "F.Cu") (net 70))
  (segment (start 132.37 76.439931) (end 132.37 76.223681) (width 0.182) (layer "F.Cu") (net 70))
  (segment (start 132.261 76.548931) (end 132.37 76.439931) (width 0.182) (layer "F.Cu") (net 70))
  (segment (start 132.142999 75.324875) (end 132.06 75.241876) (width 0.182) (layer "F.Cu") (net 70))
  (segment (start 132.142999 75.99668) (end 132.142999 75.324875) (width 0.182) (layer "F.Cu") (net 70))
  (segment (start 132.06 75.241876) (end 132.06 74.97) (width 0.182) (layer "F.Cu") (net 70))
  (segment (start 126.507941 79.515461) (end 126.507941 79.737785) (width 0.182) (layer "F.Cu") (net 70))
  (segment (start 126.518941 79.504461) (end 126.507941 79.515461) (width 0.182) (layer "F.Cu") (net 70))
  (segment (start 126.507941 79.737785) (end 126.616941 79.846785) (width 0.182) (layer "F.Cu") (net 70))
  (segment (start 126.518941 78.746061) (end 126.518941 79.504461) (width 0.182) (layer "F.Cu") (net 70))
  (via (at 132.261 76.548931) (size 0.45) (drill 0.1) (layers "F.Cu" "B.Cu") (net 70))
  (via (at 126.616941 79.846785) (size 0.45) (drill 0.1) (layers "F.Cu" "B.Cu") (net 70))
  (segment (start 127.251634 80.387812) (end 127.221487 80.406755) (width 0.109) (layer "In4.Cu") (net 70))
  (segment (start 131.651652 78.383179) (end 131.651652 78.416768) (width 0.109) (layer "In4.Cu") (net 70))
  (segment (start 127.645245 80.332488) (end 127.633486 80.298881) (width 0.109) (layer "In4.Cu") (net 70))
  (segment (start 127.633486 80.298881) (end 127.6295 80.2635) (width 0.109) (layer "In4.Cu") (net 70))
  (segment (start 127.753119 80.418514) (end 127.719512 80.406755) (width 0.109) (layer "In4.Cu") (net 70))
  (segment (start 127.594811 80.132366) (end 127.569634 80.107189) (width 0.109) (layer "In4.Cu") (net 70))
  (segment (start 131.961472 78.343285) (end 131.93521 78.322343) (width 0.109) (layer "In4.Cu") (net 70))
  (segment (start 127.1525 80.4225) (end 126.677814 80.4225) (width 0.109) (layer "In4.Cu") (net 70))
  (segment (start 132.4315 78.038186) (end 132.147343 78.322343) (width 0.109) (layer "In4.Cu") (net 70))
  (segment (start 127.50588 80.076487) (end 127.4705 80.0725) (width 0.109) (layer "In4.Cu") (net 70))
  (segment (start 131.93521 78.322343) (end 131.906775 78.293908) (width 0.109) (layer "In4.Cu") (net 70))
  (segment (start 132.4315 76.719431) (end 132.4315 78.038186) (width 0.109) (layer "In4.Cu") (net 70))
  (segment (start 127.295754 80.332488) (end 127.276811 80.362635) (width 0.109) (layer "In4.Cu") (net 70))
  (segment (start 130.047186 80.4225) (end 127.7885 80.4225) (width 0.109) (layer "In4.Cu") (net 70))
  (segment (start 132.121081 78.343285) (end 132.090818 78.357859) (width 0.109) (layer "In4.Cu") (net 70))
  (segment (start 131.744019 78.560735) (end 131.758593 78.590998) (width 0.109) (layer "In4.Cu") (net 70))
  (segment (start 132.147343 78.322343) (end 132.121081 78.343285) (width 0.109) (layer "In4.Cu") (net 70))
  (segment (start 127.3115 80.2635) (end 127.307513 80.298881) (width 0.109) (layer "In4.Cu") (net 70))
  (segment (start 127.3115 80.2315) (end 127.3115 80.2635) (width 0.109) (layer "In4.Cu") (net 70))
  (segment (start 126.677814 80.4225) (end 126.446441 80.191127) (width 0.109) (layer "In4.Cu") (net 70))
  (segment (start 132.261 76.548931) (end 132.4315 76.719431) (width 0.109) (layer "In4.Cu") (net 70))
  (segment (start 131.751167 78.258392) (end 131.720904 78.272966) (width 0.109) (layer "In4.Cu") (net 70))
  (segment (start 131.694643 78.293908) (end 131.6737 78.320169) (width 0.109) (layer "In4.Cu") (net 70))
  (segment (start 127.221487 80.406755) (end 127.18788 80.418514) (width 0.109) (layer "In4.Cu") (net 70))
  (segment (start 127.7885 80.4225) (end 127.753119 80.418514) (width 0.109) (layer "In4.Cu") (net 70))
  (segment (start 131.6737 78.320169) (end 131.659126 78.350432) (width 0.109) (layer "In4.Cu") (net 70))
  (segment (start 132.058071 78.365333) (end 132.024482 78.365333) (width 0.109) (layer "In4.Cu") (net 70))
  (segment (start 131.766067 78.623745) (end 131.766067 78.657334) (width 0.109) (layer "In4.Cu") (net 70))
  (segment (start 131.651652 78.416768) (end 131.659126 78.449515) (width 0.109) (layer "In4.Cu") (net 70))
  (segment (start 127.315486 80.19612) (end 127.3115 80.2315) (width 0.109) (layer "In4.Cu") (net 70))
  (segment (start 126.446441 80.017285) (end 126.616941 79.846785) (width 0.109) (layer "In4.Cu") (net 70))
  (segment (start 132.024482 78.365333) (end 131.991735 78.357859) (width 0.109) (layer "In4.Cu") (net 70))
  (segment (start 131.694643 78.50604) (end 131.723077 78.534474) (width 0.109) (layer "In4.Cu") (net 70))
  (segment (start 131.720904 78.272966) (end 131.694643 78.293908) (width 0.109) (layer "In4.Cu") (net 70))
  (segment (start 127.4705 80.0725) (end 127.435119 80.076487) (width 0.109) (layer "In4.Cu") (net 70))
  (segment (start 127.6295 80.2315) (end 127.625513 80.19612) (width 0.109) (layer "In4.Cu") (net 70))
  (segment (start 127.719512 80.406755) (end 127.689365 80.387812) (width 0.109) (layer "In4.Cu") (net 70))
  (segment (start 131.758593 78.690082) (end 131.744019 78.720345) (width 0.109) (layer "In4.Cu") (net 70))
  (segment (start 131.723078 78.746607) (end 130.047186 80.4225) (width 0.109) (layer "In4.Cu") (net 70))
  (segment (start 127.569634 80.107189) (end 127.539487 80.088246) (width 0.109) (layer "In4.Cu") (net 70))
  (segment (start 127.401512 80.088246) (end 127.371365 80.107189) (width 0.109) (layer "In4.Cu") (net 70))
  (segment (start 131.659126 78.449515) (end 131.6737 78.479778) (width 0.109) (layer "In4.Cu") (net 70))
  (segment (start 126.446441 80.191127) (end 126.446441 80.017285) (width 0.109) (layer "In4.Cu") (net 70))
  (segment (start 127.625513 80.19612) (end 127.613754 80.162513) (width 0.109) (layer "In4.Cu") (net 70))
  (segment (start 131.880514 78.272966) (end 131.850251 78.258392) (width 0.109) (layer "In4.Cu") (net 70))
  (segment (start 127.346188 80.132366) (end 127.327245 80.162513) (width 0.109) (layer "In4.Cu") (net 70))
  (segment (start 127.18788 80.418514) (end 127.1525 80.4225) (width 0.109) (layer "In4.Cu") (net 70))
  (segment (start 131.659126 78.350432) (end 131.651652 78.383179) (width 0.109) (layer "In4.Cu") (net 70))
  (segment (start 127.435119 80.076487) (end 127.401512 80.088246) (width 0.109) (layer "In4.Cu") (net 70))
  (segment (start 127.664188 80.362635) (end 127.645245 80.332488) (width 0.109) (layer "In4.Cu") (net 70))
  (segment (start 131.744019 78.720345) (end 131.723078 78.746607) (width 0.109) (layer "In4.Cu") (net 70))
  (segment (start 127.539487 80.088246) (end 127.50588 80.076487) (width 0.109) (layer "In4.Cu") (net 70))
  (segment (start 131.850251 78.258392) (end 131.817504 78.250918) (width 0.109) (layer "In4.Cu") (net 70))
  (segment (start 131.783915 78.250918) (end 131.751167 78.258392) (width 0.109) (layer "In4.Cu") (net 70))
  (segment (start 131.758593 78.590998) (end 131.766067 78.623745) (width 0.109) (layer "In4.Cu") (net 70))
  (segment (start 127.689365 80.387812) (end 127.664188 80.362635) (width 0.109) (layer "In4.Cu") (net 70))
  (segment (start 131.723077 78.534474) (end 131.744019 78.560735) (width 0.109) (layer "In4.Cu") (net 70))
  (segment (start 127.371365 80.107189) (end 127.346188 80.132366) (width 0.109) (layer "In4.Cu") (net 70))
  (segment (start 127.276811 80.362635) (end 127.251634 80.387812) (width 0.109) (layer "In4.Cu") (net 70))
  (segment (start 127.6295 80.2635) (end 127.6295 80.2315) (width 0.109) (layer "In4.Cu") (net 70))
  (segment (start 127.307513 80.298881) (end 127.295754 80.332488) (width 0.109) (layer "In4.Cu") (net 70))
  (segment (start 131.817504 78.250918) (end 131.783915 78.250918) (width 0.109) (layer "In4.Cu") (net 70))
  (segment (start 131.906775 78.293908) (end 131.880514 78.272966) (width 0.109) (layer "In4.Cu") (net 70))
  (segment (start 131.991735 78.357859) (end 131.961472 78.343285) (width 0.109) (layer "In4.Cu") (net 70))
  (segment (start 132.090818 78.357859) (end 132.058071 78.365333) (width 0.109) (layer "In4.Cu") (net 70))
  (segment (start 127.613754 80.162513) (end 127.594811 80.132366) (width 0.109) (layer "In4.Cu") (net 70))
  (segment (start 131.766067 78.657334) (end 131.758593 78.690082) (width 0.109) (layer "In4.Cu") (net 70))
  (segment (start 127.327245 80.162513) (end 127.315486 80.19612) (width 0.109) (layer "In4.Cu") (net 70))
  (segment (start 131.6737 78.479778) (end 131.694643 78.50604) (width 0.109) (layer "In4.Cu") (net 70))
  (segment (start 123.329941 79.740663) (end 123.220941 79.849663) (width 0.182) (layer "F.Cu") (net 71))
  (segment (start 123.318942 79.504461) (end 123.329942 79.515461) (width 0.182) (layer "F.Cu") (net 71))
  (segment (start 123.318942 78.746061) (end 123.318942 79.504461) (width 0.182) (layer "F.Cu") (net 71))
  (segment (start 123.329942 79.515461) (end 123.329941 79.740663) (width 0.182) (layer "F.Cu") (net 71))
  (via (at 123.220941 79.849663) (size 0.45) (drill 0.1) (layers "F.Cu" "B.Cu") (net 71))
  (via (at 116.021449 76.546503) (size 0.45) (drill 0.1) (layers "F.Cu" "B.Cu") (net 71))
  (segment (start 122.495678 80.930041) (end 122.5175 80.9325) (width 0.109) (layer "In4.Cu") (net 71))
  (segment (start 122.125189 80.930041) (end 122.145917 80.922788) (width 0.109) (layer "In4.Cu") (net 71))
  (segment (start 122.238356 80.757762) (end 122.25695 80.746079) (width 0.109) (layer "In4.Cu") (net 71))
  (segment (start 116.295735 78.836556) (end 116.310955 78.855641) (width 0.109) (layer "In4.Cu") (net 71))
  (segment (start 116.314499 78.509497) (end 116.333581 78.524714) (width 0.109) (layer "In4.Cu") (net 71))
  (segment (start 116.021449 76.546503) (end 115.850949 76.717003) (width 0.109) (layer "In4.Cu") (net 71))
  (segment (start 123.391441 80.703245) (end 123.391441 80.020163) (width 0.109) (layer "In4.Cu") (net 71))
  (segment (start 116.179433 78.524715) (end 116.198515 78.509496) (width 0.109) (layer "In4.Cu") (net 71))
  (segment (start 116.279713 78.76636) (end 116.279714 78.79077) (width 0.109) (layer "In4.Cu") (net 71))
  (segment (start 118.612294 80.744838) (end 118.62528 80.724171) (width 0.109) (layer "In4.Cu") (net 71))
  (segment (start 116.156805 78.547342) (end 116.179433 78.524715) (width 0.109) (layer "In4.Cu") (net 71))
  (segment (start 118.904245 80.929768) (end 118.9285 80.9325) (width 0.109) (layer "In4.Cu") (net 71))
  (segment (start 116.333582 78.678864) (end 116.310953 78.70149) (width 0.109) (layer "In4.Cu") (net 71))
  (segment (start 118.539793 80.921706) (end 118.56046 80.90872) (width 0.109) (layer "In4.Cu") (net 71))
  (segment (start 122.47495 80.922788) (end 122.495678 80.930041) (width 0.109) (layer "In4.Cu") (net 71))
  (segment (start 118.686245 80.685864) (end 118.7105 80.683131) (width 0.109) (layer "In4.Cu") (net 71))
  (segment (start 122.211145 80.791884) (end 122.222828 80.77329) (width 0.109) (layer "In4.Cu") (net 71))
  (segment (start 118.590705 80.870794) (end 118.598767 80.847755) (width 0.109) (layer "In4.Cu") (net 71))
  (segment (start 116.359389 78.565788) (end 116.364821 78.589585) (width 0.109) (layer "In4.Cu") (net 71))
  (segment (start 118.84328 80.891461) (end 118.860539 80.90872) (width 0.109) (layer "In4.Cu") (net 71))
  (segment (start 118.757793 80.693926) (end 118.77846 80.706912) (width 0.109) (layer "In4.Cu") (net 71))
  (segment (start 122.222828 80.77329) (end 122.238356 80.757762) (width 0.109) (layer "In4.Cu") (net 71))
  (segment (start 116.091934 78.578581) (end 116.115731 78.57315) (width 0.109) (layer "In4.Cu") (net 71))
  (segment (start 116.198515 78.509496) (end 116.220506 78.498905) (width 0.109) (layer "In4.Cu") (net 71))
  (segment (start 122.321368 80.736368) (end 122.343189 80.738826) (width 0.109) (layer "In4.Cu") (net 71))
  (segment (start 118.62528 80.724171) (end 118.642539 80.706912) (width 0.109) (layer "In4.Cu") (net 71))
  (segment (start 118.816767 80.767877) (end 118.8195 80.792131) (width 0.109) (layer "In4.Cu") (net 71))
  (segment (start 116.292508 78.498906) (end 116.314499 78.509497) (width 0.109) (layer "In4.Cu") (net 71))
  (segment (start 123.162186 80.9325) (end 123.391441 80.703245) (width 0.109) (layer "In4.Cu") (net 71))
  (segment (start 122.145917 80.922788) (end 122.164511 80.911105) (width 0.109) (layer "In4.Cu") (net 71))
  (segment (start 116.35939 78.63779) (end 116.348799 78.65978) (width 0.109) (layer "In4.Cu") (net 71))
  (segment (start 122.2995 80.736368) (end 122.321368 80.736368) (width 0.109) (layer "In4.Cu") (net 71))
  (segment (start 118.822232 80.847755) (end 118.830294 80.870794) (width 0.109) (layer "In4.Cu") (net 71))
  (segment (start 118.830294 80.870794) (end 118.84328 80.891461) (width 0.109) (layer "In4.Cu") (net 71))
  (segment (start 118.663206 80.693926) (end 118.686245 80.685864) (width 0.109) (layer "In4.Cu") (net 71))
  (segment (start 118.808705 80.744838) (end 118.816767 80.767877) (width 0.109) (layer "In4.Cu") (net 71))
  (segment (start 118.6015 80.8235) (end 118.6015 80.792131) (width 0.109) (layer "In4.Cu") (net 71))
  (segment (start 116.279714 78.79077) (end 116.285144 78.814565) (width 0.109) (layer "In4.Cu") (net 71))
  (segment (start 118.860539 80.90872) (end 118.881206 80.921706) (width 0.109) (layer "In4.Cu") (net 71))
  (segment (start 118.598767 80.847755) (end 118.6015 80.8235) (width 0.109) (layer "In4.Cu") (net 71))
  (segment (start 122.429145 80.876983) (end 122.440828 80.895577) (width 0.109) (layer "In4.Cu") (net 71))
  (segment (start 116.295736 78.720574) (end 116.285145 78.742565) (width 0.109) (layer "In4.Cu") (net 71))
  (segment (start 116.244303 78.493475) (end 116.268711 78.493474) (width 0.109) (layer "In4.Cu") (net 71))
  (segment (start 116.3488 78.543798) (end 116.359389 78.565788) (width 0.109) (layer "In4.Cu") (net 71))
  (segment (start 118.56046 80.90872) (end 118.577719 80.891461) (width 0.109) (layer "In4.Cu") (net 71))
  (segment (start 122.103368 80.9325) (end 122.125189 80.930041) (width 0.109) (layer "In4.Cu") (net 71))
  (segment (start 122.416975 80.812612) (end 122.421892 80.856255) (width 0.109) (layer "In4.Cu") (net 71))
  (segment (start 118.516754 80.929768) (end 118.539793 80.921706) (width 0.109) (layer "In4.Cu") (net 71))
  (segment (start 118.795719 80.724171) (end 118.808705 80.744838) (width 0.109) (layer "In4.Cu") (net 71))
  (segment (start 118.4925 80.9325) (end 118.516754 80.929768) (width 0.109) (layer "In4.Cu") (net 71))
  (segment (start 116.137723 78.562561) (end 116.156805 78.547342) (width 0.109) (layer "In4.Cu") (net 71))
  (segment (start 123.391441 80.020163) (end 123.220941 79.849663) (width 0.109) (layer "In4.Cu") (net 71))
  (segment (start 122.203892 80.812612) (end 122.211145 80.791884) (width 0.109) (layer "In4.Cu") (net 71))
  (segment (start 116.220506 78.498905) (end 116.244303 78.493475) (width 0.109) (layer "In4.Cu") (net 71))
  (segment (start 116.067526 78.578581) (end 116.091934 78.578581) (width 0.109) (layer "In4.Cu") (net 71))
  (segment (start 116.115731 78.57315) (end 116.137723 78.562561) (width 0.109) (layer "In4.Cu") (net 71))
  (segment (start 122.421892 80.856255) (end 122.429145 80.876983) (width 0.109) (layer "In4.Cu") (net 71))
  (segment (start 116.310955 78.855641) (end 118.387814 80.9325) (width 0.109) (layer "In4.Cu") (net 71))
  (segment (start 118.642539 80.706912) (end 118.663206 80.693926) (width 0.109) (layer "In4.Cu") (net 71))
  (segment (start 116.310953 78.70149) (end 116.295736 78.720574) (width 0.109) (layer "In4.Cu") (net 71))
  (segment (start 115.850949 78.395635) (end 116.002657 78.547343) (width 0.109) (layer "In4.Cu") (net 71))
  (segment (start 118.77846 80.706912) (end 118.795719 80.724171) (width 0.109) (layer "In4.Cu") (net 71))
  (segment (start 122.440828 80.895577) (end 122.456356 80.911105) (width 0.109) (layer "In4.Cu") (net 71))
  (segment (start 115.850949 76.717003) (end 115.850949 78.395635) (width 0.109) (layer "In4.Cu") (net 71))
  (segment (start 122.277678 80.738826) (end 122.2995 80.736368) (width 0.109) (layer "In4.Cu") (net 71))
  (segment (start 118.6015 80.792131) (end 118.604232 80.767877) (width 0.109) (layer "In4.Cu") (net 71))
  (segment (start 122.25695 80.746079) (end 122.277678 80.738826) (width 0.109) (layer "In4.Cu") (net 71))
  (segment (start 116.021739 78.56256) (end 116.043731 78.573151) (width 0.109) (layer "In4.Cu") (net 71))
  (segment (start 116.002657 78.547343) (end 116.021739 78.56256) (width 0.109) (layer "In4.Cu") (net 71))
  (segment (start 122.382511 80.757762) (end 122.398039 80.77329) (width 0.109) (layer "In4.Cu") (net 71))
  (segment (start 118.7105 80.683131) (end 118.734754 80.685864) (width 0.109) (layer "In4.Cu") (net 71))
  (segment (start 122.198975 80.856255) (end 122.203892 80.812612) (width 0.109) (layer "In4.Cu") (net 71))
  (segment (start 118.8195 80.792131) (end 118.8195 80.8235) (width 0.109) (layer "In4.Cu") (net 71))
  (segment (start 116.348799 78.65978) (end 116.333582 78.678864) (width 0.109) (layer "In4.Cu") (net 71))
  (segment (start 122.363917 80.746079) (end 122.382511 80.757762) (width 0.109) (layer "In4.Cu") (net 71))
  (segment (start 122.456356 80.911105) (end 122.47495 80.922788) (width 0.109) (layer "In4.Cu") (net 71))
  (segment (start 122.409722 80.791884) (end 122.416975 80.812612) (width 0.109) (layer "In4.Cu") (net 71))
  (segment (start 118.387814 80.9325) (end 118.4925 80.9325) (width 0.109) (layer "In4.Cu") (net 71))
  (segment (start 122.164511 80.911105) (end 122.180039 80.895577) (width 0.109) (layer "In4.Cu") (net 71))
  (segment (start 116.285145 78.742565) (end 116.279713 78.76636) (width 0.109) (layer "In4.Cu") (net 71))
  (segment (start 116.364821 78.589585) (end 116.364821 78.613993) (width 0.109) (layer "In4.Cu") (net 71))
  (segment (start 118.734754 80.685864) (end 118.757793 80.693926) (width 0.109) (layer "In4.Cu") (net 71))
  (segment (start 122.5175 80.9325) (end 123.162186 80.9325) (width 0.109) (layer "In4.Cu") (net 71))
  (segment (start 116.268711 78.493474) (end 116.292508 78.498906) (width 0.109) (layer "In4.Cu") (net 71))
  (segment (start 118.604232 80.767877) (end 118.612294 80.744838) (width 0.109) (layer "In4.Cu") (net 71))
  (segment (start 118.9285 80.9325) (end 122.103368 80.9325) (width 0.109) (layer "In4.Cu") (net 71))
  (segment (start 118.8195 80.8235) (end 118.822232 80.847755) (width 0.109) (layer "In4.Cu") (net 71))
  (segment (start 118.577719 80.891461) (end 118.590705 80.870794) (width 0.109) (layer "In4.Cu") (net 71))
  (segment (start 116.333581 78.524714) (end 116.3488 78.543798) (width 0.109) (layer "In4.Cu") (net 71))
  (segment (start 122.180039 80.895577) (end 122.191722 80.876983) (width 0.109) (layer "In4.Cu") (net 71))
  (segment (start 122.343189 80.738826) (end 122.363917 80.746079) (width 0.109) (layer "In4.Cu") (net 71))
  (segment (start 116.043731 78.573151) (end 116.067526 78.578581) (width 0.109) (layer "In4.Cu") (net 71))
  (segment (start 118.881206 80.921706) (end 118.904245 80.929768) (width 0.109) (layer "In4.Cu") (net 71))
  (segment (start 122.191722 80.876983) (end 122.198975 80.856255) (width 0.109) (layer "In4.Cu") (net 71))
  (segment (start 122.398039 80.77329) (end 122.409722 80.791884) (width 0.109) (layer "In4.Cu") (net 71))
  (segment (start 116.285144 78.814565) (end 116.295735 78.836556) (width 0.109) (layer "In4.Cu") (net 71))
  (segment (start 116.364821 78.613993) (end 116.35939 78.63779) (width 0.109) (layer "In4.Cu") (net 71))
  (segment (start 115.912449 76.437503) (end 115.912449 76.221253) (width 0.182) (layer "B.Cu") (net 71))
  (segment (start 116.021449 76.546503) (end 115.912449 76.437503) (width 0.182) (layer "B.Cu") (net 71))
  (segment (start 116.13945 75.994252) (end 116.13945 75.327549) (width 0.182) (layer "B.Cu") (net 71))
  (segment (start 116.13945 75.327549) (end 116.224449 75.24255) (width 0.182) (layer "B.Cu") (net 71))
  (segment (start 115.912449 76.221253) (end 116.13945 75.994252) (width 0.182) (layer "B.Cu") (net 71))
  (segment (start 116.224449 75.24255) (end 116.224449 74.967572) (width 0.182) (layer "B.Cu") (net 71))
  (segment (start 123.707941 79.740663) (end 123.816941 79.849663) (width 0.182) (layer "F.Cu") (net 72))
  (segment (start 123.707941 79.515461) (end 123.707941 79.740663) (width 0.182) (layer "F.Cu") (net 72))
  (segment (start 123.718941 79.504461) (end 123.707941 79.515461) (width 0.182) (layer "F.Cu") (net 72))
  (segment (start 123.718941 78.746061) (end 123.718941 79.504461) (width 0.182) (layer "F.Cu") (net 72))
  (via (at 115.425449 76.546503) (size 0.45) (drill 0.1) (layers "F.Cu" "B.Cu") (net 72))
  (via (at 123.816941 79.849663) (size 0.45) (drill 0.1) (layers "F.Cu" "B.Cu") (net 72))
  (segment (start 115.425449 76.546503) (end 115.595949 76.717003) (width 0.109) (layer "In4.Cu") (net 72))
  (segment (start 123.646441 80.808873) (end 123.646441 80.020163) (width 0.109) (layer "In4.Cu") (net 72))
  (segment (start 115.595949 76.717003) (end 115.595949 78.501263) (width 0.109) (layer "In4.Cu") (net 72))
  (segment (start 123.267814 81.1875) (end 123.646441 80.808873) (width 0.109) (layer "In4.Cu") (net 72))
  (segment (start 123.646441 80.020163) (end 123.816941 79.849663) (width 0.109) (layer "In4.Cu") (net 72))
  (segment (start 115.595949 78.501263) (end 118.282186 81.1875) (width 0.109) (layer "In4.Cu") (net 72))
  (segment (start 118.282186 81.1875) (end 123.267814 81.1875) (width 0.109) (layer "In4.Cu") (net 72))
  (segment (start 115.534449 76.437503) (end 115.534449 76.221253) (width 0.182) (layer "B.Cu") (net 72))
  (segment (start 115.425449 76.546503) (end 115.534449 76.437503) (width 0.182) (layer "B.Cu") (net 72))
  (segment (start 115.534449 76.221253) (end 115.307448 75.994252) (width 0.182) (layer "B.Cu") (net 72))
  (segment (start 115.224449 75.239448) (end 115.224449 74.967572) (width 0.182) (layer "B.Cu") (net 72))
  (segment (start 115.307448 75.322447) (end 115.224449 75.239448) (width 0.182) (layer "B.Cu") (net 72))
  (segment (start 115.307448 75.994252) (end 115.307448 75.322447) (width 0.182) (layer "B.Cu") (net 72))
  (segment (start 121.898883 91.113433) (end 121.898883 92.060723) (width 0.182) (layer "F.Cu") (net 73))
  (segment (start 121.718943 90.323661) (end 121.718943 90.727261) (width 0.182) (layer "F.Cu") (net 73))
  (segment (start 121.707942 90.738262) (end 121.707942 90.922492) (width 0.182) (layer "F.Cu") (net 73))
  (segment (start 121.718943 90.727261) (end 121.707942 90.738262) (width 0.182) (layer "F.Cu") (net 73))
  (segment (start 121.707942 90.922492) (end 121.898883 91.113433) (width 0.182) (layer "F.Cu") (net 73))
  (segment (start 108.98614 75.427584) (end 108.956355 75.380182) (width 0.182) (layer "F.Cu") (net 73))
  (segment (start 107.211001 70.611) (end 107.080001 70.48) (width 0.182) (layer "F.Cu") (net 73))
  (segment (start 107.211 71.378288) (end 107.211001 70.611) (width 0.182) (layer "F.Cu") (net 73))
  (segment (start 109.406458 75.615839) (end 109.366873 75.576254) (width 0.182) (layer "F.Cu") (net 73))
  (segment (start 109.454732 75.716081) (end 109.436243 75.663241) (width 0.182) (layer "F.Cu") (net 73))
  (segment (start 108.196607 76.116068) (end 109.116644 76.116068) (width 0.182) (layer "F.Cu") (net 73))
  (segment (start 109.319471 75.546469) (end 109.266631 75.52798) (width 0.182) (layer "F.Cu") (net 73))
  (segment (start 109.211 75.521712) (end 109.181597 75.521712) (width 0.182) (layer "F.Cu") (net 73))
  (segment (start 109.125967 75.02798) (end 109.181597 75.021712) (width 0.182) (layer "F.Cu") (net 73))
  (segment (start 108.087606 76.007067) (end 108.196607 76.116068) (width 0.182) (layer "F.Cu") (net 73))
  (segment (start 109.461 75.771712) (end 109.454732 75.716081) (width 0.182) (layer "F.Cu") (net 73))
  (segment (start 108.931597 75.271712) (end 108.937866 75.216081) (width 0.182) (layer "F.Cu") (net 73))
  (segment (start 109.125967 75.515443) (end 109.073127 75.496954) (width 0.182) (layer "F.Cu") (net 73))
  (segment (start 109.025725 75.467169) (end 108.98614 75.427584) (width 0.182) (layer "F.Cu") (net 73))
  (segment (start 109.181597 75.021712) (end 109.211 75.021712) (width 0.182) (layer "F.Cu") (net 73))
  (segment (start 109.461 74.771712) (end 109.461 74.202251) (width 0.182) (layer "F.Cu") (net 73))
  (segment (start 109.073127 75.046469) (end 109.125967 75.02798) (width 0.182) (layer "F.Cu") (net 73))
  (segment (start 122.007882 92.169722) (end 121.898883 92.060723) (width 0.182) (layer "F.Cu") (net 73))
  (segment (start 109.025725 75.076254) (end 109.073127 75.046469) (width 0.182) (layer "F.Cu") (net 73))
  (segment (start 108.98614 75.115839) (end 109.025725 75.076254) (width 0.182) (layer "F.Cu") (net 73))
  (segment (start 109.4 72.458748) (end 109.461 72.397748) (width 0.182) (layer "F.Cu") (net 73))
  (segment (start 109.436243 75.663241) (end 109.406458 75.615839) (width 0.182) (layer "F.Cu") (net 73))
  (segment (start 109.319471 74.996954) (end 109.366873 74.967169) (width 0.182) (layer "F.Cu") (net 73))
  (segment (start 122.007884 92.169722) (end 122.007882 92.169722) (width 0.182) (layer "F.Cu") (net 73))
  (segment (start 109.436243 74.880182) (end 109.454732 74.827342) (width 0.182) (layer "F.Cu") (net 73))
  (segment (start 109.454732 74.827342) (end 109.461 74.771712) (width 0.182) (layer "F.Cu") (net 73))
  (segment (start 109.221712 71.788999) (end 107.621712 71.789) (width 0.182) (layer "F.Cu") (net 73))
  (segment (start 109.181597 75.521712) (end 109.125967 75.515443) (width 0.182) (layer "F.Cu") (net 73))
  (segment (start 109.402 72.9455) (end 109.402 73.7175) (width 0.182) (layer "F.Cu") (net 73))
  (segment (start 109.4 73.7175) (end 109.4 74.141251) (width 0.182) (layer "F.Cu") (net 73))
  (segment (start 109.461 72.397748) (end 109.461 72.028288) (width 0.182) (layer "F.Cu") (net 73))
  (segment (start 107.621712 71.789) (end 107.211 71.378288) (width 0.182) (layer "F.Cu") (net 73))
  (segment (start 109.073127 75.496954) (end 109.025725 75.467169) (width 0.182) (layer "F.Cu") (net 73))
  (segment (start 108.937866 75.216081) (end 108.956355 75.163241) (width 0.182) (layer "F.Cu") (net 73))
  (segment (start 109.461 72.028288) (end 109.221712 71.788999) (width 0.182) (layer "F.Cu") (net 73))
  (segment (start 108.956355 75.380182) (end 108.937866 75.327342) (width 0.182) (layer "F.Cu") (net 73))
  (segment (start 109.406458 74.927584) (end 109.436243 74.880182) (width 0.182) (layer "F.Cu") (net 73))
  (segment (start 109.116644 76.116068) (end 109.461 75.771712) (width 0.182) (layer "F.Cu") (net 73))
  (segment (start 109.366873 74.967169) (end 109.406458 74.927584) (width 0.182) (layer "F.Cu") (net 73))
  (segment (start 109.366873 75.576254) (end 109.319471 75.546469) (width 0.182) (layer "F.Cu") (net 73))
  (segment (start 108.937866 75.327342) (end 108.931597 75.271712) (width 0.182) (layer "F.Cu") (net 73))
  (segment (start 109.266631 75.52798) (end 109.211 75.521712) (width 0.182) (layer "F.Cu") (net 73))
  (segment (start 109.4 72.882499) (end 109.4 72.458748) (width 0.182) (layer "F.Cu") (net 73))
  (segment (start 108.956355 75.163241) (end 108.98614 75.115839) (width 0.182) (layer "F.Cu") (net 73))
  (segment (start 107.080001 70.48) (end 106.4 70.48) (width 0.182) (layer "F.Cu") (net 73))
  (segment (start 109.461 74.202251) (end 109.4 74.141251) (width 0.182) (layer "F.Cu") (net 73))
  (segment (start 109.211 75.021712) (end 109.266631 75.015443) (width 0.182) (layer "F.Cu") (net 73))
  (segment (start 109.266631 75.015443) (end 109.319471 74.996954) (width 0.182) (layer "F.Cu") (net 73))
  (via (at 122.007884 92.169722) (size 0.45) (drill 0.1) (layers "F.Cu" "B.Cu") (net 73))
  (via (at 108.087606 76.007067) (size 0.45) (drill 0.1) (layers "F.Cu" "B.Cu") (net 73))
  (segment (start 111.1725 91.202814) (end 111.1725 82.627814) (width 0.109) (layer "In6.Cu") (net 73))
  (segment (start 114.797186 94.8275) (end 118.852814 94.8275) (width 0.109) (layer "In6.Cu") (net 73))
  (segment (start 114.797186 94.8275) (end 111.1725 91.202814) (width 0.109) (layer "In6.Cu") (net 73))
  (segment (start 121.837383 92.340222) (end 121.837383 93.440586) (width 0.109) (layer "In6.Cu") (net 73))
  (segment (start 121.837383 93.440586) (end 120.750469 94.5275) (width 0.109) (layer "In6.Cu") (net 73))
  (segment (start 108.087606 76.007067) (end 107.917106 76.177567) (width 0.109) (layer "In6.Cu") (net 73))
  (segment (start 107.267119 76.177567) (end 106.4725 76.972186) (width 0.109) (layer "In6.Cu") (net 73))
  (segment (start 118.852814 94.8275) (end 119.152814 94.5275) (width 0.109) (layer "In6.Cu") (net 73))
  (segment (start 106.4725 77.927814) (end 106.4725 76.972186) (width 0.109) (layer "In6.Cu") (net 73))
  (segment (start 119.152814 94.5275) (end 120.750469 94.5275) (width 0.109) (layer "In6.Cu") (net 73))
  (segment (start 122.007883 92.169722) (end 121.837383 92.340222) (width 0.109) (layer "In6.Cu") (net 73))
  (segment (start 122.007884 92.169722) (end 122.007883 92.169722) (width 0.109) (layer "In6.Cu") (net 73))
  (segment (start 111.1725 82.627814) (end 106.4725 77.927814) (width 0.109) (layer "In6.Cu") (net 73))
  (segment (start 107.917106 76.177567) (end 107.267119 76.177567) (width 0.109) (layer "In6.Cu") (net 73))
  (segment (start 121.329942 90.738262) (end 121.329942 91.079067) (width 0.182) (layer "F.Cu") (net 74))
  (segment (start 121.411883 92.169722) (end 121.520883 92.060722) (width 0.182) (layer "F.Cu") (net 74))
  (segment (start 121.318941 90.727261) (end 121.329942 90.738262) (width 0.182) (layer "F.Cu") (net 74))
  (segment (start 121.520883 91.270009) (end 121.520883 92.060722) (width 0.182) (layer "F.Cu") (net 74))
  (segment (start 121.318941 90.323661) (end 121.318941 90.727261) (width 0.182) (layer "F.Cu") (net 74))
  (segment (start 121.329942 91.079067) (end 121.520883 91.270009) (width 0.182) (layer "F.Cu") (net 74))
  (segment (start 109.378289 71.410999) (end 107.778288 71.410999) (width 0.182) (layer "F.Cu") (net 74))
  (segment (start 108.196607 76.494068) (end 108.087607 76.603068) (width 0.182) (layer "F.Cu") (net 74))
  (segment (start 109.839 74.202251) (end 109.839 75.928288) (width 0.182) (layer "F.Cu") (net 74))
  (segment (start 109.902 72.9455) (end 109.902 73.7175) (width 0.182) (layer "F.Cu") (net 74))
  (segment (start 109.9 72.8825) (end 109.9 72.458749) (width 0.182) (layer "F.Cu") (net 74))
  (segment (start 109.27322 76.494068) (end 108.196607 76.494068) (width 0.182) (layer "F.Cu") (net 74))
  (segment (start 107.589 71.221711) (end 107.589 70.611) (width 0.182) (layer "F.Cu") (net 74))
  (segment (start 109.839 72.397748) (end 109.839001 71.871711) (width 0.182) (layer "F.Cu") (net 74))
  (segment (start 109.9 73.7175) (end 109.9 74.141251) (width 0.182) (layer "F.Cu") (net 74))
  (segment (start 109.839 75.928288) (end 109.27322 76.494068) (width 0.182) (layer "F.Cu") (net 74))
  (segment (start 107.778288 71.410999) (end 107.589 71.221711) (width 0.182) (layer "F.Cu") (net 74))
  (segment (start 107.589 70.611) (end 107.72 70.48) (width 0.182) (layer "F.Cu") (net 74))
  (segment (start 107.72 70.48) (end 108.4 70.479999) (width 0.182) (layer "F.Cu") (net 74))
  (segment (start 109.9 74.141251) (end 109.839 74.202251) (width 0.182) (layer "F.Cu") (net 74))
  (segment (start 109.839001 71.871711) (end 109.378289 71.410999) (width 0.182) (layer "F.Cu") (net 74))
  (segment (start 109.9 72.458749) (end 109.839 72.397748) (width 0.182) (layer "F.Cu") (net 74))
  (via (at 121.411883 92.169722) (size 0.45) (drill 0.1) (layers "F.Cu" "B.Cu") (net 74))
  (via (at 108.087607 76.603068) (size 0.45) (drill 0.1) (layers "F.Cu" "B.Cu") (net 74))
  (segment (start 112.276028 91.945714) (end 114.902814 94.5725) (width 0.109) (layer "In6.Cu") (net 74))
  (segment (start 121.263133 93.362713) (end 121.272849 93.342538) (width 0.109) (layer "In6.Cu") (net 74))
  (segment (start 106.7275 77.077814) (end 106.99386 76.811455) (width 0.109) (layer "In6.Cu") (net 74))
  (segment (start 111.4275 82.522186) (end 111.4275 91.097186) (width 0.109) (layer "In6.Cu") (net 74))
  (segment (start 107.302157 76.503157) (end 107.286939 76.522241) (width 0.109) (layer "In6.Cu") (net 74))
  (segment (start 111.878024 91.542391) (end 111.908288 91.556966) (width 0.109) (layer "In6.Cu") (net 74))
  (segment (start 111.51677 91.140175) (end 111.55036 91.140176) (width 0.109) (layer "In6.Cu") (net 74))
  (segment (start 111.711902 91.045922) (end 111.744648 91.038447) (width 0.109) (layer "In6.Cu") (net 74))
  (segment (start 121.403278 93.288625) (end 121.423453 93.298341) (width 0.109) (layer "In6.Cu") (net 74))
  (segment (start 107.148009 76.811457) (end 107.128927 76.796238) (width 0.109) (layer "In6.Cu") (net 74))
  (segment (start 111.83082 91.495188) (end 111.851764 91.52145) (width 0.109) (layer "In6.Cu") (net 74))
  (segment (start 111.888451 91.267308) (end 111.867509 91.29357) (width 0.109) (layer "In6.Cu") (net 74))
  (segment (start 111.655377 91.081438) (end 111.681638 91.060495) (width 0.109) (layer "In6.Cu") (net 74))
  (segment (start 107.250128 76.855535) (end 107.22572 76.855535) (width 0.109) (layer "In6.Cu") (net 74))
  (segment (start 112.291773 91.505702) (end 112.312716 91.531964) (width 0.109) (layer "In6.Cu") (net 74))
  (segment (start 119.047186 94.2725) (end 120.622186 94.2725) (width 0.109) (layer "In6.Cu") (net 74))
  (segment (start 121.272849 93.342538) (end 121.286811 93.32503) (width 0.109) (layer "In6.Cu") (net 74))
  (segment (start 107.106936 76.785647) (end 107.083139 76.780216) (width 0.109) (layer "In6.Cu") (net 74))
  (segment (start 107.314997 76.670147) (end 107.330216 76.689229) (width 0.109) (layer "In6.Cu") (net 74))
  (segment (start 121.300772 93.483959) (end 121.272849 93.448944) (width 0.109) (layer "In6.Cu") (net 74))
  (segment (start 111.903025 91.137962) (end 111.9105 91.17071) (width 0.109) (layer "In6.Cu") (net 74))
  (segment (start 112.327289 91.562226) (end 112.334764 91.594974) (width 0.109) (layer "In6.Cu") (net 74))
  (segment (start 111.55036 91.140176) (end 111.583106 91.132701) (width 0.109) (layer "In6.Cu") (net 74))
  (segment (start 112.136166 91.470186) (end 112.168912 91.462711) (width 0.109) (layer "In6.Cu") (net 74))
  (segment (start 112.202502 91.462711) (end 112.23525 91.470186) (width 0.109) (layer "In6.Cu") (net 74))
  (segment (start 112.079641 91.505702) (end 112.105902 91.484759) (width 0.109) (layer "In6.Cu") (net 74))
  (segment (start 121.359053 93.283642) (end 121.381446 93.283642) (width 0.109) (layer "In6.Cu") (net 74))
  (segment (start 107.083139 76.780216) (end 107.058731 76.780216) (width 0.109) (layer "In6.Cu") (net 74))
  (segment (start 112.334763 91.628562) (end 112.32729 91.66131) (width 0.109) (layer "In6.Cu") (net 74))
  (segment (start 106.7275 77.822186) (end 111.4275 82.522186) (width 0.109) (layer "In6.Cu") (net 74))
  (segment (start 107.917106 76.432567) (end 107.372747 76.432567) (width 0.109) (layer "In6.Cu") (net 74))
  (segment (start 121.582383 93.312303) (end 121.582383 92.340222) (width 0.109) (layer "In6.Cu") (net 74))
  (segment (start 111.639632 91.097186) (end 111.655377 91.081438) (width 0.109) (layer "In6.Cu") (net 74))
  (segment (start 121.582383 92.340222) (end 121.411883 92.169722) (width 0.109) (layer "In6.Cu") (net 74))
  (segment (start 121.381446 93.283642) (end 121.403278 93.288625) (width 0.109) (layer "In6.Cu") (net 74))
  (segment (start 111.851763 91.309317) (end 111.83082 91.335578) (width 0.109) (layer "In6.Cu") (net 74))
  (segment (start 112.063896 91.52145) (end 112.079641 91.505702) (width 0.109) (layer "In6.Cu") (net 74))
  (segment (start 111.810986 91.045922) (end 111.841248 91.060495) (width 0.109) (layer "In6.Cu") (net 74))
  (segment (start 111.841248 91.060495) (end 111.867509 91.081438) (width 0.109) (layer "In6.Cu") (net 74))
  (segment (start 112.240509 91.790104) (end 112.233036 91.822852) (width 0.109) (layer "In6.Cu") (net 74))
  (segment (start 107.28694 76.638223) (end 107.302157 76.657307) (width 0.109) (layer "In6.Cu") (net 74))
  (segment (start 118.747186 94.5725) (end 119.047186 94.2725) (width 0.109) (layer "In6.Cu") (net 74))
  (segment (start 107.372747 76.432567) (end 107.302157 76.503157) (width 0.109) (layer "In6.Cu") (net 74))
  (segment (start 112.233036 91.856442) (end 112.240509 91.889188) (width 0.109) (layer "In6.Cu") (net 74))
  (segment (start 120.622186 94.2725) (end 121.286811 93.607873) (width 0.109) (layer "In6.Cu") (net 74))
  (segment (start 111.808772 91.432178) (end 111.816245 91.464924) (width 0.109) (layer "In6.Cu") (net 74))
  (segment (start 107.22572 76.855535) (end 107.201923 76.850104) (width 0.109) (layer "In6.Cu") (net 74))
  (segment (start 107.034934 76.785648) (end 107.012943 76.796239) (width 0.109) (layer "In6.Cu") (net 74))
  (segment (start 112.312716 91.531964) (end 112.327289 91.562226) (width 0.109) (layer "In6.Cu") (net 74))
  (segment (start 121.337222 93.288625) (end 121.359053 93.283642) (width 0.109) (layer "In6.Cu") (net 74))
  (segment (start 112.255084 91.759842) (end 112.240509 91.790104) (width 0.109) (layer "In6.Cu") (net 74))
  (segment (start 121.564875 93.326264) (end 121.582383 93.312303) (width 0.109) (layer "In6.Cu") (net 74))
  (segment (start 111.744648 91.038447) (end 111.778238 91.038447) (width 0.109) (layer "In6.Cu") (net 74))
  (segment (start 111.867509 91.29357) (end 111.851763 91.309317) (width 0.109) (layer "In6.Cu") (net 74))
  (segment (start 112.265512 91.484759) (end 112.291773 91.505702) (width 0.109) (layer "In6.Cu") (net 74))
  (segment (start 107.270918 76.568028) (end 107.270918 76.592436) (width 0.109) (layer "In6.Cu") (net 74))
  (segment (start 112.334764 91.594974) (end 112.334763 91.628562) (width 0.109) (layer "In6.Cu") (net 74))
  (segment (start 107.314998 76.824295) (end 107.295915 76.839514) (width 0.109) (layer "In6.Cu") (net 74))
  (segment (start 112.105902 91.484759) (end 112.136166 91.470186) (width 0.109) (layer "In6.Cu") (net 74))
  (segment (start 107.340806 76.783222) (end 107.330215 76.805213) (width 0.109) (layer "In6.Cu") (net 74))
  (segment (start 111.583106 91.132701) (end 111.61337 91.118128) (width 0.109) (layer "In6.Cu") (net 74))
  (segment (start 112.23525 91.470186) (end 112.265512 91.484759) (width 0.109) (layer "In6.Cu") (net 74))
  (segment (start 112.233036 91.822852) (end 112.233036 91.856442) (width 0.109) (layer "In6.Cu") (net 74))
  (segment (start 111.867509 91.081438) (end 111.888452 91.1077) (width 0.109) (layer "In6.Cu") (net 74))
  (segment (start 114.902814 94.5725) (end 118.747186 94.5725) (width 0.109) (layer "In6.Cu") (net 74))
  (segment (start 107.330215 76.805213) (end 107.314998 76.824295) (width 0.109) (layer "In6.Cu") (net 74))
  (segment (start 111.816245 91.36584) (end 111.808772 91.398588) (width 0.109) (layer "In6.Cu") (net 74))
  (segment (start 106.7275 77.077814) (end 106.7275 77.822186) (width 0.109) (layer "In6.Cu") (net 74))
  (segment (start 111.9105 91.17071) (end 111.910499 91.204298) (width 0.109) (layer "In6.Cu") (net 74))
  (segment (start 121.272849 93.448944) (end 121.263133 93.428769) (width 0.109) (layer "In6.Cu") (net 74))
  (segment (start 107.179931 76.839515) (end 107.160848 76.824296) (width 0.109) (layer "In6.Cu") (net 74))
  (segment (start 111.808772 91.398588) (end 111.808772 91.432178) (width 0.109) (layer "In6.Cu") (net 74))
  (segment (start 107.276349 76.616233) (end 107.28694 76.638223) (width 0.109) (layer "In6.Cu") (net 74))
  (segment (start 107.286939 76.522241) (end 107.27635 76.544231) (width 0.109) (layer "In6.Cu") (net 74))
  (segment (start 111.681638 91.060495) (end 111.711902 91.045922) (width 0.109) (layer "In6.Cu") (net 74))
  (segment (start 112.037634 91.542392) (end 112.063896 91.52145) (width 0.109) (layer "In6.Cu") (net 74))
  (segment (start 107.346238 76.735017) (end 107.346238 76.759425) (width 0.109) (layer "In6.Cu") (net 74))
  (segment (start 111.484024 91.132702) (end 111.51677 91.140175) (width 0.109) (layer "In6.Cu") (net 74))
  (segment (start 107.346238 76.759425) (end 107.340806 76.783222) (width 0.109) (layer "In6.Cu") (net 74))
  (segment (start 112.00737 91.556965) (end 112.037634 91.542392) (width 0.109) (layer "In6.Cu") (net 74))
  (segment (start 121.5447 93.33598) (end 121.564875 93.326264) (width 0.109) (layer "In6.Cu") (net 74))
  (segment (start 107.295915 76.839514) (end 107.273923 76.850105) (width 0.109) (layer "In6.Cu") (net 74))
  (segment (start 121.25815 93.384545) (end 121.263133 93.362713) (width 0.109) (layer "In6.Cu") (net 74))
  (segment (start 111.4275 91.097186) (end 111.45376 91.118127) (width 0.109) (layer "In6.Cu") (net 74))
  (segment (start 107.302157 76.657307) (end 107.314997 76.670147) (width 0.109) (layer "In6.Cu") (net 74))
  (segment (start 107.201923 76.850104) (end 107.179931 76.839515) (width 0.109) (layer "In6.Cu") (net 74))
  (segment (start 121.458469 93.326264) (end 121.478644 93.33598) (width 0.109) (layer "In6.Cu") (net 74))
  (segment (start 121.300772 93.590365) (end 121.310488 93.57019) (width 0.109) (layer "In6.Cu") (net 74))
  (segment (start 121.500475 93.340963) (end 121.522868 93.340963) (width 0.109) (layer "In6.Cu") (net 74))
  (segment (start 121.299539 93.312303) (end 121.317047 93.298341) (width 0.109) (layer "In6.Cu") (net 74))
  (segment (start 107.058731 76.780216) (end 107.034934 76.785648) (width 0.109) (layer "In6.Cu") (net 74))
  (segment (start 121.25815 93.406938) (end 121.25815 93.384545) (width 0.109) (layer "In6.Cu") (net 74))
  (segment (start 112.312715 91.691572) (end 112.291773 91.717834) (width 0.109) (layer "In6.Cu") (net 74))
  (segment (start 112.276027 91.733581) (end 112.255084 91.759842) (width 0.109) (layer "In6.Cu") (net 74))
  (segment (start 111.83082 91.335578) (end 111.816245 91.36584) (width 0.109) (layer "In6.Cu") (net 74))
  (segment (start 121.286811 93.32503) (end 121.299539 93.312303) (width 0.109) (layer "In6.Cu") (net 74))
  (segment (start 107.012943 76.796239) (end 106.99386 76.811455) (width 0.109) (layer "In6.Cu") (net 74))
  (segment (start 121.478644 93.33598) (end 121.500475 93.340963) (width 0.109) (layer "In6.Cu") (net 74))
  (segment (start 112.255084 91.919452) (end 112.276028 91.945714) (width 0.109) (layer "In6.Cu") (net 74))
  (segment (start 121.522868 93.340963) (end 121.5447 93.33598) (width 0.109) (layer "In6.Cu") (net 74))
  (segment (start 108.087607 76.603068) (end 107.917106 76.432567) (width 0.109) (layer "In6.Cu") (net 74))
  (segment (start 107.340807 76.71122) (end 107.346238 76.735017) (width 0.109) (layer "In6.Cu") (net 74))
  (segment (start 112.291773 91.717834) (end 112.276027 91.733581) (width 0.109) (layer "In6.Cu") (net 74))
  (segment (start 107.273923 76.850105) (end 107.250128 76.855535) (width 0.109) (layer "In6.Cu") (net 74))
  (segment (start 111.851764 91.52145) (end 111.878024 91.542391) (width 0.109) (layer "In6.Cu") (net 74))
  (segment (start 121.286811 93.607873) (end 121.300772 93.590365) (width 0.109) (layer "In6.Cu") (net 74))
  (segment (start 111.778238 91.038447) (end 111.810986 91.045922) (width 0.109) (layer "In6.Cu") (net 74))
  (segment (start 112.32729 91.66131) (end 112.312715 91.691572) (width 0.109) (layer "In6.Cu") (net 74))
  (segment (start 107.27635 76.544231) (end 107.270918 76.568028) (width 0.109) (layer "In6.Cu") (net 74))
  (segment (start 107.330216 76.689229) (end 107.340807 76.71122) (width 0.109) (layer "In6.Cu") (net 74))
  (segment (start 111.903026 91.237046) (end 111.888451 91.267308) (width 0.109) (layer "In6.Cu") (net 74))
  (segment (start 111.61337 91.118128) (end 111.639632 91.097186) (width 0.109) (layer "In6.Cu") (net 74))
  (segment (start 111.974624 91.56444) (end 112.00737 91.556965) (width 0.109) (layer "In6.Cu") (net 74))
  (segment (start 121.423453 93.298341) (end 121.458469 93.326264) (width 0.109) (layer "In6.Cu") (net 74))
  (segment (start 121.315471 93.548359) (end 121.315471 93.525966) (width 0.109) (layer "In6.Cu") (net 74))
  (segment (start 121.315471 93.525966) (end 121.310488 93.504134) (width 0.109) (layer "In6.Cu") (net 74))
  (segment (start 121.263133 93.428769) (end 121.25815 93.406938) (width 0.109) (layer "In6.Cu") (net 74))
  (segment (start 112.168912 91.462711) (end 112.202502 91.462711) (width 0.109) (layer "In6.Cu") (net 74))
  (segment (start 121.310488 93.504134) (end 121.300772 93.483959) (width 0.109) (layer "In6.Cu") (net 74))
  (segment (start 111.941034 91.564439) (end 111.974624 91.56444) (width 0.109) (layer "In6.Cu") (net 74))
  (segment (start 112.240509 91.889188) (end 112.255084 91.919452) (width 0.109) (layer "In6.Cu") (net 74))
  (segment (start 107.270918 76.592436) (end 107.276349 76.616233) (width 0.109) (layer "In6.Cu") (net 74))
  (segment (start 111.45376 91.118127) (end 111.484024 91.132702) (width 0.109) (layer "In6.Cu") (net 74))
  (segment (start 107.160848 76.824296) (end 107.148009 76.811457) (width 0.109) (layer "In6.Cu") (net 74))
  (segment (start 107.128927 76.796238) (end 107.106936 76.785647) (width 0.109) (layer "In6.Cu") (net 74))
  (segment (start 121.310488 93.57019) (end 121.315471 93.548359) (width 0.109) (layer "In6.Cu") (net 74))
  (segment (start 121.317047 93.298341) (end 121.337222 93.288625) (width 0.109) (layer "In6.Cu") (net 74))
  (segment (start 111.816245 91.464924) (end 111.83082 91.495188) (width 0.109) (layer "In6.Cu") (net 74))
  (segment (start 111.910499 91.204298) (end 111.903026 91.237046) (width 0.109) (layer "In6.Cu") (net 74))
  (segment (start 111.908288 91.556966) (end 111.941034 91.564439) (width 0.109) (layer "In6.Cu") (net 74))
  (segment (start 111.888452 91.1077) (end 111.903025 91.137962) (width 0.109) (layer "In6.Cu") (net 74))
  (segment (start 120.518943 90.727261) (end 120.507942 90.738262) (width 0.182) (layer "F.Cu") (net 75))
  (segment (start 120.507943 91.079067) (end 120.317001 91.27001) (width 0.182) (layer "F.Cu") (net 75))
  (segment (start 120.507942 90.738262) (end 120.507943 91.079067) (width 0.182) (layer "F.Cu") (net 75))
  (segment (start 120.518943 90.323661) (end 120.518943 90.727261) (width 0.182) (layer "F.Cu") (net 75))
  (segment (start 120.317001 92.060721) (end 120.426002 92.169722) (width 0.182) (layer "F.Cu") (net 75))
  (segment (start 110.961 76.199288) (end 111.6352 76.873488) (width 0.182) (layer "F.Cu") (net 75))
  (segment (start 111.6352 77.309803) (end 111.526199 77.418804) (width 0.182) (layer "F.Cu") (net 75))
  (segment (start 110.961 75.891) (end 110.961 76.199288) (width 0.182) (layer "F.Cu") (net 75))
  (segment (start 110.7 75.63) (end 110.961 75.891) (width 0.182) (layer "F.Cu") (net 75))
  (segment (start 120.317001 91.27001) (end 120.317001 92.060721) (width 0.182) (layer "F.Cu") (net 75))
  (segment (start 111.6352 76.873488) (end 111.6352 77.309803) (width 0.182) (layer "F.Cu") (net 75))
  (via (at 120.426002 92.169722) (size 0.45) (drill 0.1) (layers "F.Cu" "B.Cu") (net 75))
  (via (at 111.526199 77.418804) (size 0.45) (drill 0.1) (layers "F.Cu" "B.Cu") (net 75))
  (segment (start 111.499199 80.434199) (end 111.543146 80.43915) (width 0.109) (layer "In6.Cu") (net 75))
  (segment (start 111.65361 80.508559) (end 111.67714 80.546006) (width 0.109) (layer "In6.Cu") (net 75))
  (segment (start 111.499199 78.229199) (end 110.669193 78.229199) (width 0.109) (layer "In6.Cu") (net 75))
  (segment (start 113.131 79.246006) (end 113.145607 79.287751) (width 0.109) (layer "In6.Cu") (net 75))
  (segment (start 118.757814 93.9025) (end 119.902814 93.9025) (width 0.109) (layer "In6.Cu") (net 75))
  (segment (start 110.285062 80.192833) (end 110.335856 80.273672) (width 0.109) (layer "In6.Cu") (net 75))
  (segment (start 113.038751 79.153757) (end 113.076198 79.177287) (width 0.109) (layer "In6.Cu") (net 75))
  (segment (start 110.335856 78.389725) (end 110.285062 78.470564) (width 0.109) (layer "In6.Cu") (net 75))
  (segment (start 110.403366 78.322215) (end 110.335856 78.389725) (width 0.109) (layer "In6.Cu") (net 75))
  (segment (start 113.10747 79.208559) (end 113.131 79.246006) (width 0.109) (layer "In6.Cu") (net 75))
  (segment (start 110.335856 79.689725) (end 110.285062 79.770564) (width 0.109) (layer "In6.Cu") (net 75))
  (segment (start 113.10747 79.454838) (end 113.076198 79.48611) (width 0.109) (layer "In6.Cu") (net 75))
  (segment (start 110.669193 79.529199) (end 110.57432 79.539888) (width 0.109) (layer "In6.Cu") (net 75))
  (segment (start 110.669193 78.229199) (end 110.57432 78.239888) (width 0.109) (layer "In6.Cu") (net 75))
  (segment (start 111.543146 78.224247) (end 111.499199 78.229199) (width 0.109) (layer "In6.Cu") (net 75))
  (segment (start 118.492814 94.1675) (end 118.757814 93.9025) (width 0.109) (layer "In6.Cu") (net 75))
  (segment (start 111.622338 80.477287) (end 111.65361 80.508559) (width 0.109) (layer "In6.Cu") (net 75))
  (segment (start 110.669193 79.134199) (end 112.953058 79.134199) (width 0.109) (layer "In6.Cu") (net 75))
  (segment (start 111.691747 78.075646) (end 111.67714 78.117391) (width 0.109) (layer "In6.Cu") (net 75))
  (segment (start 112.953058 79.529199) (end 110.669193 79.529199) (width 0.109) (layer "In6.Cu") (net 75))
  (segment (start 111.696699 78.031699) (end 111.691747 78.075646) (width 0.109) (layer "In6.Cu") (net 75))
  (segment (start 110.285062 78.892833) (end 110.335856 78.973672) (width 0.109) (layer "In6.Cu") (net 75))
  (segment (start 112.953058 79.134199) (end 112.997006 79.13915) (width 0.109) (layer "In6.Cu") (net 75))
  (segment (start 110.484205 80.391976) (end 110.57432 80.423509) (width 0.109) (layer "In6.Cu") (net 75))
  (segment (start 111.691747 80.587751) (end 111.696699 80.631699) (width 0.109) (layer "In6.Cu") (net 75))
  (segment (start 110.285062 78.470564) (end 110.253529 78.560679) (width 0.109) (layer "In6.Cu") (net 75))
  (segment (start 120.255501 93.549813) (end 120.255501 92.340223) (width 0.109) (layer "In6.Cu") (net 75))
  (segment (start 112.5575 82.012814) (end 112.5575 90.837814) (width 0.109) (layer "In6.Cu") (net 75))
  (segment (start 112.997006 79.524247) (end 112.953058 79.529199) (width 0.109) (layer "In6.Cu") (net 75))
  (segment (start 110.57432 78.239888) (end 110.484205 78.271421) (width 0.109) (layer "In6.Cu") (net 75))
  (segment (start 111.65361 78.154838) (end 111.622338 78.18611) (width 0.109) (layer "In6.Cu") (net 75))
  (segment (start 110.253529 78.802718) (end 110.285062 78.892833) (width 0.109) (layer "In6.Cu") (net 75))
  (segment (start 110.484205 78.271421) (end 110.403366 78.322215) (width 0.109) (layer "In6.Cu") (net 75))
  (segment (start 111.526199 77.418804) (end 111.696699 77.589304) (width 0.109) (layer "In6.Cu") (net 75))
  (segment (start 111.696699 81.152013) (end 112.5575 82.012814) (width 0.109) (layer "In6.Cu") (net 75))
  (segment (start 110.57432 80.423509) (end 110.669193 80.434199) (width 0.109) (layer "In6.Cu") (net 75))
  (segment (start 113.076198 79.177287) (end 113.10747 79.208559) (width 0.109) (layer "In6.Cu") (net 75))
  (segment (start 110.484205 79.091976) (end 110.57432 79.123509) (width 0.109) (layer "In6.Cu") (net 75))
  (segment (start 110.57432 79.123509) (end 110.669193 79.134199) (width 0.109) (layer "In6.Cu") (net 75))
  (segment (start 111.584891 80.453757) (end 111.622338 80.477287) (width 0.109) (layer "In6.Cu") (net 75))
  (segment (start 110.335856 78.973672) (end 110.403366 79.041182) (width 0.109) (layer "In6.Cu") (net 75))
  (segment (start 110.253529 79.860679) (end 110.24284 79.955552) (width 0.109) (layer "In6.Cu") (net 75))
  (segment (start 115.887186 94.1675) (end 118.492814 94.1675) (width 0.109) (layer "In6.Cu") (net 75))
  (segment (start 111.543146 80.43915) (end 111.584891 80.453757) (width 0.109) (layer "In6.Cu") (net 75))
  (segment (start 110.403366 80.341182) (end 110.484205 80.391976) (width 0.109) (layer "In6.Cu") (net 75))
  (segment (start 111.584891 78.20964) (end 111.543146 78.224247) (width 0.109) (layer "In6.Cu") (net 75))
  (segment (start 113.145607 79.287751) (end 113.150558 79.331699) (width 0.109) (layer "In6.Cu") (net 75))
  (segment (start 111.67714 80.546006) (end 111.691747 80.587751) (width 0.109) (layer "In6.Cu") (net 75))
  (segment (start 113.145607 79.375646) (end 113.131 79.417391) (width 0.109) (layer "In6.Cu") (net 75))
  (segment (start 110.484205 79.571421) (end 110.403366 79.622215) (width 0.109) (layer "In6.Cu") (net 75))
  (segment (start 120.255501 92.340223) (end 120.426002 92.169722) (width 0.109) (layer "In6.Cu") (net 75))
  (segment (start 110.24284 80.007845) (end 110.253529 80.102718) (width 0.109) (layer "In6.Cu") (net 75))
  (segment (start 110.335856 80.273672) (end 110.403366 80.341182) (width 0.109) (layer "In6.Cu") (net 75))
  (segment (start 113.038751 79.50964) (end 112.997006 79.524247) (width 0.109) (layer "In6.Cu") (net 75))
  (segment (start 113.131 79.417391) (end 113.10747 79.454838) (width 0.109) (layer "In6.Cu") (net 75))
  (segment (start 110.253529 78.560679) (end 110.24284 78.655552) (width 0.109) (layer "In6.Cu") (net 75))
  (segment (start 110.24284 79.955552) (end 110.24284 80.007845) (width 0.109) (layer "In6.Cu") (net 75))
  (segment (start 112.997006 79.13915) (end 113.038751 79.153757) (width 0.109) (layer "In6.Cu") (net 75))
  (segment (start 110.253529 80.102718) (end 110.285062 80.192833) (width 0.109) (layer "In6.Cu") (net 75))
  (segment (start 113.150558 79.331699) (end 113.145607 79.375646) (width 0.109) (layer "In6.Cu") (net 75))
  (segment (start 111.622338 78.18611) (end 111.584891 78.20964) (width 0.109) (layer "In6.Cu") (net 75))
  (segment (start 110.57432 79.539888) (end 110.484205 79.571421) (width 0.109) (layer "In6.Cu") (net 75))
  (segment (start 111.696699 77.589304) (end 111.696699 78.031699) (width 0.109) (layer "In6.Cu") (net 75))
  (segment (start 111.67714 78.117391) (end 111.65361 78.154838) (width 0.109) (layer "In6.Cu") (net 75))
  (segment (start 110.24284 78.707845) (end 110.253529 78.802718) (width 0.109) (layer "In6.Cu") (net 75))
  (segment (start 110.24284 78.655552) (end 110.24284 78.707845) (width 0.109) (layer "In6.Cu") (net 75))
  (segment (start 113.076198 79.48611) (end 113.038751 79.50964) (width 0.109) (layer "In6.Cu") (net 75))
  (segment (start 110.669193 80.434199) (end 111.499199 80.434199) (width 0.109) (layer "In6.Cu") (net 75))
  (segment (start 110.403366 79.041182) (end 110.484205 79.091976) (width 0.109) (layer "In6.Cu") (net 75))
  (segment (start 110.285062 79.770564) (end 110.253529 79.860679) (width 0.109) (layer "In6.Cu") (net 75))
  (segment (start 111.696699 80.631699) (end 111.696699 81.152013) (width 0.109) (layer "In6.Cu") (net 75))
  (segment (start 112.5575 90.837814) (end 115.887186 94.1675) (width 0.109) (layer "In6.Cu") (net 75))
  (segment (start 110.403366 79.622215) (end 110.335856 79.689725) (width 0.109) (layer "In6.Cu") (net 75))
  (segment (start 119.902814 93.9025) (end 120.255501 93.549813) (width 0.109) (layer "In6.Cu") (net 75))
  (segment (start 119.939001 91.113433) (end 119.939001 92.060723) (width 0.182) (layer "F.Cu") (net 76))
  (segment (start 120.129942 90.738262) (end 120.129941 90.922492) (width 0.182) (layer "F.Cu") (net 76))
  (segment (start 120.118941 90.727261) (end 120.129942 90.738262) (width 0.182) (layer "F.Cu") (net 76))
  (segment (start 120.129941 90.922492) (end 119.939001 91.113433) (width 0.182) (layer "F.Cu") (net 76))
  (segment (start 119.830001 92.169722) (end 119.939001 92.060723) (width 0.182) (layer "F.Cu") (net 76))
  (segment (start 120.118941 90.323661) (end 120.118941 90.727261) (width 0.182) (layer "F.Cu") (net 76))
  (segment (start 111.339 75.891) (end 111.339 76.042712) (width 0.182) (layer "F.Cu") (net 76))
  (segment (start 111.6 75.63) (end 111.339 75.891) (width 0.182) (layer "F.Cu") (net 76))
  (segment (start 112.0132 77.309803) (end 112.1222 77.418803) (width 0.182) (layer "F.Cu") (net 76))
  (segment (start 112.0132 76.716912) (end 112.0132 77.309803) (width 0.182) (layer "F.Cu") (net 76))
  (segment (start 111.339 76.042712) (end 112.0132 76.716912) (width 0.182) (layer "F.Cu") (net 76))
  (via (at 119.830001 92.169722) (size 0.45) (drill 0.1) (layers "F.Cu" "B.Cu") (net 76))
  (via (at 112.1222 77.418803) (size 0.45) (drill 0.1) (layers "F.Cu" "B.Cu") (net 76))
  (segment (start 116.571206 93.901706) (end 116.594245 93.909768) (width 0.109) (layer "In6.Cu") (net 76))
  (segment (start 116.31528 93.663738) (end 116.332539 93.646479) (width 0.109) (layer "In6.Cu") (net 76))
  (segment (start 111.791172 78.391182) (end 111.710333 78.441976) (width 0.109) (layer "In6.Cu") (net 76))
  (segment (start 113.164193 78.921421) (end 113.245032 78.972215) (width 0.109) (layer "In6.Cu") (net 76))
  (segment (start 111.710333 78.441976) (end 111.620218 78.473509) (width 0.109) (layer "In6.Cu") (net 76))
  (segment (start 113.139263 90.948999) (end 113.129548 90.969175) (width 0.109) (layer "In6.Cu") (net 76))
  (segment (start 116.267719 93.871461) (end 116.280705 93.850794) (width 0.109) (layer "In6.Cu") (net 76))
  (segment (start 113.245032 78.972215) (end 113.312542 79.039725) (width 0.109) (layer "In6.Cu") (net 76))
  (segment (start 116.6185 93.9125) (end 118.387186 93.9125) (width 0.109) (layer "In6.Cu") (net 76))
  (segment (start 111.951699 80.605552) (end 111.951699 81.046385) (width 0.109) (layer "In6.Cu") (net 76))
  (segment (start 110.540928 78.558559) (end 110.517398 78.596006) (width 0.109) (layer "In6.Cu") (net 76))
  (segment (start 110.517398 78.596006) (end 110.502791 78.637751) (width 0.109) (layer "In6.Cu") (net 76))
  (segment (start 116.2915 93.8035) (end 116.2915 93.731698) (width 0.109) (layer "In6.Cu") (net 76))
  (segment (start 111.941009 78.152718) (end 111.909476 78.242833) (width 0.109) (layer "In6.Cu") (net 76))
  (segment (start 113.181887 90.849586) (end 113.181886 90.871978) (width 0.109) (layer "In6.Cu") (net 76))
  (segment (start 113.447561 91.257297) (end 113.437846 91.277473) (width 0.109) (layer "In6.Cu") (net 76))
  (segment (start 115.992814 93.9125) (end 116.1825 93.9125) (width 0.109) (layer "In6.Cu") (net 76))
  (segment (start 113.394869 79.452718) (end 113.363336 79.542833) (width 0.109) (layer "In6.Cu") (net 76))
  (segment (start 113.176903 90.893809) (end 113.167188 90.913985) (width 0.109) (layer "In6.Cu") (net 76))
  (segment (start 113.074078 78.889888) (end 113.164193 78.921421) (width 0.109) (layer "In6.Cu") (net 76))
  (segment (start 113.431289 91.07168) (end 113.448797 91.085642) (width 0.109) (layer "In6.Cu") (net 76))
  (segment (start 110.502791 80.025646) (end 110.517398 80.067391) (width 0.109) (layer "In6.Cu") (net 76))
  (segment (start 120.000501 93.444185) (end 120.000501 92.340222) (width 0.109) (layer "In6.Cu") (net 76))
  (segment (start 113.475486 91.222283) (end 113.461524 91.239791) (width 0.109) (layer "In6.Cu") (net 76))
  (segment (start 116.25046 93.88872) (end 116.267719 93.871461) (width 0.109) (layer "In6.Cu") (net 76))
  (segment (start 110.517398 79.896006) (end 110.502791 79.937751) (width 0.109) (layer "In6.Cu") (net 76))
  (segment (start 111.951699 77.589304) (end 111.951699 78.057845) (width 0.109) (layer "In6.Cu") (net 76))
  (segment (start 112.979205 78.879199) (end 113.074078 78.889888) (width 0.109) (layer "In6.Cu") (net 76))
  (segment (start 112.857657 90.777344) (end 112.875164 90.791305) (width 0.109) (layer "In6.Cu") (net 76))
  (segment (start 110.651392 80.174247) (end 110.69534 80.179199) (width 0.109) (layer "In6.Cu") (net 76))
  (segment (start 113.164193 79.741976) (end 113.074078 79.773509) (width 0.109) (layer "In6.Cu") (net 76))
  (segment (start 110.69534 79.784199) (end 110.651392 79.78915) (width 0.109) (layer "In6.Cu") (net 76))
  (segment (start 116.4005 93.622698) (end 116.424754 93.625431) (width 0.109) (layer "In6.Cu") (net 76))
  (segment (start 112.8125 90.732187) (end 112.857657 90.777344) (width 0.109) (layer "In6.Cu") (net 76))
  (segment (start 110.5722 78.527287) (end 110.540928 78.558559) (width 0.109) (layer "In6.Cu") (net 76))
  (segment (start 116.498705 93.684405) (end 116.506767 93.707444) (width 0.109) (layer "In6.Cu") (net 76))
  (segment (start 113.153226 90.931493) (end 113.139263 90.948999) (width 0.109) (layer "In6.Cu") (net 76))
  (segment (start 110.69534 78.879199) (end 112.979205 78.879199) (width 0.109) (layer "In6.Cu") (net 76))
  (segment (start 113.448797 91.085642) (end 113.461524 91.098369) (width 0.109) (layer "In6.Cu") (net 76))
  (segment (start 116.520294 93.850794) (end 116.53328 93.871461) (width 0.109) (layer "In6.Cu") (net 76))
  (segment (start 110.540928 80.104838) (end 110.5722 80.13611) (width 0.109) (layer "In6.Cu") (net 76))
  (segment (start 113.203636 91.109318) (end 113.225469 91.114302) (width 0.109) (layer "In6.Cu") (net 76))
  (segment (start 111.951699 81.046385) (end 112.8125 81.907186) (width 0.109) (layer "In6.Cu") (net 76))
  (segment (start 118.652186 93.6475) (end 119.797186 93.6475) (width 0.109) (layer "In6.Cu") (net 76))
  (segment (start 113.363336 79.120564) (end 113.394869 79.210679) (width 0.109) (layer "In6.Cu") (net 76))
  (segment (start 113.122991 90.763382) (end 113.140499 90.777344) (width 0.109) (layer "In6.Cu") (net 76))
  (segment (start 113.411113 91.061963) (end 113.431289 91.07168) (width 0.109) (layer "In6.Cu") (net 76))
  (segment (start 110.69534 80.179199) (end 111.525345 80.179199) (width 0.109) (layer "In6.Cu") (net 76))
  (segment (start 113.140499 90.777344) (end 113.153226 90.790071) (width 0.109) (layer "In6.Cu") (net 76))
  (segment (start 113.129548 90.969175) (end 113.124564 90.991006) (width 0.109) (layer "In6.Cu") (net 76))
  (segment (start 110.609647 78.503757) (end 110.5722 78.527287) (width 0.109) (layer "In6.Cu") (net 76))
  (segment (start 113.437846 91.277473) (end 113.432862 91.299304) (width 0.109) (layer "In6.Cu") (net 76))
  (segment (start 112.917171 90.806004) (end 112.939563 90.806003) (width 0.109) (layer "In6.Cu") (net 76))
  (segment (start 110.609647 78.85964) (end 110.651392 78.874247) (width 0.109) (layer "In6.Cu") (net 76))
  (segment (start 113.447561 91.363703) (end 113.461523 91.381211) (width 0.109) (layer "In6.Cu") (net 76))
  (segment (start 113.176903 90.827753) (end 113.181887 90.849586) (width 0.109) (layer "In6.Cu") (net 76))
  (segment (start 113.345057 91.061963) (end 113.36689 91.056981) (width 0.109) (layer "In6.Cu") (net 76))
  (segment (start 113.183462 91.099603) (end 113.203636 91.109318) (width 0.109) (layer "In6.Cu") (net 76))
  (segment (start 110.609647 80.15964) (end 110.651392 80.174247) (width 0.109) (layer "In6.Cu") (net 76))
  (segment (start 116.46846 93.646479) (end 116.485719 93.663738) (width 0.109) (layer "In6.Cu") (net 76))
  (segment (start 112.961394 90.80102) (end 112.98157 90.791305) (width 0.109) (layer "In6.Cu") (net 76))
  (segment (start 116.506767 93.707444) (end 116.5095 93.731698) (width 0.109) (layer "In6.Cu") (net 76))
  (segment (start 113.269692 91.109318) (end 113.289868 91.099603) (width 0.109) (layer "In6.Cu") (net 76))
  (segment (start 119.797186 93.6475) (end 120.000501 93.444185) (width 0.109) (layer "In6.Cu") (net 76))
  (segment (start 113.102815 90.753665) (end 113.122991 90.763382) (width 0.109) (layer "In6.Cu") (net 76))
  (segment (start 113.129548 91.035231) (end 113.139263 91.055405) (width 0.109) (layer "In6.Cu") (net 76))
  (segment (start 110.5722 80.13611) (end 110.609647 80.15964) (width 0.109) (layer "In6.Cu") (net 76))
  (segment (start 113.124564 90.991006) (end 113.124565 91.0134) (width 0.109) (layer "In6.Cu") (net 76))
  (segment (start 110.517398 80.067391) (end 110.540928 80.104838) (width 0.109) (layer "In6.Cu") (net 76))
  (segment (start 111.941009 80.510679) (end 111.951699 80.605552) (width 0.109) (layer "In6.Cu") (net 76))
  (segment (start 113.036759 90.753665) (end 113.058592 90.748683) (width 0.109) (layer "In6.Cu") (net 76))
  (segment (start 113.389282 91.05698) (end 113.411113 91.061963) (width 0.109) (layer "In6.Cu") (net 76))
  (segment (start 113.36689 91.056981) (end 113.389282 91.05698) (width 0.109) (layer "In6.Cu") (net 76))
  (segment (start 113.324883 91.07168) (end 113.345057 91.061963) (width 0.109) (layer "In6.Cu") (net 76))
  (segment (start 113.437846 91.343529) (end 113.447561 91.363703) (width 0.109) (layer "In6.Cu") (net 76))
  (segment (start 113.490185 91.157884) (end 113.490184 91.180276) (width 0.109) (layer "In6.Cu") (net 76))
  (segment (start 111.620218 80.189888) (end 111.710333 80.221421) (width 0.109) (layer "In6.Cu") (net 76))
  (segment (start 116.302294 93.684405) (end 116.31528 93.663738) (width 0.109) (layer "In6.Cu") (net 76))
  (segment (start 111.909476 78.242833) (end 111.858682 78.323672) (width 0.109) (layer "In6.Cu") (net 76))
  (segment (start 110.502791 78.637751) (end 110.49784 78.681699) (width 0.109) (layer "In6.Cu") (net 76))
  (segment (start 113.124565 91.0134) (end 113.129548 91.035231) (width 0.109) (layer "In6.Cu") (net 76))
  (segment (start 111.909476 80.420564) (end 111.941009 80.510679) (width 0.109) (layer "In6.Cu") (net 76))
  (segment (start 116.353206 93.633493) (end 116.376245 93.625431) (width 0.109) (layer "In6.Cu") (net 76))
  (segment (start 111.791172 80.272215) (end 111.858682 80.339725) (width 0.109) (layer "In6.Cu") (net 76))
  (segment (start 112.939563 90.806003) (end 112.961394 90.80102) (width 0.109) (layer "In6.Cu") (net 76))
  (segment (start 113.058592 90.748683) (end 113.080984 90.748682) (width 0.109) (layer "In6.Cu") (net 76))
  (segment (start 113.225469 91.114302) (end 113.247861 91.114301) (width 0.109) (layer "In6.Cu") (net 76))
  (segment (start 110.49784 78.681699) (end 110.502791 78.725646) (width 0.109) (layer "In6.Cu") (net 76))
  (segment (start 116.288767 93.827755) (end 116.2915 93.8035) (width 0.109) (layer "In6.Cu") (net 76))
  (segment (start 110.502791 78.725646) (end 110.517398 78.767391) (width 0.109) (layer "In6.Cu") (net 76))
  (segment (start 116.206754 93.909768) (end 116.229793 93.901706) (width 0.109) (layer "In6.Cu") (net 76))
  (segment (start 116.53328 93.871461) (end 116.550539 93.88872) (width 0.109) (layer "In6.Cu") (net 76))
  (segment (start 113.405558 79.357845) (end 113.394869 79.452718) (width 0.109) (layer "In6.Cu") (net 76))
  (segment (start 110.609647 79.803757) (end 110.5722 79.827287) (width 0.109) (layer "In6.Cu") (net 76))
  (segment (start 112.1222 77.418803) (end 111.951699 77.589304) (width 0.109) (layer "In6.Cu") (net 76))
  (segment (start 116.447793 93.633493) (end 116.46846 93.646479) (width 0.109) (layer "In6.Cu") (net 76))
  (segment (start 112.98157 90.791305) (end 113.016585 90.763382) (width 0.109) (layer "In6.Cu") (net 76))
  (segment (start 113.074078 79.773509) (end 112.979205 79.784199) (width 0.109) (layer "In6.Cu") (net 76))
  (segment (start 110.540928 78.804838) (end 110.5722 78.83611) (width 0.109) (layer "In6.Cu") (net 76))
  (segment (start 110.69534 78.484199) (end 110.651392 78.48915) (width 0.109) (layer "In6.Cu") (net 76))
  (segment (start 116.280705 93.850794) (end 116.288767 93.827755) (width 0.109) (layer "In6.Cu") (net 76))
  (segment (start 113.312542 79.039725) (end 113.363336 79.120564) (width 0.109) (layer "In6.Cu") (net 76))
  (segment (start 110.5722 79.827287) (end 110.540928 79.858559) (width 0.109) (layer "In6.Cu") (net 76))
  (segment (start 113.475486 91.115877) (end 113.485201 91.136051) (width 0.109) (layer "In6.Cu") (net 76))
  (segment (start 116.2915 93.731698) (end 116.294232 93.707444) (width 0.109) (layer "In6.Cu") (net 76))
  (segment (start 116.512232 93.827755) (end 116.520294 93.850794) (width 0.109) (layer "In6.Cu") (net 76))
  (segment (start 110.517398 78.767391) (end 110.540928 78.804838) (width 0.109) (layer "In6.Cu") (net 76))
  (segment (start 120.000501 92.340222) (end 119.830001 92.169722) (width 0.109) (layer "In6.Cu") (net 76))
  (segment (start 113.167188 90.807579) (end 113.176903 90.827753) (width 0.109) (layer "In6.Cu") (net 76))
  (segment (start 111.525345 80.179199) (end 111.620218 80.189888) (width 0.109) (layer "In6.Cu") (net 76))
  (segment (start 110.651392 78.874247) (end 110.69534 78.879199) (width 0.109) (layer "In6.Cu") (net 76))
  (segment (start 110.651392 78.48915) (end 110.609647 78.503757) (width 0.109) (layer "In6.Cu") (net 76))
  (segment (start 113.432862 91.299304) (end 113.432863 91.321698) (width 0.109) (layer "In6.Cu") (net 76))
  (segment (start 110.651392 79.78915) (end 110.609647 79.803757) (width 0.109) (layer "In6.Cu") (net 76))
  (segment (start 111.858682 80.339725) (end 111.909476 80.420564) (width 0.109) (layer "In6.Cu") (net 76))
  (segment (start 113.485201 91.136051) (end 113.490185 91.157884) (width 0.109) (layer "In6.Cu") (net 76))
  (segment (start 116.5095 93.8035) (end 116.512232 93.827755) (width 0.109) (layer "In6.Cu") (net 76))
  (segment (start 112.979205 79.784199) (end 110.69534 79.784199) (width 0.109) (layer "In6.Cu") (net 76))
  (segment (start 113.153226 90.790071) (end 113.167188 90.807579) (width 0.109) (layer "In6.Cu") (net 76))
  (segment (start 116.376245 93.625431) (end 116.4005 93.622698) (width 0.109) (layer "In6.Cu") (net 76))
  (segment (start 118.387186 93.9125) (end 118.652186 93.6475) (width 0.109) (layer "In6.Cu") (net 76))
  (segment (start 110.5722 78.83611) (end 110.609647 78.85964) (width 0.109) (layer "In6.Cu") (net 76))
  (segment (start 111.858682 78.323672) (end 111.791172 78.391182) (width 0.109) (layer "In6.Cu") (net 76))
  (segment (start 113.153225 91.072913) (end 113.165955 91.085642) (width 0.109) (layer "In6.Cu") (net 76))
  (segment (start 113.165955 91.085642) (end 113.183462 91.099603) (width 0.109) (layer "In6.Cu") (net 76))
  (segment (start 116.485719 93.663738) (end 116.498705 93.684405) (width 0.109) (layer "In6.Cu") (net 76))
  (segment (start 113.461523 91.381211) (end 115.992814 93.9125) (width 0.109) (layer "In6.Cu") (net 76))
  (segment (start 113.016585 90.763382) (end 113.036759 90.753665) (width 0.109) (layer "In6.Cu") (net 76))
  (segment (start 116.229793 93.901706) (end 116.25046 93.88872) (width 0.109) (layer "In6.Cu") (net 76))
  (segment (start 113.461524 91.098369) (end 113.475486 91.115877) (width 0.109) (layer "In6.Cu") (net 76))
  (segment (start 113.245032 79.691182) (end 113.164193 79.741976) (width 0.109) (layer "In6.Cu") (net 76))
  (segment (start 113.247861 91.114301) (end 113.269692 91.109318) (width 0.109) (layer "In6.Cu") (net 76))
  (segment (start 113.167188 90.913985) (end 113.153226 90.931493) (width 0.109) (layer "In6.Cu") (net 76))
  (segment (start 110.540928 79.858559) (end 110.517398 79.896006) (width 0.109) (layer "In6.Cu") (net 76))
  (segment (start 113.490184 91.180276) (end 113.485201 91.202107) (width 0.109) (layer "In6.Cu") (net 76))
  (segment (start 116.332539 93.646479) (end 116.353206 93.633493) (width 0.109) (layer "In6.Cu") (net 76))
  (segment (start 116.1825 93.9125) (end 116.206754 93.909768) (width 0.109) (layer "In6.Cu") (net 76))
  (segment (start 112.895338 90.80102) (end 112.917171 90.806004) (width 0.109) (layer "In6.Cu") (net 76))
  (segment (start 113.312542 79.623672) (end 113.245032 79.691182) (width 0.109) (layer "In6.Cu") (net 76))
  (segment (start 116.424754 93.625431) (end 116.447793 93.633493) (width 0.109) (layer "In6.Cu") (net 76))
  (segment (start 116.294232 93.707444) (end 116.302294 93.684405) (width 0.109) (layer "In6.Cu") (net 76))
  (segment (start 113.405558 79.305552) (end 113.405558 79.357845) (width 0.109) (layer "In6.Cu") (net 76))
  (segment (start 113.432863 91.321698) (end 113.437846 91.343529) (width 0.109) (layer "In6.Cu") (net 76))
  (segment (start 116.594245 93.909768) (end 116.6185 93.9125) (width 0.109) (layer "In6.Cu") (net 76))
  (segment (start 113.461524 91.239791) (end 113.447561 91.257297) (width 0.109) (layer "In6.Cu") (net 76))
  (segment (start 113.289868 91.099603) (end 113.324883 91.07168) (width 0.109) (layer "In6.Cu") (net 76))
  (segment (start 113.363336 79.542833) (end 113.312542 79.623672) (width 0.109) (layer "In6.Cu") (net 76))
  (segment (start 111.710333 80.221421) (end 111.791172 80.272215) (width 0.109) (layer "In6.Cu") (net 76))
  (segment (start 113.080984 90.748682) (end 113.102815 90.753665) (width 0.109) (layer "In6.Cu") (net 76))
  (segment (start 112.8125 81.907186) (end 112.8125 90.732187) (width 0.109) (layer "In6.Cu") (net 76))
  (segment (start 112.875164 90.791305) (end 112.895338 90.80102) (width 0.109) (layer "In6.Cu") (net 76))
  (segment (start 110.502791 79.937751) (end 110.49784 79.981699) (width 0.109) (layer "In6.Cu") (net 76))
  (segment (start 113.139263 91.055405) (end 113.153225 91.072913) (width 0.109) (layer "In6.Cu") (net 76))
  (segment (start 111.951699 78.057845) (end 111.941009 78.152718) (width 0.109) (layer "In6.Cu") (net 76))
  (segment (start 111.620218 78.473509) (end 111.525345 78.484199) (width 0.109) (layer "In6.Cu") (net 76))
  (segment (start 113.394869 79.210679) (end 113.405558 79.305552) (width 0.109) (layer "In6.Cu") (net 76))
  (segment (start 111.525345 78.484199) (end 110.69534 78.484199) (width 0.109) (layer "In6.Cu") (net 76))
  (segment (start 113.485201 91.202107) (end 113.475486 91.222283) (width 0.109) (layer "In6.Cu") (net 76))
  (segment (start 116.5095 93.731698) (end 116.5095 93.8035) (width 0.109) (layer "In6.Cu") (net 76))
  (segment (start 113.181886 90.871978) (end 113.176903 90.893809) (width 0.109) (layer "In6.Cu") (net 76))
  (segment (start 110.49784 79.981699) (end 110.502791 80.025646) (width 0.109) (layer "In6.Cu") (net 76))
  (segment (start 116.550539 93.88872) (end 116.571206 93.901706) (width 0.109) (layer "In6.Cu") (net 76))
  (segment (start 113.378 76.267681) (end 113.605001 76.04068) (width 0.182) (layer "F.Cu") (net 77))
  (segment (start 113.378 76.483931) (end 113.378 76.267681) (width 0.182) (layer "F.Cu") (net 77))
  (segment (start 113.487 76.592931) (end 113.378 76.483931) (width 0.182) (layer "F.Cu") (net 77))
  (segment (start 113.605001 75.373977) (end 113.69 75.288978) (width 0.182) (layer "F.Cu") (net 77))
  (segment (start 113.69 75.288978) (end 113.69 75.014) (width 0.182) (layer "F.Cu") (net 77))
  (segment (start 113.605001 76.04068) (end 113.605001 75.373977) (width 0.182) (layer "F.Cu") (net 77))
  (segment (start 119.707942 89.554261) (end 119.707943 89.331937) (width 0.182) (layer "F.Cu") (net 77))
  (segment (start 119.718942 90.323661) (end 119.718942 89.565261) (width 0.182) (layer "F.Cu") (net 77))
  (segment (start 119.718942 89.565261) (end 119.707942 89.554261) (width 0.182) (layer "F.Cu") (net 77))
  (segment (start 119.707943 89.331937) (end 119.816943 89.222937) (width 0.182) (layer "F.Cu") (net 77))
  (via (at 113.487 76.592931) (size 0.45) (drill 0.1) (layers "F.Cu" "B.Cu") (net 77))
  (via (at 119.816943 89.222937) (size 0.45) (drill 0.1) (layers "F.Cu" "B.Cu") (net 77))
  (segment (start 115.177814 89.4725) (end 114.5025 88.797186) (width 0.109) (layer "In6.Cu") (net 77))
  (segment (start 119.646443 89.052437) (end 119.646443 88.016129) (width 0.109) (layer "In6.Cu") (net 77))
  (segment (start 119.646443 88.016129) (end 119.302814 87.6725) (width 0.109) (layer "In6.Cu") (net 77))
  (segment (start 113.3165 76.763431) (end 113.3165 78.086186) (width 0.109) (layer "In6.Cu") (net 77))
  (segment (start 114.5025 83.447186) (end 114.0775 83.022186) (width 0.109) (layer "In6.Cu") (net 77))
  (segment (start 114.5025 88.797186) (end 114.5025 83.447186) (width 0.109) (layer "In6.Cu") (net 77))
  (segment (start 114.0775 83.022186) (end 114.0775 78.847186) (width 0.109) (layer "In6.Cu") (net 77))
  (segment (start 116.522186 89.4725) (end 115.177814 89.4725) (width 0.109) (layer "In6.Cu") (net 77))
  (segment (start 119.816943 89.222937) (end 119.646443 89.052437) (width 0.109) (layer "In6.Cu") (net 77))
  (segment (start 119.302814 87.6725) (end 118.322186 87.6725) (width 0.109) (layer "In6.Cu") (net 77))
  (segment (start 113.3165 78.086186) (end 114.0775 78.847186) (width 0.109) (layer "In6.Cu") (net 77))
  (segment (start 118.322186 87.6725) (end 116.522186 89.4725) (width 0.109) (layer "In6.Cu") (net 77))
  (segment (start 113.487 76.592931) (end 113.3165 76.763431) (width 0.109) (layer "In6.Cu") (net 77))
  (segment (start 112.772999 76.04068) (end 112.772999 75.368875) (width 0.182) (layer "F.Cu") (net 78))
  (segment (start 113 76.483931) (end 113 76.267681) (width 0.182) (layer "F.Cu") (net 78))
  (segment (start 112.891 76.592931) (end 113 76.483931) (width 0.182) (layer "F.Cu") (net 78))
  (segment (start 113 76.267681) (end 112.772999 76.04068) (width 0.182) (layer "F.Cu") (net 78))
  (segment (start 112.772999 75.368875) (end 112.69 75.285876) (width 0.182) (layer "F.Cu") (net 78))
  (segment (start 112.69 75.285876) (end 112.69 75.014) (width 0.182) (layer "F.Cu") (net 78))
  (segment (start 119.329943 89.554261) (end 119.329943 89.331937) (width 0.182) (layer "F.Cu") (net 78))
  (segment (start 119.318943 89.565261) (end 119.329943 89.554261) (width 0.182) (layer "F.Cu") (net 78))
  (segment (start 119.329943 89.331937) (end 119.220943 89.222937) (width 0.182) (layer "F.Cu") (net 78))
  (segment (start 119.318943 90.323661) (end 119.318943 89.565261) (width 0.182) (layer "F.Cu") (net 78))
  (via (at 112.891 76.592931) (size 0.45) (drill 0.1) (layers "F.Cu" "B.Cu") (net 78))
  (via (at 119.220943 89.222937) (size 0.45) (drill 0.1) (layers "F.Cu" "B.Cu") (net 78))
  (segment (start 119.197186 87.9275) (end 118.427814 87.9275) (width 0.109) (layer "In6.Cu") (net 78))
  (segment (start 114.2475 83.552814) (end 113.8225 83.127814) (width 0.109) (layer "In6.Cu") (net 78))
  (segment (start 119.220943 89.222937) (end 119.391443 89.052437) (width 0.109) (layer "In6.Cu") (net 78))
  (segment (start 116.627814 89.7275) (end 115.072186 89.7275) (width 0.109) (layer "In6.Cu") (net 78))
  (segment (start 118.427814 87.9275) (end 116.627814 89.7275) (width 0.109) (layer "In6.Cu") (net 78))
  (segment (start 119.391443 89.052437) (end 119.391443 88.121757) (width 0.109) (layer "In6.Cu") (net 78))
  (segment (start 113.0615 78.191814) (end 113.8225 78.952814) (width 0.109) (layer "In6.Cu") (net 78))
  (segment (start 119.391443 88.121757) (end 119.197186 87.9275) (width 0.109) (layer "In6.Cu") (net 78))
  (segment (start 115.072186 89.7275) (end 114.2475 88.902814) (width 0.109) (layer "In6.Cu") (net 78))
  (segment (start 114.2475 88.902814) (end 114.2475 83.552814) (width 0.109) (layer "In6.Cu") (net 78))
  (segment (start 113.0615 76.763431) (end 113.0615 78.191814) (width 0.109) (layer "In6.Cu") (net 78))
  (segment (start 112.891 76.592931) (end 113.0615 76.763431) (width 0.109) (layer "In6.Cu") (net 78))
  (segment (start 113.8225 83.127814) (end 113.8225 78.952814) (width 0.109) (layer "In6.Cu") (net 78))
  (segment (start 121.318941 78.342461) (end 121.329942 78.33146) (width 0.182) (layer "F.Cu") (net 79))
  (segment (start 121.329942 78.33146) (end 121.329942 78.14723) (width 0.182) (layer "F.Cu") (net 79))
  (segment (start 121.139001 77.956289) (end 121.139001 77.009) (width 0.182) (layer "F.Cu") (net 79))
  (segment (start 121.030001 76.9) (end 121.139001 77.009) (width 0.182) (layer "F.Cu") (net 79))
  (segment (start 121.329942 78.14723) (end 121.139001 77.956289) (width 0.182) (layer "F.Cu") (net 79))
  (segment (start 121.318941 78.746061) (end 121.318941 78.342461) (width 0.182) (layer "F.Cu") (net 79))
  (segment (start 121.03 76.9) (end 121.030001 76.9) (width 0.182) (layer "F.Cu") (net 79))
  (via (at 121.03 76.9) (size 0.45) (drill 0.1) (layers "F.Cu" "B.Cu") (net 79))
  (via (at 108.746932 77.637607) (size 0.45) (drill 0.1) (layers "F.Cu" "B.Cu") (net 79))
  (segment (start 109.897186 79.8525) (end 108.917432 78.872746) (width 0.109) (layer "In2.Cu") (net 79))
  (segment (start 120.452354 75.731227) (end 120.44126 75.699523) (width 0.109) (layer "In2.Cu") (net 79))
  (segment (start 120.352582 75.442355) (end 120.320878 75.431261) (width 0.109) (layer "In2.Cu") (net 79))
  (segment (start 120.704774 75.759668) (end 120.681023 75.783419) (width 0.109) (layer "In2.Cu") (net 79))
  (segment (start 120.493976 75.783419) (end 120.470225 75.759668) (width 0.109) (layer "In2.Cu") (net 79))
  (segment (start 115.327814 79.8525) (end 109.897186 79.8525) (width 0.109) (layer "In2.Cu") (net 79))
  (segment (start 120.554121 75.812384) (end 120.522417 75.80129) (width 0.109) (layer "In2.Cu") (net 79))
  (segment (start 120.854121 75.431261) (end 120.822417 75.442355) (width 0.109) (layer "In2.Cu") (net 79))
  (segment (start 121.03 76.9) (end 121.030001 76.9) (width 0.109) (layer "In2.Cu") (net 79))
  (segment (start 120.793976 75.460226) (end 120.770225 75.483977) (width 0.109) (layer "In2.Cu") (net 79))
  (segment (start 120.44126 75.699523) (end 120.4375 75.666144) (width 0.109) (layer "In2.Cu") (net 79))
  (segment (start 120.681023 75.783419) (end 120.652582 75.80129) (width 0.109) (layer "In2.Cu") (net 79))
  (segment (start 120.8875 75.4275) (end 120.854121 75.431261) (width 0.109) (layer "In2.Cu") (net 79))
  (segment (start 120.470225 75.759668) (end 120.452354 75.731227) (width 0.109) (layer "In2.Cu") (net 79))
  (segment (start 120.433739 75.544122) (end 120.422645 75.512418) (width 0.109) (layer "In2.Cu") (net 79))
  (segment (start 120.822417 75.442355) (end 120.793976 75.460226) (width 0.109) (layer "In2.Cu") (net 79))
  (segment (start 120.320878 75.431261) (end 120.2875 75.4275) (width 0.109) (layer "In2.Cu") (net 79))
  (segment (start 120.770225 75.483977) (end 120.752354 75.512418) (width 0.109) (layer "In2.Cu") (net 79))
  (segment (start 120.7375 75.666144) (end 120.733739 75.699523) (width 0.109) (layer "In2.Cu") (net 79))
  (segment (start 120.7375 75.5775) (end 120.7375 75.666144) (width 0.109) (layer "In2.Cu") (net 79))
  (segment (start 120.74126 75.544122) (end 120.7375 75.5775) (width 0.109) (layer "In2.Cu") (net 79))
  (segment (start 121.022186 75.4275) (end 120.8875 75.4275) (width 0.109) (layer "In2.Cu") (net 79))
  (segment (start 120.422645 75.512418) (end 120.404774 75.483977) (width 0.109) (layer "In2.Cu") (net 79))
  (segment (start 120.4375 75.666144) (end 120.4375 75.5775) (width 0.109) (layer "In2.Cu") (net 79))
  (segment (start 121.200501 75.605815) (end 121.022186 75.4275) (width 0.109) (layer "In2.Cu") (net 79))
  (segment (start 120.381023 75.460226) (end 120.352582 75.442355) (width 0.109) (layer "In2.Cu") (net 79))
  (segment (start 120.4375 75.5775) (end 120.433739 75.544122) (width 0.109) (layer "In2.Cu") (net 79))
  (segment (start 120.2875 75.4275) (end 119.752814 75.4275) (width 0.109) (layer "In2.Cu") (net 79))
  (segment (start 120.620878 75.812384) (end 120.5875 75.816144) (width 0.109) (layer "In2.Cu") (net 79))
  (segment (start 108.917432 78.872746) (end 108.917432 77.808107) (width 0.109) (layer "In2.Cu") (net 79))
  (segment (start 120.404774 75.483977) (end 120.381023 75.460226) (width 0.109) (layer "In2.Cu") (net 79))
  (segment (start 119.752814 75.4275) (end 115.327814 79.8525) (width 0.109) (layer "In2.Cu") (net 79))
  (segment (start 108.917432 77.808107) (end 108.746932 77.637607) (width 0.109) (layer "In2.Cu") (net 79))
  (segment (start 120.522417 75.80129) (end 120.493976 75.783419) (width 0.109) (layer "In2.Cu") (net 79))
  (segment (start 121.200501 76.7295) (end 121.200501 75.605815) (width 0.109) (layer "In2.Cu") (net 79))
  (segment (start 120.733739 75.699523) (end 120.722645 75.731227) (width 0.109) (layer "In2.Cu") (net 79))
  (segment (start 120.752354 75.512418) (end 120.74126 75.544122) (width 0.109) (layer "In2.Cu") (net 79))
  (segment (start 121.030001 76.9) (end 121.200501 76.7295) (width 0.109) (layer "In2.Cu") (net 79))
  (segment (start 120.722645 75.731227) (end 120.704774 75.759668) (width 0.109) (layer "In2.Cu") (net 79))
  (segment (start 120.652582 75.80129) (end 120.620878 75.812384) (width 0.109) (layer "In2.Cu") (net 79))
  (segment (start 120.5875 75.816144) (end 120.554121 75.812384) (width 0.109) (layer "In2.Cu") (net 79))
  (segment (start 109.4 72.451248) (end 109.4 72.874999) (width 0.182) (layer "B.Cu") (net 79))
  (segment (start 107.621712 71.7815) (end 107.187813 71.347601) (width 0.182) (layer "B.Cu") (net 79))
  (segment (start 107.211 67.411) (end 107.211 67.968547) (width 0.182) (layer "B.Cu") (net 79))
  (segment (start 108.855933 76.676779) (end 109.461 76.071712) (width 0.182) (layer "B.Cu") (net 79))
  (segment (start 107.08 67.28) (end 107.211 67.411) (width 0.182) (layer "B.Cu") (net 79))
  (segment (start 109.461 72.390248) (end 109.4 72.451248) (width 0.182) (layer "B.Cu") (net 79))
  (segment (start 107.187813 71.347601) (end 107.187813 69.944899) (width 0.182) (layer "B.Cu") (net 79))
  (segment (start 106.4 67.28) (end 107.08 67.28) (width 0.182) (layer "B.Cu") (net 79))
  (segment (start 109.461 72.020788) (end 109.461 72.390248) (width 0.182) (layer "B.Cu") (net 79))
  (segment (start 109.4 72.913) (end 109.4 73.685) (width 0.182) (layer "B.Cu") (net 79))
  (segment (start 107.211 67.968547) (end 107.761 68.518547) (width 0.182) (layer "B.Cu") (net 79))
  (segment (start 108.855933 77.528606) (end 108.855933 76.676779) (width 0.182) (layer "B.Cu") (net 79))
  (segment (start 109.4 74.141251) (end 109.4 73.7175) (width 0.182) (layer "B.Cu") (net 79))
  (segment (start 107.621712 71.7815) (end 109.221712 71.781499) (width 0.182) (layer "B.Cu") (net 79))
  (segment (start 109.461 74.202251) (end 109.4 74.141251) (width 0.182) (layer "B.Cu") (net 79))
  (segment (start 108.746932 77.637607) (end 108.855933 77.528606) (width 0.182) (layer "B.Cu") (net 79))
  (segment (start 107.761 68.518547) (end 107.761 69.371712) (width 0.182) (layer "B.Cu") (net 79))
  (segment (start 109.221712 71.781499) (end 109.461 72.020788) (width 0.182) (layer "B.Cu") (net 79))
  (segment (start 109.461 76.071712) (end 109.461 74.202251) (width 0.182) (layer "B.Cu") (net 79))
  (segment (start 107.187813 69.944899) (end 107.761 69.371712) (width 0.182) (layer "B.Cu") (net 79))
  (segment (start 121.517001 77.799713) (end 121.517001 77.009) (width 0.182) (layer "F.Cu") (net 80))
  (segment (start 121.707942 78.33146) (end 121.707942 77.990654) (width 0.182) (layer "F.Cu") (net 80))
  (segment (start 121.718943 78.746061) (end 121.718943 78.342461) (width 0.182) (layer "F.Cu") (net 80))
  (segment (start 121.626001 76.9) (end 121.517001 77.009) (width 0.182) (layer "F.Cu") (net 80))
  (segment (start 121.718943 78.342461) (end 121.707942 78.33146) (width 0.182) (layer "F.Cu") (net 80))
  (segment (start 121.707942 77.990654) (end 121.517001 77.799713) (width 0.182) (layer "F.Cu") (net 80))
  (via (at 121.626001 76.9) (size 0.45) (drill 0.1) (layers "F.Cu" "B.Cu") (net 80))
  (via (at 109.342933 77.637606) (size 0.45) (drill 0.1) (layers "F.Cu" "B.Cu") (net 80))
  (segment (start 109.785031 78.993909) (end 109.800478 78.961829) (width 0.109) (layer "In2.Cu") (net 80))
  (segment (start 119.647186 75.1725) (end 115.222186 79.5975) (width 0.109) (layer "In2.Cu") (net 80))
  (segment (start 109.257657 78.852343) (end 109.172432 78.767118) (width 0.109) (layer "In2.Cu") (net 80))
  (segment (start 109.285492 78.874541) (end 109.257657 78.852343) (width 0.109) (layer "In2.Cu") (net 80))
  (segment (start 109.762832 78.796886) (end 109.734996 78.774686) (width 0.109) (layer "In2.Cu") (net 80))
  (segment (start 121.455501 75.500187) (end 121.127814 75.1725) (width 0.109) (layer "In2.Cu") (net 80))
  (segment (start 109.707376 79.302062) (end 109.685175 79.274225) (width 0.109) (layer "In2.Cu") (net 80))
  (segment (start 109.317572 78.88999) (end 109.285492 78.874541) (width 0.109) (layer "In2.Cu") (net 80))
  (segment (start 109.45468 78.874542) (end 109.4226 78.889989) (width 0.109) (layer "In2.Cu") (net 80))
  (segment (start 121.455501 76.7295) (end 121.455501 75.500187) (width 0.109) (layer "In2.Cu") (net 80))
  (segment (start 109.762831 79.021744) (end 109.785031 78.993909) (width 0.109) (layer "In2.Cu") (net 80))
  (segment (start 109.702916 78.759237) (end 109.668205 78.751315) (width 0.109) (layer "In2.Cu") (net 80))
  (segment (start 109.734996 78.774686) (end 109.702916 78.759237) (width 0.109) (layer "In2.Cu") (net 80))
  (segment (start 109.632599 78.751314) (end 109.597888 78.759238) (width 0.109) (layer "In2.Cu") (net 80))
  (segment (start 121.626001 76.9) (end 121.455501 76.7295) (width 0.109) (layer "In2.Cu") (net 80))
  (segment (start 109.482515 78.852342) (end 109.45468 78.874542) (width 0.109) (layer "In2.Cu") (net 80))
  (segment (start 109.685174 79.105037) (end 109.707375 79.077201) (width 0.109) (layer "In2.Cu") (net 80))
  (segment (start 109.537972 78.796886) (end 109.482515 78.852342) (width 0.109) (layer "In2.Cu") (net 80))
  (segment (start 109.565808 78.774685) (end 109.537972 78.796886) (width 0.109) (layer "In2.Cu") (net 80))
  (segment (start 109.597888 78.759238) (end 109.565808 78.774685) (width 0.109) (layer "In2.Cu") (net 80))
  (segment (start 109.685175 79.274225) (end 109.669726 79.242145) (width 0.109) (layer "In2.Cu") (net 80))
  (segment (start 109.172432 78.767118) (end 109.172432 77.808107) (width 0.109) (layer "In2.Cu") (net 80))
  (segment (start 109.387889 78.897913) (end 109.352283 78.897912) (width 0.109) (layer "In2.Cu") (net 80))
  (segment (start 109.172432 77.808107) (end 109.342933 77.637606) (width 0.109) (layer "In2.Cu") (net 80))
  (segment (start 115.222186 79.5975) (end 110.002814 79.5975) (width 0.109) (layer "In2.Cu") (net 80))
  (segment (start 110.002814 79.5975) (end 109.707376 79.302062) (width 0.109) (layer "In2.Cu") (net 80))
  (segment (start 109.78503 78.824721) (end 109.762832 78.796886) (width 0.109) (layer "In2.Cu") (net 80))
  (segment (start 121.127814 75.1725) (end 119.647186 75.1725) (width 0.109) (layer "In2.Cu") (net 80))
  (segment (start 109.808401 78.891512) (end 109.800479 78.856801) (width 0.109) (layer "In2.Cu") (net 80))
  (segment (start 109.800479 78.856801) (end 109.78503 78.824721) (width 0.109) (layer "In2.Cu") (net 80))
  (segment (start 109.800478 78.961829) (end 109.808402 78.927118) (width 0.109) (layer "In2.Cu") (net 80))
  (segment (start 109.668205 78.751315) (end 109.632599 78.751314) (width 0.109) (layer "In2.Cu") (net 80))
  (segment (start 109.669727 79.137117) (end 109.685174 79.105037) (width 0.109) (layer "In2.Cu") (net 80))
  (segment (start 109.669726 79.242145) (end 109.661804 79.207434) (width 0.109) (layer "In2.Cu") (net 80))
  (segment (start 109.707375 79.077201) (end 109.762831 79.021744) (width 0.109) (layer "In2.Cu") (net 80))
  (segment (start 109.4226 78.889989) (end 109.387889 78.897913) (width 0.109) (layer "In2.Cu") (net 80))
  (segment (start 109.352283 78.897912) (end 109.317572 78.88999) (width 0.109) (layer "In2.Cu") (net 80))
  (segment (start 109.661803 79.171828) (end 109.669727 79.137117) (width 0.109) (layer "In2.Cu") (net 80))
  (segment (start 109.661804 79.207434) (end 109.661803 79.171828) (width 0.109) (layer "In2.Cu") (net 80))
  (segment (start 109.808402 78.927118) (end 109.808401 78.891512) (width 0.109) (layer "In2.Cu") (net 80))
  (segment (start 109.378289 71.403499) (end 107.778288 71.403499) (width 0.182) (layer "B.Cu") (net 80))
  (segment (start 109.233933 76.833355) (end 109.839 76.228288) (width 0.182) (layer "B.Cu") (net 80))
  (segment (start 107.589 67.811971) (end 107.589 67.361) (width 0.182) (layer "B.Cu") (net 80))
  (segment (start 109.839 76.228288) (end 109.839 74.202251) (width 0.182) (layer "B.Cu") (net 80))
  (segment (start 109.9 72.875) (end 109.9 72.451249) (width 0.182) (layer "B.Cu") (net 80))
  (segment (start 109.839001 71.864211) (end 109.378289 71.403499) (width 0.182) (layer "B.Cu") (net 80))
  (segment (start 109.342933 77.637606) (end 109.233933 77.528606) (width 0.182) (layer "B.Cu") (net 80))
  (segment (start 107.778288 71.403499) (end 107.565813 71.191024) (width 0.182) (layer "B.Cu") (net 80))
  (segment (start 107.589 67.361) (end 107.67 67.28) (width 0.182) (layer "B.Cu") (net 80))
  (segment (start 108.139 69.528288) (end 108.139 68.361971) (width 0.182) (layer "B.Cu") (net 80))
  (segment (start 109.839 74.202251) (end 109.9 74.141251) (width 0.182) (layer "B.Cu") (net 80))
  (segment (start 108.139 68.361971) (end 107.589 67.811971) (width 0.182) (layer "B.Cu") (net 80))
  (segment (start 109.9 74.141251) (end 109.9 73.7175) (width 0.182) (layer "B.Cu") (net 80))
  (segment (start 107.565813 70.101475) (end 108.139 69.528288) (width 0.182) (layer "B.Cu") (net 80))
  (segment (start 109.233933 77.528606) (end 109.233933 76.833355) (width 0.182) (layer "B.Cu") (net 80))
  (segment (start 107.565813 71.191024) (end 107.565813 70.101475) (width 0.182) (layer "B.Cu") (net 80))
  (segment (start 109.9 72.451249) (end 109.839 72.390248) (width 0.182) (layer "B.Cu") (net 80))
  (segment (start 109.839 72.390248) (end 109.839001 71.864211) (width 0.182) (layer "B.Cu") (net 80))
  (segment (start 107.67 67.28) (end 108.4 67.28) (width 0.182) (layer "B.Cu") (net 80))
  (segment (start 109.9 72.913) (end 109.9 73.685) (width 0.182) (layer "B.Cu") (net 80))
  (segment (start 128.786243 75.613241) (end 128.756458 75.565839) (width 0.182) (layer "F.Cu") (net 81))
  (segment (start 128.669471 74.946954) (end 128.716873 74.917169) (width 0.182) (layer "F.Cu") (net 81))
  (segment (start 128.475967 75.465443) (end 128.423127 75.446954) (width 0.182) (layer "F.Cu") (net 81))
  (segment (start 128.811 75.721712) (end 128.804732 75.666081) (width 0.182) (layer "F.Cu") (net 81))
  (segment (start 128.669471 75.496469) (end 128.616631 75.47798) (width 0.182) (layer "F.Cu") (net 81))
  (segment (start 128.306355 75.330182) (end 128.287866 75.277342) (width 0.182) (layer "F.Cu") (net 81))
  (segment (start 128.375725 75.026254) (end 128.423127 74.996469) (width 0.182) (layer "F.Cu") (net 81))
  (segment (start 128.33614 75.065839) (end 128.375725 75.026254) (width 0.182) (layer "F.Cu") (net 81))
  (segment (start 128.804732 74.777342) (end 128.811 74.721712) (width 0.182) (layer "F.Cu") (net 81))
  (segment (start 127.437606 75.957067) (end 127.546607 76.066068) (width 0.182) (layer "F.Cu") (net 81))
  (segment (start 128.811 74.152251) (end 128.75 74.091251) (width 0.182) (layer "F.Cu") (net 81))
  (segment (start 127.546607 76.066068) (end 128.466644 76.066068) (width 0.182) (layer "F.Cu") (net 81))
  (segment (start 128.466644 76.066068) (end 128.811 75.721712) (width 0.182) (layer "F.Cu") (net 81))
  (segment (start 128.616631 74.965443) (end 128.669471 74.946954) (width 0.182) (layer "F.Cu") (net 81))
  (segment (start 128.281597 75.221712) (end 128.287866 75.166081) (width 0.182) (layer "F.Cu") (net 81))
  (segment (start 128.287866 75.277342) (end 128.281597 75.221712) (width 0.182) (layer "F.Cu") (net 81))
  (segment (start 128.306355 75.113241) (end 128.33614 75.065839) (width 0.182) (layer "F.Cu") (net 81))
  (segment (start 128.786243 74.830182) (end 128.804732 74.777342) (width 0.182) (layer "F.Cu") (net 81))
  (segment (start 128.531597 74.971712) (end 128.561 74.971712) (width 0.182) (layer "F.Cu") (net 81))
  (segment (start 128.375725 75.417169) (end 128.33614 75.377584) (width 0.182) (layer "F.Cu") (net 81))
  (segment (start 128.287866 75.166081) (end 128.306355 75.113241) (width 0.182) (layer "F.Cu") (net 81))
  (segment (start 128.561 75.471712) (end 128.531597 75.471712) (width 0.182) (layer "F.Cu") (net 81))
  (segment (start 128.475967 74.97798) (end 128.531597 74.971712) (width 0.182) (layer "F.Cu") (net 81))
  (segment (start 128.756458 75.565839) (end 128.716873 75.526254) (width 0.182) (layer "F.Cu") (net 81))
  (segment (start 128.756458 74.877584) (end 128.786243 74.830182) (width 0.182) (layer "F.Cu") (net 81))
  (segment (start 128.423127 74.996469) (end 128.475967 74.97798) (width 0.182) (layer "F.Cu") (net 81))
  (segment (start 128.716873 75.526254) (end 128.669471 75.496469) (width 0.182) (layer "F.Cu") (net 81))
  (segment (start 128.811 74.721712) (end 128.811 74.152251) (width 0.182) (layer "F.Cu") (net 81))
  (segment (start 128.804732 75.666081) (end 128.786243 75.613241) (width 0.182) (layer "F.Cu") (net 81))
  (segment (start 128.616631 75.47798) (end 128.561 75.471712) (width 0.182) (layer "F.Cu") (net 81))
  (segment (start 128.33614 75.377584) (end 128.306355 75.330182) (width 0.182) (layer "F.Cu") (net 81))
  (segment (start 128.561 74.971712) (end 128.616631 74.965443) (width 0.182) (layer "F.Cu") (net 81))
  (segment (start 128.423127 75.446954) (end 128.375725 75.417169) (width 0.182) (layer "F.Cu") (net 81))
  (segment (start 128.531597 75.471712) (end 128.475967 75.465443) (width 0.182) (layer "F.Cu") (net 81))
  (segment (start 128.716873 74.917169) (end 128.756458 74.877584) (width 0.182) (layer "F.Cu") (net 81))
  (segment (start 128.571712 71.738999) (end 128.811 71.978288) (width 0.182) (layer "F.Cu") (net 81))
  (segment (start 128.811 72.347748) (end 128.75 72.408748) (width 0.182) (layer "F.Cu") (net 81))
  (segment (start 128.75 72.408748) (end 128.75 72.832499) (width 0.182) (layer "F.Cu") (net 81))
  (segment (start 126.430001 70.43) (end 126.561001 70.561) (width 0.182) (layer "F.Cu") (net 81))
  (segment (start 125.75 70.43) (end 126.430001 70.43) (width 0.182) (layer "F.Cu") (net 81))
  (segment (start 128.811 71.978288) (end 128.811 72.347748) (width 0.182) (layer "F.Cu") (net 81))
  (segment (start 126.561001 70.561) (end 126.561 71.328288) (width 0.182) (layer "F.Cu") (net 81))
  (segment (start 126.561 71.328288) (end 126.971712 71.739) (width 0.182) (layer "F.Cu") (net 81))
  (segment (start 126.971712 71.739) (end 128.571712 71.738999) (width 0.182) (layer "F.Cu") (net 81))
  (segment (start 128.75 73.6675) (end 128.75 74.091251) (width 0.182) (layer "F.Cu") (net 81))
  (segment (start 124.023533 76.82) (end 124.132533 76.929) (width 0.182) (layer "F.Cu") (net 81))
  (segment (start 124.023532 76.82) (end 124.023533 76.82) (width 0.182) (layer "F.Cu") (net 81))
  (segment (start 128.752 72.8955) (end 128.752 73.6675) (width 0.182) (layer "F.Cu") (net 81))
  (segment (start 124.132533 76.929) (end 124.132533 78.732471) (width 0.182) (layer "F.Cu") (net 81))
  (via (at 124.023532 76.82) (size 0.45) (drill 0.1) (layers "F.Cu" "B.Cu") (net 81))
  (via (at 127.437606 75.957067) (size 0.45) (drill 0.1) (layers "F.Cu" "B.Cu") (net 81))
  (segment (start 126.5275 75.722186) (end 126.5275 74.247186) (width 0.109) (layer "In6.Cu") (net 81))
  (segment (start 123.7725 74.377186) (end 123.7725 75.452814) (width 0.109) (layer "In6.Cu") (net 81))
  (segment (start 123.7725 75.452814) (end 124.194033 75.874347) (width 0.109) (layer "In6.Cu") (net 81))
  (segment (start 126.932881 76.127567) (end 126.5275 75.722186) (width 0.109) (layer "In6.Cu") (net 81))
  (segment (start 126.5275 74.247186) (end 126.240314 73.96) (width 0.109) (layer "In6.Cu") (net 81))
  (segment (start 124.194033 76.6495) (end 124.023533 76.82) (width 0.109) (layer "In6.Cu") (net 81))
  (segment (start 124.023533 76.82) (end 124.023532 76.82) (width 0.109) (layer "In6.Cu") (net 81))
  (segment (start 124.189686 73.96) (end 123.7725 74.377186) (width 0.109) (layer "In6.Cu") (net 81))
  (segment (start 127.437606 75.957067) (end 127.267106 76.127567) (width 0.109) (layer "In6.Cu") (net 81))
  (segment (start 126.240314 73.96) (end 124.189686 73.96) (width 0.109) (layer "In6.Cu") (net 81))
  (segment (start 124.194033 75.874347) (end 124.194033 76.6495) (width 0.109) (layer "In6.Cu") (net 81))
  (segment (start 127.267106 76.127567) (end 126.932881 76.127567) (width 0.109) (layer "In6.Cu") (net 81))
  (segment (start 129.189 74.152251) (end 129.189 75.878288) (width 0.182) (layer "F.Cu") (net 82))
  (segment (start 129.25 74.091251) (end 129.189 74.152251) (width 0.182) (layer "F.Cu") (net 82))
  (segment (start 128.62322 76.444068) (end 127.546607 76.444068) (width 0.182) (layer "F.Cu") (net 82))
  (segment (start 129.189 75.878288) (end 128.62322 76.444068) (width 0.182) (layer "F.Cu") (net 82))
  (segment (start 129.25 73.6675) (end 129.25 74.091251) (width 0.182) (layer "F.Cu") (net 82))
  (segment (start 127.546607 76.444068) (end 127.437607 76.553068) (width 0.182) (layer "F.Cu") (net 82))
  (segment (start 126.939 70.561) (end 126.939 71.171711) (width 0.182) (layer "F.Cu") (net 82))
  (segment (start 127.128288 71.360999) (end 128.728289 71.360999) (width 0.182) (layer "F.Cu") (net 82))
  (segment (start 129.25 72.408749) (end 129.25 72.8325) (width 0.182) (layer "F.Cu") (net 82))
  (segment (start 128.728289 71.360999) (end 129.189001 71.821711) (width 0.182) (layer "F.Cu") (net 82))
  (segment (start 129.189001 71.821711) (end 129.189 72.347748) (width 0.182) (layer "F.Cu") (net 82))
  (segment (start 129.189 72.347748) (end 129.25 72.408749) (width 0.182) (layer "F.Cu") (net 82))
  (segment (start 127.75 70.429999) (end 127.07 70.43) (width 0.182) (layer "F.Cu") (net 82))
  (segment (start 126.939 71.171711) (end 127.128288 71.360999) (width 0.182) (layer "F.Cu") (net 82))
  (segment (start 127.07 70.43) (end 126.939 70.561) (width 0.182) (layer "F.Cu") (net 82))
  (segment (start 124.510533 76.929) (end 124.510533 78.737652) (width 0.182) (layer "F.Cu") (net 82))
  (segment (start 124.619533 76.82) (end 124.510533 76.929) (width 0.182) (layer "F.Cu") (net 82))
  (segment (start 129.252 72.8955) (end 129.252 73.6675) (width 0.182) (layer "F.Cu") (net 82))
  (via (at 124.619533 76.82) (size 0.45) (drill 0.1) (layers "F.Cu" "B.Cu") (net 82))
  (via (at 127.437607 76.553068) (size 0.45) (drill 0.1) (layers "F.Cu" "B.Cu") (net 82))
  (segment (start 124.624722 74.260143) (end 124.653856 74.289277) (width 0.109) (layer "In6.Cu") (net 82))
  (segment (start 124.550943 74.224613) (end 124.589834 74.238221) (width 0.109) (layer "In6.Cu") (net 82))
  (segment (start 126.139686 74.22) (end 126.2725 74.352814) (width 0.109) (layer "In6.Cu") (net 82))
  (segment (start 124.694 74.404) (end 124.694 74.405895) (width 0.109) (layer "In6.Cu") (net 82))
  (segment (start 124.918943 74.585281) (end 124.957834 74.571673) (width 0.109) (layer "In6.Cu") (net 82))
  (segment (start 125.062 74.405895) (end 125.062 74.404) (width 0.109) (layer "In6.Cu") (net 82))
  (segment (start 125.166165 74.238221) (end 125.205056 74.224613) (width 0.109) (layer "In6.Cu") (net 82))
  (segment (start 125.062 74.404) (end 125.066613 74.363056) (width 0.109) (layer "In6.Cu") (net 82))
  (segment (start 126.827253 76.382567) (end 127.267106 76.382567) (width 0.109) (layer "In6.Cu") (net 82))
  (segment (start 124.619533 76.82) (end 124.449033 76.6495) (width 0.109) (layer "In6.Cu") (net 82))
  (segment (start 124.734143 74.520617) (end 124.763277 74.549751) (width 0.109) (layer "In6.Cu") (net 82))
  (segment (start 124.763277 74.549751) (end 124.798165 74.571673) (width 0.109) (layer "In6.Cu") (net 82))
  (segment (start 124.0275 74.482814) (end 124.290314 74.22) (width 0.109) (layer "In6.Cu") (net 82))
  (segment (start 124.653856 74.289277) (end 124.675778 74.324165) (width 0.109) (layer "In6.Cu") (net 82))
  (segment (start 126.2725 74.352814) (end 126.2725 75.827814) (width 0.109) (layer "In6.Cu") (net 82))
  (segment (start 125.080221 74.324165) (end 125.102143 74.289277) (width 0.109) (layer "In6.Cu") (net 82))
  (segment (start 124.992722 74.549751) (end 125.021856 74.520617) (width 0.109) (layer "In6.Cu") (net 82))
  (segment (start 125.131277 74.260143) (end 125.166165 74.238221) (width 0.109) (layer "In6.Cu") (net 82))
  (segment (start 124.689386 74.363056) (end 124.694 74.404) (width 0.109) (layer "In6.Cu") (net 82))
  (segment (start 124.837056 74.585281) (end 124.878 74.589895) (width 0.109) (layer "In6.Cu") (net 82))
  (segment (start 125.043778 74.485729) (end 125.057386 74.446838) (width 0.109) (layer "In6.Cu") (net 82))
  (segment (start 125.246 74.22) (end 126.139686 74.22) (width 0.109) (layer "In6.Cu") (net 82))
  (segment (start 124.449033 76.6495) (end 124.449033 75.768719) (width 0.109) (layer "In6.Cu") (net 82))
  (segment (start 124.290314 74.22) (end 124.51 74.22) (width 0.109) (layer "In6.Cu") (net 82))
  (segment (start 124.0275 75.347186) (end 124.0275 74.482814) (width 0.109) (layer "In6.Cu") (net 82))
  (segment (start 124.798165 74.571673) (end 124.837056 74.585281) (width 0.109) (layer "In6.Cu") (net 82))
  (segment (start 124.698613 74.446838) (end 124.712221 74.485729) (width 0.109) (layer "In6.Cu") (net 82))
  (segment (start 124.712221 74.485729) (end 124.734143 74.520617) (width 0.109) (layer "In6.Cu") (net 82))
  (segment (start 125.057386 74.446838) (end 125.062 74.405895) (width 0.109) (layer "In6.Cu") (net 82))
  (segment (start 124.51 74.22) (end 124.550943 74.224613) (width 0.109) (layer "In6.Cu") (net 82))
  (segment (start 127.267106 76.382567) (end 127.437607 76.553068) (width 0.109) (layer "In6.Cu") (net 82))
  (segment (start 124.589834 74.238221) (end 124.624722 74.260143) (width 0.109) (layer "In6.Cu") (net 82))
  (segment (start 126.2725 75.827814) (end 126.827253 76.382567) (width 0.109) (layer "In6.Cu") (net 82))
  (segment (start 125.021856 74.520617) (end 125.043778 74.485729) (width 0.109) (layer "In6.Cu") (net 82))
  (segment (start 124.878 74.589895) (end 124.918943 74.585281) (width 0.109) (layer "In6.Cu") (net 82))
  (segment (start 124.694 74.405895) (end 124.698613 74.446838) (width 0.109) (layer "In6.Cu") (net 82))
  (segment (start 125.066613 74.363056) (end 125.080221 74.324165) (width 0.109) (layer "In6.Cu") (net 82))
  (segment (start 125.205056 74.224613) (end 125.246 74.22) (width 0.109) (layer "In6.Cu") (net 82))
  (segment (start 124.675778 74.324165) (end 124.689386 74.363056) (width 0.109) (layer "In6.Cu") (net 82))
  (segment (start 125.102143 74.289277) (end 125.131277 74.260143) (width 0.109) (layer "In6.Cu") (net 82))
  (segment (start 124.449033 75.768719) (end 124.0275 75.347186) (width 0.109) (layer "In6.Cu") (net 82))
  (segment (start 124.957834 74.571673) (end 124.992722 74.549751) (width 0.109) (layer "In6.Cu") (net 82))
  (segment (start 128.322343 85.34586) (end 128.506573 85.34586) (width 0.182) (layer "F.Cu") (net 83))
  (segment (start 128.311342 85.334859) (end 128.322343 85.34586) (width 0.182) (layer "F.Cu") (net 83))
  (segment (start 128.697514 85.154919) (end 129.644804 85.154919) (width 0.182) (layer "F.Cu") (net 83))
  (segment (start 128.506573 85.34586) (end 128.697514 85.154919) (width 0.182) (layer "F.Cu") (net 83))
  (segment (start 127.907742 85.334859) (end 128.311342 85.334859) (width 0.182) (layer "F.Cu") (net 83))
  (segment (start 129.753803 85.045919) (end 129.644804 85.154919) (width 0.182) (layer "F.Cu") (net 83))
  (via (at 129.753803 85.045918) (size 0.45) (drill 0.1) (layers "F.Cu" "B.Cu") (net 83))
  (via (at 128.103999 77.600001) (size 0.45) (drill 0.1) (layers "F.Cu" "B.Cu") (net 83))
  (segment (start 130.54668 84.607859) (end 130.53366 84.634893) (width 0.109) (layer "In2.Cu") (net 83))
  (segment (start 128.274499 78.074813) (end 130.079843 79.880155) (width 0.109) (layer "In2.Cu") (net 83))
  (segment (start 130.880087 84.668248) (end 130.850833 84.661571) (width 0.109) (layer "In2.Cu") (net 83))
  (segment (start 130.526983 84.694154) (end 130.53366 84.723408) (width 0.109) (layer "In2.Cu") (net 83))
  (segment (start 130.731434 84.56569) (end 130.704399 84.552671) (width 0.109) (layer "In2.Cu") (net 83))
  (segment (start 131.838184 80.101707) (end 131.869248 80.140661) (width 0.109) (layer "In2.Cu") (net 83))
  (segment (start 130.526983 84.664148) (end 130.526983 84.694154) (width 0.109) (layer "In2.Cu") (net 83))
  (segment (start 130.132526 80.110973) (end 130.110908 80.155863) (width 0.109) (layer "In2.Cu") (net 83))
  (segment (start 131.6475 83.972186) (end 130.989843 84.629843) (width 0.109) (layer "In2.Cu") (net 83))
  (segment (start 129.680385 80.954474) (end 129.724098 81.045245) (width 0.109) (layer "In2.Cu") (net 83))
  (segment (start 130.939348 84.661571) (end 130.910093 84.668248) (width 0.109) (layer "In2.Cu") (net 83))
  (segment (start 129.657967 80.856253) (end 129.680385 80.954474) (width 0.109) (layer "In2.Cu") (net 83))
  (segment (start 130.64256 84.869841) (end 130.649237 84.899095) (width 0.109) (layer "In2.Cu") (net 83))
  (segment (start 130.675145 84.545994) (end 130.645138 84.545994) (width 0.109) (layer "In2.Cu") (net 83))
  (segment (start 131.799229 80.070642) (end 131.838184 80.101707) (width 0.109) (layer "In2.Cu") (net 83))
  (segment (start 129.825933 81.163033) (end 129.9047 81.225848) (width 0.109) (layer "In2.Cu") (net 83))
  (segment (start 130.966382 84.648551) (end 130.939348 84.661571) (width 0.109) (layer "In2.Cu") (net 83))
  (segment (start 131.890866 80.185551) (end 131.901953 80.234126) (width 0.109) (layer "In2.Cu") (net 83))
  (segment (start 130.850833 84.661571) (end 130.823798 84.648551) (width 0.109) (layer "In2.Cu") (net 83))
  (segment (start 130.403267 85.216419) (end 129.924303 85.216419) (width 0.109) (layer "In2.Cu") (net 83))
  (segment (start 131.545253 81.345563) (end 131.6475 81.447813) (width 0.109) (layer "In2.Cu") (net 83))
  (segment (start 130.132526 79.963999) (end 130.143613 80.012574) (width 0.109) (layer "In2.Cu") (net 83))
  (segment (start 131.65594 80.037937) (end 131.705764 80.037937) (width 0.109) (layer "In2.Cu") (net 83))
  (segment (start 130.565389 84.773903) (end 130.610832 84.819346) (width 0.109) (layer "In2.Cu") (net 83))
  (segment (start 131.562475 80.070642) (end 131.607365 80.049024) (width 0.109) (layer "In2.Cu") (net 83))
  (segment (start 131.869248 80.140661) (end 131.890866 80.185551) (width 0.109) (layer "In2.Cu") (net 83))
  (segment (start 130.143613 80.012574) (end 130.143613 80.062398) (width 0.109) (layer "In2.Cu") (net 83))
  (segment (start 128.274499 77.770501) (end 128.274499 78.074813) (width 0.109) (layer "In2.Cu") (net 83))
  (segment (start 131.6475 81.447813) (end 131.6475 83.972186) (width 0.109) (layer "In2.Cu") (net 83))
  (segment (start 131.890866 80.332525) (end 131.869248 80.377415) (width 0.109) (layer "In2.Cu") (net 83))
  (segment (start 131.52352 80.101706) (end 131.562475 80.070642) (width 0.109) (layer "In2.Cu") (net 83))
  (segment (start 130.645138 84.545994) (end 130.615884 84.552671) (width 0.109) (layer "In2.Cu") (net 83))
  (segment (start 130.754894 84.584399) (end 130.731434 84.56569) (width 0.109) (layer "In2.Cu") (net 83))
  (segment (start 131.416308 81.077805) (end 131.438725 81.176025) (width 0.109) (layer "In2.Cu") (net 83))
  (segment (start 131.901953 80.28395) (end 131.890866 80.332525) (width 0.109) (layer "In2.Cu") (net 83))
  (segment (start 128.103999 77.600001) (end 128.274499 77.770501) (width 0.109) (layer "In2.Cu") (net 83))
  (segment (start 130.588849 84.56569) (end 130.565389 84.584399) (width 0.109) (layer "In2.Cu") (net 83))
  (segment (start 131.705764 80.037937) (end 131.754339 80.049024) (width 0.109) (layer "In2.Cu") (net 83))
  (segment (start 130.079843 80.194817) (end 129.786913 80.487746) (width 0.109) (layer "In2.Cu") (net 83))
  (segment (start 129.924303 85.216419) (end 129.753803 85.045919) (width 0.109) (layer "In2.Cu") (net 83))
  (segment (start 131.869248 80.377415) (end 131.838184 80.416369) (width 0.109) (layer "In2.Cu") (net 83))
  (segment (start 130.64256 84.958356) (end 130.629541 84.985391) (width 0.109) (layer "In2.Cu") (net 83))
  (segment (start 131.754339 80.049024) (end 131.799229 80.070642) (width 0.109) (layer "In2.Cu") (net 83))
  (segment (start 130.292661 81.26956) (end 130.383432 81.225848) (width 0.109) (layer "In2.Cu") (net 83))
  (segment (start 130.823798 84.648551) (end 130.800338 84.629843) (width 0.109) (layer "In2.Cu") (net 83))
  (segment (start 131.482438 80.788064) (end 131.438725 80.878835) (width 0.109) (layer "In2.Cu") (net 83))
  (segment (start 130.093692 81.291979) (end 130.19444 81.291979) (width 0.109) (layer "In2.Cu") (net 83))
  (segment (start 130.615884 84.552671) (end 130.588849 84.56569) (width 0.109) (layer "In2.Cu") (net 83))
  (segment (start 130.110908 79.919109) (end 130.132526 79.963999) (width 0.109) (layer "In2.Cu") (net 83))
  (segment (start 130.649237 84.929102) (end 130.64256 84.958356) (width 0.109) (layer "In2.Cu") (net 83))
  (segment (start 131.545253 80.709297) (end 131.482438 80.788064) (width 0.109) (layer "In2.Cu") (net 83))
  (segment (start 130.383432 81.225848) (end 130.462199 81.163033) (width 0.109) (layer "In2.Cu") (net 83))
  (segment (start 130.403267 85.216419) (end 130.610833 85.008852) (width 0.109) (layer "In2.Cu") (net 83))
  (segment (start 129.786913 81.124012) (end 129.825933 81.163033) (width 0.109) (layer "In2.Cu") (net 83))
  (segment (start 130.143613 80.062398) (end 130.132526 80.110973) (width 0.109) (layer "In2.Cu") (net 83))
  (segment (start 129.724098 81.045245) (end 129.786913 81.124012) (width 0.109) (layer "In2.Cu") (net 83))
  (segment (start 130.53366 84.723408) (end 130.54668 84.750443) (width 0.109) (layer "In2.Cu") (net 83))
  (segment (start 131.838184 80.416369) (end 131.545253 80.709297) (width 0.109) (layer "In2.Cu") (net 83))
  (segment (start 129.9047 81.225848) (end 129.995471 81.26956) (width 0.109) (layer "In2.Cu") (net 83))
  (segment (start 131.250101 80.375125) (end 131.52352 80.101706) (width 0.109) (layer "In2.Cu") (net 83))
  (segment (start 129.724098 80.566513) (end 129.680385 80.657284) (width 0.109) (layer "In2.Cu") (net 83))
  (segment (start 131.438725 81.176025) (end 131.482438 81.266796) (width 0.109) (layer "In2.Cu") (net 83))
  (segment (start 130.19444 81.291979) (end 130.292661 81.26956) (width 0.109) (layer "In2.Cu") (net 83))
  (segment (start 130.989843 84.629843) (end 130.966382 84.648551) (width 0.109) (layer "In2.Cu") (net 83))
  (segment (start 129.995471 81.26956) (end 130.093692 81.291979) (width 0.109) (layer "In2.Cu") (net 83))
  (segment (start 131.482438 81.266796) (end 131.545253 81.345563) (width 0.109) (layer "In2.Cu") (net 83))
  (segment (start 130.53366 84.634893) (end 130.526983 84.664148) (width 0.109) (layer "In2.Cu") (net 83))
  (segment (start 131.438725 80.878835) (end 131.416308 80.977057) (width 0.109) (layer "In2.Cu") (net 83))
  (segment (start 130.54668 84.750443) (end 130.565389 84.773903) (width 0.109) (layer "In2.Cu") (net 83))
  (segment (start 131.002615 80.622616) (end 131.250101 80.375125) (width 0.109) (layer "In2.Cu") (net 83))
  (segment (start 130.704399 84.552671) (end 130.675145 84.545994) (width 0.109) (layer "In2.Cu") (net 83))
  (segment (start 130.610832 84.819346) (end 130.629541 84.842806) (width 0.109) (layer "In2.Cu") (net 83))
  (segment (start 131.901953 80.234126) (end 131.901953 80.28395) (width 0.109) (layer "In2.Cu") (net 83))
  (segment (start 130.629541 84.985391) (end 130.610833 85.008852) (width 0.109) (layer "In2.Cu") (net 83))
  (segment (start 130.649237 84.899095) (end 130.649237 84.929102) (width 0.109) (layer "In2.Cu") (net 83))
  (segment (start 131.607365 80.049024) (end 131.65594 80.037937) (width 0.109) (layer "In2.Cu") (net 83))
  (segment (start 130.910093 84.668248) (end 130.880087 84.668248) (width 0.109) (layer "In2.Cu") (net 83))
  (segment (start 130.110908 80.155863) (end 130.079843 80.194817) (width 0.109) (layer "In2.Cu") (net 83))
  (segment (start 130.462199 81.163033) (end 131.002615 80.622616) (width 0.109) (layer "In2.Cu") (net 83))
  (segment (start 129.786913 80.487746) (end 129.724098 80.566513) (width 0.109) (layer "In2.Cu") (net 83))
  (segment (start 130.629541 84.842806) (end 130.64256 84.869841) (width 0.109) (layer "In2.Cu") (net 83))
  (segment (start 129.680385 80.657284) (end 129.657967 80.755505) (width 0.109) (layer "In2.Cu") (net 83))
  (segment (start 129.753803 85.045919) (end 129.753803 85.045918) (width 0.109) (layer "In2.Cu") (net 83))
  (segment (start 131.416308 80.977057) (end 131.416308 81.077805) (width 0.109) (layer "In2.Cu") (net 83))
  (segment (start 130.079843 79.880155) (end 130.110908 79.919109) (width 0.109) (layer "In2.Cu") (net 83))
  (segment (start 129.657967 80.755505) (end 129.657967 80.856253) (width 0.109) (layer "In2.Cu") (net 83))
  (segment (start 130.565389 84.584399) (end 130.54668 84.607859) (width 0.109) (layer "In2.Cu") (net 83))
  (segment (start 130.800338 84.629843) (end 130.754894 84.584399) (width 0.109) (layer "In2.Cu") (net 83))
  (segment (start 128.811001 74.16975) (end 128.750001 74.10875) (width 0.182) (layer "B.Cu") (net 83))
  (segment (start 128.205934 77.496105) (end 128.205934 76.644278) (width 0.182) (layer "B.Cu") (net 83))
  (segment (start 128.205934 76.644278) (end 128.811001 76.039211) (width 0.182) (layer "B.Cu") (net 83))
  (segment (start 128.750001 74.10875) (end 128.750001 73.684999) (width 0.182) (layer "B.Cu") (net 83))
  (segment (start 128.811001 76.039211) (end 128.811001 74.16975) (width 0.182) (layer "B.Cu") (net 83))
  (segment (start 126.971712 71.7315) (end 126.537813 71.297601) (width 0.182) (layer "B.Cu") (net 83))
  (segment (start 126.537813 69.894899) (end 127.111 69.321712) (width 0.182) (layer "B.Cu") (net 83))
  (segment (start 126.537813 71.297601) (end 126.537813 69.894899) (width 0.182) (layer "B.Cu") (net 83))
  (segment (start 126.43 67.23) (end 126.561 67.361) (width 0.182) (layer "B.Cu") (net 83))
  (segment (start 126.561 67.918547) (end 127.111 68.468547) (width 0.182) (layer "B.Cu") (net 83))
  (segment (start 126.971712 71.7315) (end 128.571712 71.731499) (width 0.182) (layer "B.Cu") (net 83))
  (segment (start 128.75 72.401248) (end 128.75 72.824999) (width 0.182) (layer "B.Cu") (net 83))
  (segment (start 128.811 71.970788) (end 128.811 72.340248) (width 0.182) (layer "B.Cu") (net 83))
  (segment (start 128.571712 71.731499) (end 128.811 71.970788) (width 0.182) (layer "B.Cu") (net 83))
  (segment (start 126.561 67.361) (end 126.561 67.918547) (width 0.182) (layer "B.Cu") (net 83))
  (segment (start 128.811 72.340248) (end 128.75 72.401248) (width 0.182) (layer "B.Cu") (net 83))
  (segment (start 127.111 68.468547) (end 127.111 69.321712) (width 0.182) (layer "B.Cu") (net 83))
  (segment (start 125.75 67.23) (end 126.43 67.23) (width 0.182) (layer "B.Cu") (net 83))
  (segment (start 128.103999 77.600001) (end 128.205934 77.496105) (width 0.182) (layer "B.Cu") (net 83))
  (segment (start 128.75 72.863) (end 128.75 73.635) (width 0.182) (layer "B.Cu") (net 83))
  (segment (start 128.322343 85.72386) (end 128.663148 85.72386) (width 0.182) (layer "F.Cu") (net 84))
  (segment (start 129.753803 85.641919) (end 129.644803 85.532919) (width 0.182) (layer "F.Cu") (net 84))
  (segment (start 128.85409 85.532919) (end 129.644803 85.532919) (width 0.182) (layer "F.Cu") (net 84))
  (segment (start 127.907742 85.734861) (end 128.311342 85.734861) (width 0.182) (layer "F.Cu") (net 84))
  (segment (start 128.311342 85.734861) (end 128.322343 85.72386) (width 0.182) (layer "F.Cu") (net 84))
  (segment (start 128.663148 85.72386) (end 128.85409 85.532919) (width 0.182) (layer "F.Cu") (net 84))
  (via (at 129.753803 85.641919) (size 0.45) (drill 0.1) (layers "F.Cu" "B.Cu") (net 84))
  (via (at 128.7 77.6) (size 0.45) (drill 0.1) (layers "F.Cu" "B.Cu") (net 84))
  (segment (start 129.934054 80.879366) (end 129.955672 80.924256) (width 0.109) (layer "In2.Cu") (net 84))
  (segment (start 132.100821 80.498404) (end 132.038006 80.577171) (width 0.109) (layer "In2.Cu") (net 84))
  (segment (start 128.529499 77.770501) (end 128.529499 77.969185) (width 0.109) (layer "In2.Cu") (net 84))
  (segment (start 130.386194 79.888891) (end 130.408612 79.987112) (width 0.109) (layer "In2.Cu") (net 84))
  (segment (start 130.168979 81.026979) (end 130.217554 81.015892) (width 0.109) (layer "In2.Cu") (net 84))
  (segment (start 131.714011 80.909053) (end 131.692393 80.953943) (width 0.109) (layer "In2.Cu") (net 84))
  (segment (start 131.63048 79.77294) (end 131.731226 79.772939) (width 0.109) (layer "In2.Cu") (net 84))
  (segment (start 131.829448 79.795357) (end 131.920217 79.839069) (width 0.109) (layer "In2.Cu") (net 84))
  (segment (start 130.386194 80.186081) (end 130.342481 80.276852) (width 0.109) (layer "In2.Cu") (net 84))
  (segment (start 130.822304 80.442303) (end 130.822302 80.442301) (width 0.109) (layer "In2.Cu") (net 84))
  (segment (start 130.822302 80.442301) (end 131.069791 80.194815) (width 0.109) (layer "In2.Cu") (net 84))
  (segment (start 131.441487 79.83907) (end 131.532258 79.795358) (width 0.109) (layer "In2.Cu") (net 84))
  (segment (start 131.681306 81.002518) (end 131.681306 81.052342) (width 0.109) (layer "In2.Cu") (net 84))
  (segment (start 132.038006 79.940905) (end 132.100821 80.019672) (width 0.109) (layer "In2.Cu") (net 84))
  (segment (start 131.745075 80.870099) (end 131.714011 80.909053) (width 0.109) (layer "In2.Cu") (net 84))
  (segment (start 129.922967 80.830791) (end 129.934054 80.879366) (width 0.109) (layer "In2.Cu") (net 84))
  (segment (start 130.342481 80.276852) (end 130.279666 80.355619) (width 0.109) (layer "In2.Cu") (net 84))
  (segment (start 131.692393 81.100917) (end 131.714011 81.145807) (width 0.109) (layer "In2.Cu") (net 84))
  (segment (start 130.408612 80.08786) (end 130.386194 80.186081) (width 0.109) (layer "In2.Cu") (net 84))
  (segment (start 129.955672 80.924256) (end 129.986736 80.96321) (width 0.109) (layer "In2.Cu") (net 84))
  (segment (start 131.9025 81.342186) (end 131.9025 84.077814) (width 0.109) (layer "In2.Cu") (net 84))
  (segment (start 132.166951 80.208663) (end 132.166951 80.309411) (width 0.109) (layer "In2.Cu") (net 84))
  (segment (start 131.692393 80.953943) (end 131.681306 81.002518) (width 0.109) (layer "In2.Cu") (net 84))
  (segment (start 131.9025 84.077814) (end 130.508895 85.471419) (width 0.109) (layer "In2.Cu") (net 84))
  (segment (start 131.532258 79.795358) (end 131.63048 79.77294) (width 0.109) (layer "In2.Cu") (net 84))
  (segment (start 130.02569 80.994274) (end 130.07058 81.015892) (width 0.109) (layer "In2.Cu") (net 84))
  (segment (start 132.100821 80.019672) (end 132.144532 80.110442) (width 0.109) (layer "In2.Cu") (net 84))
  (segment (start 132.038006 80.577171) (end 132.018496 80.596681) (width 0.109) (layer "In2.Cu") (net 84))
  (segment (start 129.924303 85.471419) (end 129.753803 85.641919) (width 0.109) (layer "In2.Cu") (net 84))
  (segment (start 130.262444 80.994274) (end 130.301398 80.96321) (width 0.109) (layer "In2.Cu") (net 84))
  (segment (start 131.681306 81.052342) (end 131.692393 81.100917) (width 0.109) (layer "In2.Cu") (net 84))
  (segment (start 131.998986 79.901885) (end 132.038006 79.940905) (width 0.109) (layer "In2.Cu") (net 84))
  (segment (start 129.986736 80.96321) (end 130.02569 80.994274) (width 0.109) (layer "In2.Cu") (net 84))
  (segment (start 130.119155 81.026979) (end 130.168979 81.026979) (width 0.109) (layer "In2.Cu") (net 84))
  (segment (start 131.745075 81.184761) (end 131.9025 81.342186) (width 0.109) (layer "In2.Cu") (net 84))
  (segment (start 128.7 77.6) (end 128.529499 77.770501) (width 0.109) (layer "In2.Cu") (net 84))
  (segment (start 129.986736 80.648548) (end 129.955672 80.687502) (width 0.109) (layer "In2.Cu") (net 84))
  (segment (start 132.018496 80.596681) (end 131.745075 80.870099) (width 0.109) (layer "In2.Cu") (net 84))
  (segment (start 131.920217 79.839069) (end 131.998986 79.901885) (width 0.109) (layer "In2.Cu") (net 84))
  (segment (start 129.934054 80.732392) (end 129.922967 80.780967) (width 0.109) (layer "In2.Cu") (net 84))
  (segment (start 132.144532 80.110442) (end 132.166951 80.208663) (width 0.109) (layer "In2.Cu") (net 84))
  (segment (start 130.217554 81.015892) (end 130.262444 80.994274) (width 0.109) (layer "In2.Cu") (net 84))
  (segment (start 130.279666 80.355619) (end 129.986736 80.648548) (width 0.109) (layer "In2.Cu") (net 84))
  (segment (start 129.922967 80.780967) (end 129.922967 80.830791) (width 0.109) (layer "In2.Cu") (net 84))
  (segment (start 130.342481 79.79812) (end 130.386194 79.888891) (width 0.109) (layer "In2.Cu") (net 84))
  (segment (start 130.408612 79.987112) (end 130.408612 80.08786) (width 0.109) (layer "In2.Cu") (net 84))
  (segment (start 131.069791 80.194815) (end 131.36272 79.901886) (width 0.109) (layer "In2.Cu") (net 84))
  (segment (start 130.508895 85.471419) (end 129.924303 85.471419) (width 0.109) (layer "In2.Cu") (net 84))
  (segment (start 130.301398 80.96321) (end 130.822304 80.442303) (width 0.109) (layer "In2.Cu") (net 84))
  (segment (start 131.731226 79.772939) (end 131.829448 79.795357) (width 0.109) (layer "In2.Cu") (net 84))
  (segment (start 128.529499 77.969185) (end 130.279666 79.719353) (width 0.109) (layer "In2.Cu") (net 84))
  (segment (start 129.955672 80.687502) (end 129.934054 80.732392) (width 0.109) (layer "In2.Cu") (net 84))
  (segment (start 130.07058 81.015892) (end 130.119155 81.026979) (width 0.109) (layer "In2.Cu") (net 84))
  (segment (start 132.144532 80.407632) (end 132.100821 80.498404) (width 0.109) (layer "In2.Cu") (net 84))
  (segment (start 131.714011 81.145807) (end 131.745075 81.184761) (width 0.109) (layer "In2.Cu") (net 84))
  (segment (start 130.279666 79.719353) (end 130.342481 79.79812) (width 0.109) (layer "In2.Cu") (net 84))
  (segment (start 131.36272 79.901886) (end 131.441487 79.83907) (width 0.109) (layer "In2.Cu") (net 84))
  (segment (start 132.166951 80.309411) (end 132.144532 80.407632) (width 0.109) (layer "In2.Cu") (net 84))
  (segment (start 128.583934 76.800854) (end 129.189001 76.195787) (width 0.182) (layer "B.Cu") (net 84))
  (segment (start 129.189001 74.16975) (end 129.250001 74.10875) (width 0.182) (layer "B.Cu") (net 84))
  (segment (start 128.583934 77.496105) (end 128.583934 76.800854) (width 0.182) (layer "B.Cu") (net 84))
  (segment (start 129.189001 76.195787) (end 129.189001 74.16975) (width 0.182) (layer "B.Cu") (net 84))
  (segment (start 129.250001 74.10875) (end 129.250001 73.684999) (width 0.182) (layer "B.Cu") (net 84))
  (segment (start 127.02 67.23) (end 127.75 67.23) (width 0.182) (layer "B.Cu") (net 84))
  (segment (start 126.939 67.311) (end 127.02 67.23) (width 0.182) (layer "B.Cu") (net 84))
  (segment (start 127.128288 71.353499) (end 126.915813 71.141024) (width 0.182) (layer "B.Cu") (net 84))
  (segment (start 126.939 67.761971) (end 126.939 67.311) (width 0.182) (layer "B.Cu") (net 84))
  (segment (start 127.489 68.311971) (end 126.939 67.761971) (width 0.182) (layer "B.Cu") (net 84))
  (segment (start 129.25 72.401249) (end 129.189 72.340248) (width 0.182) (layer "B.Cu") (net 84))
  (segment (start 129.25 72.825) (end 129.25 72.401249) (width 0.182) (layer "B.Cu") (net 84))
  (segment (start 129.189001 71.814211) (end 128.728289 71.353499) (width 0.182) (layer "B.Cu") (net 84))
  (segment (start 128.728289 71.353499) (end 127.128288 71.353499) (width 0.182) (layer "B.Cu") (net 84))
  (segment (start 126.915813 71.141024) (end 126.915813 70.051475) (width 0.182) (layer "B.Cu") (net 84))
  (segment (start 126.915813 70.051475) (end 127.489 69.478288) (width 0.182) (layer "B.Cu") (net 84))
  (segment (start 127.489 69.478288) (end 127.489 68.311971) (width 0.182) (layer "B.Cu") (net 84))
  (segment (start 129.189 72.340248) (end 129.189001 71.814211) (width 0.182) (layer "B.Cu") (net 84))
  (segment (start 129.25 72.863) (end 129.25 73.635) (width 0.182) (layer "B.Cu") (net 84))
  (segment (start 128.7 77.6) (end 128.583934 77.496105) (width 0.182) (layer "B.Cu") (net 84))
  (segment (start 134.755001 73.524999) (end 136.000001 73.524999) (width 0.4) (layer "F.Cu") (net 85))
  (segment (start 132.559 74.041) (end 132.55 74.05) (width 0.182) (layer "F.Cu") (net 85))
  (segment (start 134.24 74.04) (end 134.755001 73.524999) (width 0.4) (layer "F.Cu") (net 85))
  (segment (start 136.6 72.925) (end 138.015 72.925) (width 0.4) (layer "F.Cu") (net 85))
  (segment (start 136.000001 73.524999) (end 136.6 72.925) (width 0.4) (layer "F.Cu") (net 85))
  (segment (start 132.559 73.473) (end 132.559 74.041) (width 0.182) (layer "F.Cu") (net 85))
  (via (at 134.24 74.04) (size 0.45) (drill 0.1) (layers "F.Cu" "B.Cu") (net 85))
  (via (at 132.56 74.1) (size 0.45) (drill 0.1) (layers "F.Cu" "B.Cu") (net 85))
  (segment (start 134.04 72.54) (end 132.775 71.275) (width 0.4) (layer "In4.Cu") (net 85))
  (segment (start 133.74 73.43) (end 134.04 73.13) (width 0.4) (layer "In4.Cu") (net 85))
  (segment (start 133.74 73.98) (end 133.74 73.43) (width 0.4) (layer "In4.Cu") (net 85))
  (segment (start 133.85 74.09) (end 133.74 73.98) (width 0.4) (layer "In4.Cu") (net 85))
  (segment (start 132.775 71.275) (end 132.775 69.405) (width 0.4) (layer "In4.Cu") (net 85))
  (segment (start 132.56 74.1) (end 134.18 74.1) (width 0.4) (layer "In4.Cu") (net 85))
  (segment (start 134.18 74.1) (end 134.24 74.04) (width 0.4) (layer "In4.Cu") (net 85))
  (segment (start 134.04 73.13) (end 134.04 72.54) (width 0.4) (layer "In4.Cu") (net 85))
  (segment (start 132.775 69.405) (end 133.25 68.93) (width 0.4) (layer "In4.Cu") (net 85))
  (segment (start 137.265 65.65) (end 137.265 66.55) (width 0.4) (layer "B.Cu") (net 85))
  (segment (start 137.265 67.45) (end 135.7 67.45) (width 0.4) (layer "B.Cu") (net 85))
  (segment (start 135.7 67.45) (end 134.22 68.93) (width 0.4) (layer "B.Cu") (net 85))
  (segment (start 134.22 68.93) (end 133.25 68.93) (width 0.4) (layer "B.Cu") (net 85))
  (segment (start 137.265 66.55) (end 137.265 67.45) (width 0.4) (layer "B.Cu") (net 85))
  (segment (start 116.244428 74.095572) (end 116.915572 74.095572) (width 0.4) (layer "F.Cu") (net 86))
  (segment (start 116.915572 74.095572) (end 117.244 74.424) (width 0.4) (layer "F.Cu") (net 86))
  (segment (start 116.244428 74.095572) (end 115.723449 74.095572) (width 0.4) (layer "F.Cu") (net 86))
  (segment (start 117.244 74.424) (end 118.169 74.424) (width 0.4) (layer "F.Cu") (net 86))
  (via (at 116.244428 74.095572) (size 0.45) (drill 0.1) (layers "F.Cu" "B.Cu") (net 86))
  (via (at 115.723449 74.095572) (size 0.45) (drill 0.1) (layers "F.Cu" "B.Cu") (net 86))
  (segment (start 115.723449 73.520572) (end 115.723449 74.088571) (width 0.182) (layer "B.Cu") (net 86))
  (segment (start 112.05 64.285) (end 112.95 64.285) (width 0.4) (layer "B.Cu") (net 86))
  (segment (start 113.9 65.78) (end 113.9 64.435001) (width 0.4) (layer "B.Cu") (net 86))
  (segment (start 113.9 64.335001) (end 113.849999 64.285) (width 0.4) (layer "B.Cu") (net 86))
  (segment (start 112.95 64.285) (end 113.849999 64.285) (width 0.4) (layer "B.Cu") (net 86))
  (segment (start 113.189 74.085) (end 113.18 74.094) (width 0.182) (layer "F.Cu") (net 87))
  (segment (start 113.189 73.517) (end 113.189 74.085) (width 0.182) (layer "F.Cu") (net 87))
  (segment (start 116.97 73.4) (end 117.343 73.773) (width 0.4) (layer "F.Cu") (net 87))
  (segment (start 117.343 73.773) (end 118.169 73.773) (width 0.4) (layer "F.Cu") (net 87))
  (segment (start 114.7 73.4) (end 116.97 73.4) (width 0.4) (layer "F.Cu") (net 87))
  (segment (start 113.9 74.2) (end 114.7 73.4) (width 0.4) (layer "F.Cu") (net 87))
  (segment (start 113.18 74.094) (end 113.286 74.2) (width 0.4) (layer "F.Cu") (net 87))
  (segment (start 113.286 74.2) (end 113.9 74.2) (width 0.4) (layer "F.Cu") (net 87))
  (via (at 113.875 74.175) (size 0.45) (drill 0.1) (layers "F.Cu" "B.Cu") (net 87))
  (via (at 113.18 74.094) (size 0.45) (drill 0.1) (layers "F.Cu" "B.Cu") (net 87))
  (segment (start 114.6 72.314) (end 114.6 73.475) (width 0.4) (layer "In4.Cu") (net 87))
  (segment (start 113.875 74.2) (end 113.286 74.2) (width 0.4) (layer "In4.Cu") (net 87))
  (segment (start 113.88 68.974) (end 113.375 69.479) (width 0.4) (layer "In4.Cu") (net 87))
  (segment (start 114.6 73.475) (end 113.875 74.2) (width 0.4) (layer "In4.Cu") (net 87))
  (segment (start 113.286 74.2) (end 113.18 74.094) (width 0.4) (layer "In4.Cu") (net 87))
  (segment (start 113.375 71.089) (end 114.6 72.314) (width 0.4) (layer "In4.Cu") (net 87))
  (segment (start 113.375 69.479) (end 113.375 71.089) (width 0.4) (layer "In4.Cu") (net 87))
  (segment (start 115.2 68.5) (end 114.6 68.5) (width 0.4) (layer "B.Cu") (net 87))
  (segment (start 116.15 67.55) (end 116.075 67.625) (width 0.4) (layer "B.Cu") (net 87))
  (segment (start 117.865 67.4) (end 117.865 66.550001) (width 0.4) (layer "B.Cu") (net 87))
  (segment (start 117.865 67.55) (end 116.15 67.55) (width 0.4) (layer "B.Cu") (net 87))
  (segment (start 114.6 68.5) (end 113.92 69.18) (width 0.4) (layer "B.Cu") (net 87))
  (segment (start 113.92 69.18) (end 113.9 69.18) (width 0.4) (layer "B.Cu") (net 87))
  (segment (start 116.075 67.625) (end 115.2 68.5) (width 0.4) (layer "B.Cu") (net 87))
  (segment (start 117.865 66.550001) (end 117.865 65.7) (width 0.4) (layer "B.Cu") (net 87))
  (segment (start 90.7865 104.604) (end 91.266 104.293) (width 0.182) (layer "F.Cu") (net 88))
  (via (at 91.266 104.293) (size 0.45) (drill 0.1) (layers "F.Cu" "B.Cu") (net 88))
  (via (at 132.78 124.477) (size 0.45) (drill 0.1) (layers "F.Cu" "B.Cu") (net 88))
  (segment (start 134.5325 124.207186) (end 134.5325 123.652814) (width 0.109) (layer "In2.Cu") (net 88))
  (segment (start 134.5325 123.652814) (end 134.453394 123.573709) (width 0.109) (layer "In2.Cu") (net 88))
  (segment (start 134.099843 123.220157) (end 134.037186 123.1575) (width 0.109) (layer "In2.Cu") (net 88))
  (segment (start 134.099843 123.396933) (end 134.099842 123.396934) (width 0.109) (layer "In2.Cu") (net 88))
  (segment (start 87.372186 103.5225) (end 90.577814 103.5225) (width 0.109) (layer "In2.Cu") (net 88))
  (segment (start 133.512499 124.472499) (end 133.512499 124.372499) (width 0.109) (layer "In2.Cu") (net 88))
  (segment (start 133.962499 124.622499) (end 134.117187 124.622499) (width 0.109) (layer "In2.Cu") (net 88))
  (segment (start 91.003 104.293) (end 91.266 104.293) (width 0.109) (layer "In2.Cu") (net 88))
  (segment (start 103.922186 115.8525) (end 102.622186 114.5525) (width 0.109) (layer "In2.Cu") (net 88))
  (segment (start 86.5975 113.302814) (end 86.5975 104.297186) (width 0.109) (layer "In2.Cu") (net 88))
  (segment (start 87.847186 114.5525) (end 86.5975 113.302814) (width 0.109) (layer "In2.Cu") (net 88))
  (segment (start 132.925499 124.622499) (end 133.362499 124.622499) (width 0.109) (layer "In2.Cu") (net 88))
  (segment (start 90.9025 103.847186) (end 90.9025 104.1925) (width 0.109) (layer "In2.Cu") (net 88))
  (segment (start 134.270555 123.579773) (end 134.270556 123.579772) (width 0.109) (layer "In2.Cu") (net 88))
  (segment (start 134.037186 123.1575) (end 125.967186 123.1575) (width 0.109) (layer "In2.Cu") (net 88))
  (segment (start 133.812499 124.372499) (end 133.812499 124.472499) (width 0.109) (layer "In2.Cu") (net 88))
  (segment (start 102.622186 114.5525) (end 87.847186 114.5525) (width 0.109) (layer "In2.Cu") (net 88))
  (segment (start 134.117187 124.622499) (end 134.5325 124.207186) (width 0.109) (layer "In2.Cu") (net 88))
  (segment (start 134.093779 123.579773) (end 134.093779 123.579772) (width 0.109) (layer "In2.Cu") (net 88))
  (segment (start 125.967186 123.1575) (end 118.662186 115.8525) (width 0.109) (layer "In2.Cu") (net 88))
  (segment (start 132.78 124.477) (end 132.925499 124.622499) (width 0.109) (layer "In2.Cu") (net 88))
  (segment (start 90.577814 103.5225) (end 90.9025 103.847186) (width 0.109) (layer "In2.Cu") (net 88))
  (segment (start 90.9025 104.1925) (end 91.003 104.293) (width 0.109) (layer "In2.Cu") (net 88))
  (segment (start 134.093779 123.402996) (end 134.099843 123.396933) (width 0.109) (layer "In2.Cu") (net 88))
  (segment (start 134.276618 123.573709) (end 134.270555 123.579773) (width 0.109) (layer "In2.Cu") (net 88))
  (segment (start 118.662186 115.8525) (end 103.922186 115.8525) (width 0.109) (layer "In2.Cu") (net 88))
  (segment (start 86.5975 104.297186) (end 87.372186 103.5225) (width 0.109) (layer "In2.Cu") (net 88))
  (arc (start 133.362499 124.622499) (mid 133.468565 124.578565) (end 133.512499 124.472499) (width 0.109) (layer "In2.Cu") (net 88))
  (arc (start 133.662499 124.222499) (mid 133.768565 124.266433) (end 133.812499 124.372499) (width 0.109) (layer "In2.Cu") (net 88))
  (arc (start 134.270556 123.579772) (mid 134.182168 123.616384) (end 134.093779 123.579773) (width 0.109) (layer "In2.Cu") (net 88))
  (arc (start 134.099842 123.396934) (mid 134.136454 123.308546) (end 134.099843 123.220157) (width 0.109) (layer "In2.Cu") (net 88))
  (arc (start 133.812499 124.472499) (mid 133.856433 124.578565) (end 133.962499 124.622499) (width 0.109) (layer "In2.Cu") (net 88))
  (arc (start 133.512499 124.372499) (mid 133.556433 124.266433) (end 133.662499 124.222499) (width 0.109) (layer "In2.Cu") (net 88))
  (arc (start 134.453394 123.573709) (mid 134.365006 123.537097) (end 134.276618 123.573709) (width 0.109) (layer "In2.Cu") (net 88))
  (arc (start 134.093779 123.579772) (mid 134.057167 123.491384) (end 134.093779 123.402996) (width 0.109) (layer "In2.Cu") (net 88))
  (segment (start 135.611155 123.881155) (end 135.809 123.68331) (width 0.182) (layer "B.Cu") (net 88))
  (segment (start 134.829665 123.66535) (end 134.829664 123.665351) (width 0.182) (layer "B.Cu") (net 88))
  (segment (start 134.90331 124.589) (end 135.045468 124.446839) (width 0.182) (layer "B.Cu") (net 88))
  (segment (start 132.892 124.589) (end 134.90331 124.589) (width 0.182) (layer "B.Cu") (net 88))
  (segment (start 135.024 122.686276) (end 134.71 123.000276) (width 0.182) (layer "B.Cu") (net 88))
  (segment (start 135.308586 122.686276) (end 135.024 122.686276) (width 0.182) (layer "B.Cu") (net 88))
  (segment (start 135.809 123.18669) (end 135.308586 122.686276) (width 0.182) (layer "B.Cu") (net 88))
  (segment (start 135.328312 123.881155) (end 135.328311 123.881155) (width 0.182) (layer "B.Cu") (net 88))
  (segment (start 132.78 124.477) (end 132.892 124.589) (width 0.182) (layer "B.Cu") (net 88))
  (segment (start 135.112507 123.66535) (end 135.328312 123.881155) (width 0.182) (layer "B.Cu") (net 88))
  (segment (start 135.045469 124.163996) (end 134.829665 123.948192) (width 0.182) (layer "B.Cu") (net 88))
  (segment (start 135.809 123.68331) (end 135.809 123.18669) (width 0.182) (layer "B.Cu") (net 88))
  (arc (start 134.829665 123.948192) (mid 134.771087 123.806771) (end 134.829665 123.66535) (width 0.182) (layer "B.Cu") (net 88))
  (arc (start 135.328311 123.881155) (mid 135.469733 123.939734) (end 135.611155 123.881155) (width 0.182) (layer "B.Cu") (net 88))
  (arc (start 134.829664 123.665351) (mid 134.971085 123.606772) (end 135.112507 123.66535) (width 0.182) (layer "B.Cu") (net 88))
  (arc (start 135.045468 124.446839) (mid 135.104047 124.305418) (end 135.045469 124.163996) (width 0.182) (layer "B.Cu") (net 88))
  (segment (start 132.974559 122.713999) (end 133.475 122.714) (width 0.182) (layer "B.Cu") (net 89))
  (segment (start 132.913559 122.774999) (end 132.974559 122.713999) (width 0.182) (layer "B.Cu") (net 89))
  (segment (start 133.736276 122.975276) (end 133.475 122.714) (width 0.182) (layer "B.Cu") (net 89))
  (segment (start 132.288559 122.775) (end 132.913559 122.774999) (width 0.182) (layer "B.Cu") (net 89))
  (segment (start 133.74 122.975276) (end 133.736276 122.975276) (width 0.182) (layer "B.Cu") (net 89))
  (segment (start 90.31 104.283) (end 90.7865 103.969) (width 0.182) (layer "F.Cu") (net 90))
  (via (at 90.31 104.283) (size 0.45) (drill 0.1) (layers "F.Cu" "B.Cu") (net 90))
  (via (at 132.78 125.026503) (size 0.45) (drill 0.1) (layers "F.Cu" "B.Cu") (net 90))
  (segment (start 87.152171 113.466003) (end 87.130338 113.461019) (width 0.109) (layer "In2.Cu") (net 90))
  (segment (start 134.222813 124.877501) (end 134.7875 124.312814) (width 0.109) (layer "In2.Cu") (net 90))
  (segment (start 87.359564 113.651005) (end 87.364548 113.629174) (width 0.109) (layer "In2.Cu") (net 90))
  (segment (start 87.416886 113.531977) (end 87.416887 113.509585) (width 0.109) (layer "In2.Cu") (net 90))
  (segment (start 88.465512 104.161755) (end 88.499119 104.173514) (width 0.109) (layer "In2.Cu") (net 90))
  (segment (start 134.7875 123.547186) (end 134.142814 122.9025) (width 0.109) (layer "In2.Cu") (net 90))
  (segment (start 88.391245 104.087488) (end 88.410188 104.117635) (width 0.109) (layer "In2.Cu") (net 90))
  (segment (start 87.392657 103.862657) (end 87.477814 103.7775) (width 0.109) (layer "In2.Cu") (net 90))
  (segment (start 87.364548 113.629174) (end 87.374263 113.608998) (width 0.109) (layer "In2.Cu") (net 90))
  (segment (start 88.3755 103.9365) (end 88.3755 104.0185) (width 0.109) (layer "In2.Cu") (net 90))
  (segment (start 132.929002 124.877501) (end 134.222813 124.877501) (width 0.109) (layer "In2.Cu") (net 90))
  (segment (start 87.168779 104.186614) (end 87.193997 104.198759) (width 0.109) (layer "In2.Cu") (net 90))
  (segment (start 86.8525 113.197186) (end 86.8525 104.402814) (width 0.109) (layer "In2.Cu") (net 90))
  (segment (start 87.357991 113.423381) (end 87.337815 113.413664) (width 0.109) (layer "In2.Cu") (net 90))
  (segment (start 87.482488 104.306042) (end 87.499942 104.284157) (width 0.109) (layer "In2.Cu") (net 90))
  (segment (start 87.499942 104.151149) (end 87.482489 104.129264) (width 0.109) (layer "In2.Cu") (net 90))
  (segment (start 134.7875 124.312814) (end 134.7875 123.547186) (width 0.109) (layer "In2.Cu") (net 90))
  (segment (start 87.460605 104.323494) (end 87.482488 104.306042) (width 0.109) (layer "In2.Cu") (net 90))
  (segment (start 87.196394 113.461019) (end 87.174563 113.466002) (width 0.109) (layer "In2.Cu") (net 90))
  (segment (start 87.356833 103.96504) (end 87.356832 103.93705) (width 0.109) (layer "In2.Cu") (net 90))
  (segment (start 87.352816 104.335639) (end 87.380106 104.341867) (width 0.109) (layer "In2.Cu") (net 90))
  (segment (start 88.728188 103.837366) (end 88.753365 103.812189) (width 0.109) (layer "In2.Cu") (net 90))
  (segment (start 87.374263 113.715404) (end 87.364548 113.69523) (width 0.109) (layer "In2.Cu") (net 90))
  (segment (start 88.6935 104.0185) (end 88.6935 103.9365) (width 0.109) (layer "In2.Cu") (net 90))
  (segment (start 104.027814 115.5975) (end 102.727814 114.2975) (width 0.109) (layer "In2.Cu") (net 90))
  (segment (start 87.337815 113.413664) (end 87.315984 113.408681) (width 0.109) (layer "In2.Cu") (net 90))
  (segment (start 87.130338 113.461019) (end 87.110164 113.451304) (width 0.109) (layer "In2.Cu") (net 90))
  (segment (start 87.060989 104.198759) (end 87.086209 104.186614) (width 0.109) (layer "In2.Cu") (net 90))
  (segment (start 87.327597 104.323494) (end 87.352816 104.335639) (width 0.109) (layer "In2.Cu") (net 90))
  (segment (start 87.086209 104.186614) (end 87.113498 104.180386) (width 0.109) (layer "In2.Cu") (net 90))
  (segment (start 88.359754 103.867513) (end 88.371513 103.90112) (width 0.109) (layer "In2.Cu") (net 90))
  (segment (start 88.633634 104.142812) (end 88.658811 104.117635) (width 0.109) (layer "In2.Cu") (net 90))
  (segment (start 88.340811 103.837366) (end 88.359754 103.867513) (width 0.109) (layer "In2.Cu") (net 90))
  (segment (start 87.392658 104.039433) (end 87.375206 104.017549) (width 0.109) (layer "In2.Cu") (net 90))
  (segment (start 126.072814 122.9025) (end 118.767814 115.5975) (width 0.109) (layer "In2.Cu") (net 90))
  (segment (start 88.689513 104.053881) (end 88.6935 104.0185) (width 0.109) (layer "In2.Cu") (net 90))
  (segment (start 88.697486 103.90112) (end 88.709245 103.867513) (width 0.109) (layer "In2.Cu") (net 90))
  (segment (start 87.375499 113.437343) (end 87.357991 113.423381) (width 0.109) (layer "In2.Cu") (net 90))
  (segment (start 87.411903 113.553808) (end 87.416886 113.531977) (width 0.109) (layer "In2.Cu") (net 90))
  (segment (start 88.25188 103.781487) (end 88.285487 103.793246) (width 0.109) (layer "In2.Cu") (net 90))
  (segment (start 88.3755 104.0185) (end 88.379486 104.053881) (width 0.109) (layer "In2.Cu") (net 90))
  (segment (start 90.6475 103.952814) (end 90.6475 104.2075) (width 0.109) (layer "In2.Cu") (net 90))
  (segment (start 87.952814 114.2975) (end 87.388225 113.732912) (width 0.109) (layer "In2.Cu") (net 90))
  (segment (start 87.356832 103.93705) (end 87.363061 103.90976) (width 0.109) (layer "In2.Cu") (net 90))
  (segment (start 88.2165 103.7775) (end 88.25188 103.781487) (width 0.109) (layer "In2.Cu") (net 90))
  (segment (start 87.363061 103.90976) (end 87.375206 103.884541) (width 0.109) (layer "In2.Cu") (net 90))
  (segment (start 87.14149 104.180385) (end 87.168779 104.186614) (width 0.109) (layer "In2.Cu") (net 90))
  (segment (start 90.472186 103.7775) (end 90.6475 103.952814) (width 0.109) (layer "In2.Cu") (net 90))
  (segment (start 87.512085 104.176369) (end 87.499942 104.151149) (width 0.109) (layer "In2.Cu") (net 90))
  (segment (start 87.388225 113.732912) (end 87.374263 113.715404) (width 0.109) (layer "In2.Cu") (net 90))
  (segment (start 88.499119 104.173514) (end 88.5345 104.1775) (width 0.109) (layer "In2.Cu") (net 90))
  (segment (start 87.271759 113.413664) (end 87.251585 113.423381) (width 0.109) (layer "In2.Cu") (net 90))
  (segment (start 87.359565 113.673399) (end 87.359564 113.651005) (width 0.109) (layer "In2.Cu") (net 90))
  (segment (start 87.416887 113.509585) (end 87.411903 113.487752) (width 0.109) (layer "In2.Cu") (net 90))
  (segment (start 87.375206 104.017549) (end 87.363061 103.99233) (width 0.109) (layer "In2.Cu") (net 90))
  (segment (start 87.110164 113.451304) (end 87.092657 113.437343) (width 0.109) (layer "In2.Cu") (net 90))
  (segment (start 88.783512 103.793246) (end 88.817119 103.781487) (width 0.109) (layer "In2.Cu") (net 90))
  (segment (start 87.363061 103.99233) (end 87.356833 103.96504) (width 0.109) (layer "In2.Cu") (net 90))
  (segment (start 88.8525 103.7775) (end 90.472186 103.7775) (width 0.109) (layer "In2.Cu") (net 90))
  (segment (start 134.142814 122.9025) (end 126.072814 122.9025) (width 0.109) (layer "In2.Cu") (net 90))
  (segment (start 87.215882 104.216212) (end 87.305712 104.306042) (width 0.109) (layer "In2.Cu") (net 90))
  (segment (start 88.603487 104.161755) (end 88.633634 104.142812) (width 0.109) (layer "In2.Cu") (net 90))
  (segment (start 87.388226 113.45007) (end 87.375499 113.437343) (width 0.109) (layer "In2.Cu") (net 90))
  (segment (start 88.56988 104.173514) (end 88.603487 104.161755) (width 0.109) (layer "In2.Cu") (net 90))
  (segment (start 88.6935 103.9365) (end 88.697486 103.90112) (width 0.109) (layer "In2.Cu") (net 90))
  (segment (start 87.375206 103.884541) (end 87.392657 103.862657) (width 0.109) (layer "In2.Cu") (net 90))
  (segment (start 87.039105 104.21621) (end 87.060989 104.198759) (width 0.109) (layer "In2.Cu") (net 90))
  (segment (start 88.658811 104.117635) (end 88.677754 104.087488) (width 0.109) (layer "In2.Cu") (net 90))
  (segment (start 88.753365 103.812189) (end 88.783512 103.793246) (width 0.109) (layer "In2.Cu") (net 90))
  (segment (start 86.8525 104.402814) (end 87.039105 104.21621) (width 0.109) (layer "In2.Cu") (net 90))
  (segment (start 87.380106 104.341867) (end 87.408096 104.341868) (width 0.109) (layer "In2.Cu") (net 90))
  (segment (start 88.5345 104.1775) (end 88.56988 104.173514) (width 0.109) (layer "In2.Cu") (net 90))
  (segment (start 87.092657 113.437343) (end 86.8525 113.197186) (width 0.109) (layer "In2.Cu") (net 90))
  (segment (start 87.305712 104.306042) (end 87.327597 104.323494) (width 0.109) (layer "In2.Cu") (net 90))
  (segment (start 87.251585 113.423381) (end 87.21657 113.451304) (width 0.109) (layer "In2.Cu") (net 90))
  (segment (start 87.364548 113.69523) (end 87.359565 113.673399) (width 0.109) (layer "In2.Cu") (net 90))
  (segment (start 87.374263 113.608998) (end 87.402188 113.573984) (width 0.109) (layer "In2.Cu") (net 90))
  (segment (start 87.174563 113.466002) (end 87.152171 113.466003) (width 0.109) (layer "In2.Cu") (net 90))
  (segment (start 88.285487 103.793246) (end 88.315634 103.812189) (width 0.109) (layer "In2.Cu") (net 90))
  (segment (start 102.727814 114.2975) (end 87.952814 114.2975) (width 0.109) (layer "In2.Cu") (net 90))
  (segment (start 88.817119 103.781487) (end 88.8525 103.7775) (width 0.109) (layer "In2.Cu") (net 90))
  (segment (start 87.518314 104.203658) (end 87.512085 104.176369) (width 0.109) (layer "In2.Cu") (net 90))
  (segment (start 88.410188 104.117635) (end 88.435365 104.142812) (width 0.109) (layer "In2.Cu") (net 90))
  (segment (start 88.677754 104.087488) (end 88.689513 104.053881) (width 0.109) (layer "In2.Cu") (net 90))
  (segment (start 88.315634 103.812189) (end 88.340811 103.837366) (width 0.109) (layer "In2.Cu") (net 90))
  (segment (start 87.193997 104.198759) (end 87.215882 104.216212) (width 0.109) (layer "In2.Cu") (net 90))
  (segment (start 90.6475 104.2075) (end 90.572 104.283) (width 0.109) (layer "In2.Cu") (net 90))
  (segment (start 87.435386 104.335639) (end 87.460605 104.323494) (width 0.109) (layer "In2.Cu") (net 90))
  (segment (start 87.293592 113.408682) (end 87.271759 113.413664) (width 0.109) (layer "In2.Cu") (net 90))
  (segment (start 87.402188 113.573984) (end 87.411903 113.553808) (width 0.109) (layer "In2.Cu") (net 90))
  (segment (start 87.411903 113.487752) (end 87.402188 113.467578) (width 0.109) (layer "In2.Cu") (net 90))
  (segment (start 87.408096 104.341868) (end 87.435386 104.335639) (width 0.109) (layer "In2.Cu") (net 90))
  (segment (start 87.477814 103.7775) (end 88.2165 103.7775) (width 0.109) (layer "In2.Cu") (net 90))
  (segment (start 88.709245 103.867513) (end 88.728188 103.837366) (width 0.109) (layer "In2.Cu") (net 90))
  (segment (start 88.435365 104.142812) (end 88.465512 104.161755) (width 0.109) (layer "In2.Cu") (net 90))
  (segment (start 118.767814 115.5975) (end 104.027814 115.5975) (width 0.109) (layer "In2.Cu") (net 90))
  (segment (start 87.402188 113.467578) (end 87.388226 113.45007) (width 0.109) (layer "In2.Cu") (net 90))
  (segment (start 90.572 104.283) (end 90.31 104.283) (width 0.109) (layer "In2.Cu") (net 90))
  (segment (start 87.482489 104.129264) (end 87.392658 104.039433) (width 0.109) (layer "In2.Cu") (net 90))
  (segment (start 87.499942 104.284157) (end 87.512085 104.258939) (width 0.109) (layer "In2.Cu") (net 90))
  (segment (start 87.315984 113.408681) (end 87.293592 113.408682) (width 0.109) (layer "In2.Cu") (net 90))
  (segment (start 87.21657 113.451304) (end 87.196394 113.461019) (width 0.109) (layer "In2.Cu") (net 90))
  (segment (start 87.512085 104.258939) (end 87.518315 104.231648) (width 0.109) (layer "In2.Cu") (net 90))
  (segment (start 88.371513 103.90112) (end 88.3755 103.9365) (width 0.109) (layer "In2.Cu") (net 90))
  (segment (start 87.518315 104.231648) (end 87.518314 104.203658) (width 0.109) (layer "In2.Cu") (net 90))
  (segment (start 87.113498 104.180386) (end 87.14149 104.180385) (width 0.109) (layer "In2.Cu") (net 90))
  (segment (start 88.379486 104.053881) (end 88.391245 104.087488) (width 0.109) (layer "In2.Cu") (net 90))
  (segment (start 132.78 125.026503) (end 132.929002 124.877501) (width 0.109) (layer "In2.Cu") (net 90))
  (segment (start 135.441966 122.364276) (end 135.023999 122.364276) (width 0.182) (layer "B.Cu") (net 90))
  (segment (start 135.03669 124.911) (end 136.131 123.81669) (width 0.182) (layer "B.Cu") (net 90))
  (segment (start 135.023999 122.364276) (end 134.71 122.050277) (width 0.182) (layer "B.Cu") (net 90))
  (segment (start 136.131 123.81669) (end 136.131 123.05331) (width 0.182) (layer "B.Cu") (net 90))
  (segment (start 132.895503 124.911) (end 135.03669 124.911) (width 0.182) (layer "B.Cu") (net 90))
  (segment (start 132.78 125.026503) (end 132.895503 124.911) (width 0.182) (layer "B.Cu") (net 90))
  (segment (start 136.131 123.05331) (end 135.441966 122.364276) (width 0.182) (layer "B.Cu") (net 90))
  (segment (start 133.74 122.075276) (end 133.735723 122.075276) (width 0.182) (layer "B.Cu") (net 91))
  (segment (start 132.288559 122.274999) (end 132.913559 122.274998) (width 0.182) (layer "B.Cu") (net 91))
  (segment (start 132.974559 122.335998) (end 133.475 122.335999) (width 0.182) (layer "B.Cu") (net 91))
  (segment (start 133.735723 122.075276) (end 133.475 122.335999) (width 0.182) (layer "B.Cu") (net 91))
  (segment (start 132.913559 122.274998) (end 132.974559 122.335998) (width 0.182) (layer "B.Cu") (net 91))
  (segment (start 93.3265 107.144) (end 93.806 106.833) (width 0.182) (layer "F.Cu") (net 92))
  (segment (start 84.716 72.138) (end 84.716 72.629) (width 0.182) (layer "F.Cu") (net 92))
  (segment (start 84.716 72.629) (end 84.62 72.725) (width 0.182) (layer "F.Cu") (net 92))
  (segment (start 84.38 71.802) (end 84.716 72.138) (width 0.182) (layer "F.Cu") (net 92))
  (via (at 93.806 106.833) (size 0.45) (drill 0.1) (layers "F.Cu" "B.Cu") (net 92))
  (via (at 84.62 72.725) (size 0.45) (drill 0.1) (layers "F.Cu" "B.Cu") (net 92))
  (segment (start 93.41 106.75) (end 93.41 106.36) (width 0.109) (layer "In6.Cu") (net 92))
  (segment (start 83.215794 72.538705) (end 83.236461 72.525719) (width 0.109) (layer "In6.Cu") (net 92))
  (segment (start 86.43352 105.526712) (end 86.443486 105.48305) (width 0.109) (layer "In6.Cu") (net 92))
  (segment (start 86.443486 105.48305) (end 86.462917 105.442699) (width 0.109) (layer "In6.Cu") (net 92))
  (segment (start 83.0275 71.982814) (end 83.452814 71.5575) (width 0.109) (layer "In6.Cu") (net 92))
  (segment (start 83.7765 71.7485) (end 83.779232 71.772754) (width 0.109) (layer "In6.Cu") (net 92))
  (segment (start 83.274768 72.464754) (end 83.2775 72.4405) (width 0.109) (layer "In6.Cu") (net 92))
  (segment (start 86.31856 105.042292) (end 86.278209 105.061723) (width 0.109) (layer "In6.Cu") (net 92))
  (segment (start 84.079245 71.560232) (end 84.1035 71.5575) (width 0.109) (layer "In6.Cu") (net 92))
  (segment (start 83.714793 71.568294) (end 83.73546 71.58128) (width 0.109) (layer "In6.Cu") (net 92))
  (segment (start 83.06854 72.57328) (end 83.089207 72.560294) (width 0.109) (layer "In6.Cu") (net 92))
  (segment (start 83.1685 72.3315) (end 83.1365 72.3315) (width 0.109) (layer "In6.Cu") (net 92))
  (segment (start 83.787294 71.795793) (end 83.80028 71.81646) (width 0.109) (layer "In6.Cu") (net 92))
  (segment (start 83.9945 71.7485) (end 83.9945 71.6665) (width 0.109) (layer "In6.Cu") (net 92))
  (segment (start 84.8375 98.527186) (end 84.1675 97.857186) (width 0.109) (layer "In6.Cu") (net 92))
  (segment (start 84.6975 86.727186) (end 84.2005 86.230186) (width 0.109) (layer "In6.Cu") (net 92))
  (segment (start 86.132634 105.172198) (end 86.08897 105.182163) (width 0.109) (layer "In6.Cu") (net 92))
  (segment (start 86.583357 105.208674) (end 86.573392 105.165012) (width 0.109) (layer "In6.Cu") (net 92))
  (segment (start 83.051281 72.29046) (end 83.038295 72.269793) (width 0.109) (layer "In6.Cu") (net 92))
  (segment (start 83.7765 71.6665) (end 83.7765 71.7485) (width 0.109) (layer "In6.Cu") (net 92))
  (segment (start 84.035539 71.58128) (end 84.056206 71.568294) (width 0.109) (layer "In6.Cu") (net 92))
  (segment (start 86.207999 105.124843) (end 86.172984 105.152766) (width 0.109) (layer "In6.Cu") (net 92))
  (segment (start 84.2005 86.230186) (end 84.2005 74.100186) (width 0.109) (layer "In6.Cu") (net 92))
  (segment (start 83.9945 71.6665) (end 83.997232 71.642245) (width 0.109) (layer "In6.Cu") (net 92))
  (segment (start 86.911814 106.1115) (end 86.490842 105.690528) (width 0.109) (layer "In6.Cu") (net 92))
  (segment (start 84.397186 71.5575) (end 84.7775 71.937814) (width 0.109) (layer "In6.Cu") (net 92))
  (segment (start 86.526037 105.372489) (end 86.55396 105.337474) (width 0.109) (layer "In6.Cu") (net 92))
  (segment (start 86.278209 105.061723) (end 86.243193 105.089646) (width 0.109) (layer "In6.Cu") (net 92))
  (segment (start 86.462916 105.655511) (end 86.443485 105.61516) (width 0.109) (layer "In6.Cu") (net 92))
  (segment (start 83.0275 72.927186) (end 83.0275 72.6585) (width 0.109) (layer "In6.Cu") (net 92))
  (segment (start 83.236461 72.35528) (end 83.215794 72.342294) (width 0.109) (layer "In6.Cu") (net 92))
  (segment (start 84.632 72.725) (end 84.7775 72.5795) (width 0.109) (layer "In6.Cu") (net 92))
  (segment (start 83.909754 71.854767) (end 83.932793 71.846705) (width 0.109) (layer "In6.Cu") (net 92))
  (segment (start 93.806 106.833) (end 93.493 106.833) (width 0.109) (layer "In6.Cu") (net 92))
  (segment (start 83.452814 71.5575) (end 83.6675 71.5575) (width 0.109) (layer "In6.Cu") (net 92))
  (segment (start 83.192755 72.546767) (end 83.215794 72.538705) (width 0.109) (layer "In6.Cu") (net 92))
  (segment (start 84.005294 71.619206) (end 84.01828 71.598539) (width 0.109) (layer "In6.Cu") (net 92))
  (segment (start 86.573392 105.297124) (end 86.583357 105.25346) (width 0.109) (layer "In6.Cu") (net 92))
  (segment (start 83.691754 71.560232) (end 83.714793 71.568294) (width 0.109) (layer "In6.Cu") (net 92))
  (segment (start 83.038295 72.269793) (end 83.030233 72.246754) (width 0.109) (layer "In6.Cu") (net 92))
  (segment (start 83.112246 72.328767) (end 83.089207 72.320705) (width 0.109) (layer "In6.Cu") (net 92))
  (segment (start 86.000522 105.172198) (end 85.96017 105.152765) (width 0.109) (layer "In6.Cu") (net 92))
  (segment (start 83.2775 72.4405) (end 83.274768 72.416245) (width 0.109) (layer "In6.Cu") (net 92))
  (segment (start 84.6975 91.472814) (end 84.6975 86.727186) (width 0.109) (layer "In6.Cu") (net 92))
  (segment (start 86.172984 105.152766) (end 86.132634 105.172198) (width 0.109) (layer "In6.Cu") (net 92))
  (segment (start 86.583357 105.25346) (end 86.583357 105.208674) (width 0.109) (layer "In6.Cu") (net 92))
  (segment (start 86.43352 105.571498) (end 86.43352 105.526712) (width 0.109) (layer "In6.Cu") (net 92))
  (segment (start 83.030233 72.634245) (end 83.038295 72.611206) (width 0.109) (layer "In6.Cu") (net 92))
  (segment (start 86.462917 105.442699) (end 86.49084 105.407683) (width 0.109) (layer "In6.Cu") (net 92))
  (segment (start 86.49084 105.407683) (end 86.526037 105.372489) (width 0.109) (layer "In6.Cu") (net 92))
  (segment (start 83.861245 71.854767) (end 83.8855 71.8575) (width 0.109) (layer "In6.Cu") (net 92))
  (segment (start 83.06854 72.307719) (end 83.051281 72.29046) (width 0.109) (layer "In6.Cu") (net 92))
  (segment (start 86.490842 105.690528) (end 86.462916 105.655511) (width 0.109) (layer "In6.Cu") (net 92))
  (segment (start 83.192755 72.334232) (end 83.1685 72.3315) (width 0.109) (layer "In6.Cu") (net 92))
  (segment (start 86.45067 105.042291) (end 86.407008 105.032326) (width 0.109) (layer "In6.Cu") (net 92))
  (segment (start 86.526037 105.089647) (end 86.491021 105.061722) (width 0.109) (layer "In6.Cu") (net 92))
  (segment (start 83.266706 72.393206) (end 83.25372 72.372539) (width 0.109) (layer "In6.Cu") (net 92))
  (segment (start 84.1675 97.857186) (end 84.1675 92.002814) (width 0.109) (layer "In6.Cu") (net 92))
  (segment (start 83.1685 72.5495) (end 83.192755 72.546767) (width 0.109) (layer "In6.Cu") (net 92))
  (segment (start 83.112246 72.552232) (end 83.1365 72.5495) (width 0.109) (layer "In6.Cu") (net 92))
  (segment (start 84.62 72.725) (end 84.632 72.725) (width 0.109) (layer "In6.Cu") (net 92))
  (segment (start 83.0275 72.2225) (end 83.0275 71.982814) (width 0.109) (layer "In6.Cu") (net 92))
  (segment (start 84.1675 92.002814) (end 84.6975 91.472814) (width 0.109) (layer "In6.Cu") (net 92))
  (segment (start 84.1035 71.5575) (end 84.397186 71.5575) (width 0.109) (layer "In6.Cu") (net 92))
  (segment (start 86.491021 105.061722) (end 86.45067 105.042291) (width 0.109) (layer "In6.Cu") (net 92))
  (segment (start 83.817539 71.833719) (end 83.838206 71.846705) (width 0.109) (layer "In6.Cu") (net 92))
  (segment (start 83.73546 71.58128) (end 83.752719 71.598539) (width 0.109) (layer "In6.Cu") (net 92))
  (segment (start 83.752719 71.598539) (end 83.765705 71.619206) (width 0.109) (layer "In6.Cu") (net 92))
  (segment (start 83.932793 71.846705) (end 83.95346 71.833719) (width 0.109) (layer "In6.Cu") (net 92))
  (segment (start 83.030233 72.246754) (end 83.0275 72.2225) (width 0.109) (layer "In6.Cu") (net 92))
  (segment (start 84.01828 71.598539) (end 84.035539 71.58128) (width 0.109) (layer "In6.Cu") (net 92))
  (segment (start 83.765705 71.619206) (end 83.773767 71.642245) (width 0.109) (layer "In6.Cu") (net 92))
  (segment (start 83.038295 72.611206) (end 83.051281 72.590539) (width 0.109) (layer "In6.Cu") (net 92))
  (segment (start 83.1365 72.3315) (end 83.112246 72.328767) (width 0.109) (layer "In6.Cu") (net 92))
  (segment (start 83.089207 72.320705) (end 83.06854 72.307719) (width 0.109) (layer "In6.Cu") (net 92))
  (segment (start 84.8375 104.037186) (end 84.8375 98.527186) (width 0.109) (layer "In6.Cu") (net 92))
  (segment (start 86.573392 105.165012) (end 86.553959 105.12466) (width 0.109) (layer "In6.Cu") (net 92))
  (segment (start 83.266706 72.487793) (end 83.274768 72.464754) (width 0.109) (layer "In6.Cu") (net 92))
  (segment (start 86.443485 105.61516) (end 86.43352 105.571498) (width 0.109) (layer "In6.Cu") (net 92))
  (segment (start 86.044184 105.182163) (end 86.000522 105.172198) (width 0.109) (layer "In6.Cu") (net 92))
  (segment (start 83.991767 71.772754) (end 83.9945 71.7485) (width 0.109) (layer "In6.Cu") (net 92))
  (segment (start 83.051281 72.590539) (end 83.06854 72.57328) (width 0.109) (layer "In6.Cu") (net 92))
  (segment (start 84.2005 74.100186) (end 83.0275 72.927186) (width 0.109) (layer "In6.Cu") (net 92))
  (segment (start 86.243193 105.089646) (end 86.207999 105.124843) (width 0.109) (layer "In6.Cu") (net 92))
  (segment (start 93.41 106.36) (end 93.1615 106.1115) (width 0.109) (layer "In6.Cu") (net 92))
  (segment (start 83.215794 72.342294) (end 83.192755 72.334232) (width 0.109) (layer "In6.Cu") (net 92))
  (segment (start 86.553959 105.12466) (end 86.526037 105.089647) (width 0.109) (layer "In6.Cu") (net 92))
  (segment (start 83.274768 72.416245) (end 83.266706 72.393206) (width 0.109) (layer "In6.Cu") (net 92))
  (segment (start 83.0275 72.6585) (end 83.030233 72.634245) (width 0.109) (layer "In6.Cu") (net 92))
  (segment (start 83.6675 71.5575) (end 83.691754 71.560232) (width 0.109) (layer "In6.Cu") (net 92))
  (segment (start 86.55396 105.337474) (end 86.573392 105.297124) (width 0.109) (layer "In6.Cu") (net 92))
  (segment (start 85.925157 105.124843) (end 84.8375 104.037186) (width 0.109) (layer "In6.Cu") (net 92))
  (segment (start 83.773767 71.642245) (end 83.7765 71.6665) (width 0.109) (layer "In6.Cu") (net 92))
  (segment (start 83.970719 71.81646) (end 83.983705 71.795793) (width 0.109) (layer "In6.Cu") (net 92))
  (segment (start 83.997232 71.642245) (end 84.005294 71.619206) (width 0.109) (layer "In6.Cu") (net 92))
  (segment (start 83.80028 71.81646) (end 83.817539 71.833719) (width 0.109) (layer "In6.Cu") (net 92))
  (segment (start 86.08897 105.182163) (end 86.044184 105.182163) (width 0.109) (layer "In6.Cu") (net 92))
  (segment (start 85.96017 105.152765) (end 85.925157 105.124843) (width 0.109) (layer "In6.Cu") (net 92))
  (segment (start 86.407008 105.032326) (end 86.362222 105.032326) (width 0.109) (layer "In6.Cu") (net 92))
  (segment (start 83.95346 71.833719) (end 83.970719 71.81646) (width 0.109) (layer "In6.Cu") (net 92))
  (segment (start 84.056206 71.568294) (end 84.079245 71.560232) (width 0.109) (layer "In6.Cu") (net 92))
  (segment (start 86.362222 105.032326) (end 86.31856 105.042292) (width 0.109) (layer "In6.Cu") (net 92))
  (segment (start 84.7775 71.937814) (end 84.7775 72.5795) (width 0.109) (layer "In6.Cu") (net 92))
  (segment (start 83.8855 71.8575) (end 83.909754 71.854767) (width 0.109) (layer "In6.Cu") (net 92))
  (segment (start 93.1615 106.1115) (end 86.911814 106.1115) (width 0.109) (layer "In6.Cu") (net 92))
  (segment (start 83.25372 72.372539) (end 83.236461 72.35528) (width 0.109) (layer "In6.Cu") (net 92))
  (segment (start 83.236461 72.525719) (end 83.25372 72.50846) (width 0.109) (layer "In6.Cu") (net 92))
  (segment (start 83.25372 72.50846) (end 83.266706 72.487793) (width 0.109) (layer "In6.Cu") (net 92))
  (segment (start 83.983705 71.795793) (end 83.991767 71.772754) (width 0.109) (layer "In6.Cu") (net 92))
  (segment (start 83.838206 71.846705) (end 83.861245 71.854767) (width 0.109) (layer "In6.Cu") (net 92))
  (segment (start 83.089207 72.560294) (end 83.112246 72.552232) (width 0.109) (layer "In6.Cu") (net 92))
  (segment (start 93.493 106.833) (end 93.41 106.75) (width 0.109) (layer "In6.Cu") (net 92))
  (segment (start 83.779232 71.772754) (end 83.787294 71.795793) (width 0.109) (layer "In6.Cu") (net 92))
  (segment (start 83.1365 72.5495) (end 83.1685 72.5495) (width 0.109) (layer "In6.Cu") (net 92))
  (segment (start 85 69.1175) (end 85 69.541251) (width 0.182) (layer "F.Cu") (net 93))
  (segment (start 85.061 69.916976) (end 85.061 69.602251) (width 0.182) (layer "F.Cu") (net 93))
  (segment (start 84.706 70.271976) (end 85.061 69.916976) (width 0.182) (layer "F.Cu") (net 93))
  (segment (start 84.706 70.571) (end 84.706 70.271976) (width 0.182) (layer "F.Cu") (net 93))
  (segment (start 85 69.541251) (end 85.061 69.602251) (width 0.182) (layer "F.Cu") (net 93))
  (segment (start 84.445 70.832) (end 84.706 70.571) (width 0.182) (layer "F.Cu") (net 93))
  (segment (start 85 68.365) (end 85 69.137) (width 0.182) (layer "F.Cu") (net 93))
  (segment (start 85 67.7) (end 85 68.2825) (width 0.182) (layer "F.Cu") (net 93))
  (segment (start 84.763 67.463) (end 85 67.7) (width 0.182) (layer "F.Cu") (net 93))
  (segment (start 84.763 65.618) (end 84.763 67.463) (width 0.182) (layer "F.Cu") (net 93))
  (segment (start 92.85 106.823) (end 93.3265 106.509) (width 0.182) (layer "F.Cu") (net 94))
  (segment (start 85.094 72.068) (end 85.094 72.629) (width 0.182) (layer "F.Cu") (net 94))
  (segment (start 85.094 72.629) (end 85.19 72.725) (width 0.182) (layer "F.Cu") (net 94))
  (segment (start 85.36 71.802) (end 85.094 72.068) (width 0.182) (layer "F.Cu") (net 94))
  (via (at 92.85 106.823) (size 0.45) (drill 0.1) (layers "F.Cu" "B.Cu") (net 94))
  (via (at 85.19 72.725) (size 0.45) (drill 0.1) (layers "F.Cu" "B.Cu") (net 94))
  (segment (start 85.0325 71.832186) (end 85.0325 72.5795) (width 0.109) (layer "In6.Cu") (net 94))
  (segment (start 88.597887 106.502558) (end 88.5935 106.5415) (width 0.109) (layer "In6.Cu") (net 94))
  (segment (start 88.17761 106.404679) (end 88.144429 106.38383) (width 0.109) (layer "In6.Cu") (net 94))
  (segment (start 88.69257 106.38383) (end 88.659389 106.404679) (width 0.109) (layer "In6.Cu") (net 94))
  (segment (start 88.4185 106.759419) (end 88.379558 106.755031) (width 0.109) (layer "In6.Cu") (net 94))
  (segment (start 88.5935 106.5415) (end 88.5935 106.584419) (width 0.109) (layer "In6.Cu") (net 94))
  (segment (start 84.4425 86.832814) (end 83.9455 86.335814) (width 0.109) (layer "In6.Cu") (net 94))
  (segment (start 88.2435 106.5415) (end 88.239112 106.502558) (width 0.109) (layer "In6.Cu") (net 94))
  (segment (start 88.0685 106.3665) (end 86.806186 106.3665) (width 0.109) (layer "In6.Cu") (net 94))
  (segment (start 88.589112 106.62336) (end 88.576169 106.660348) (width 0.109) (layer "In6.Cu") (net 94))
  (segment (start 88.5935 106.584419) (end 88.589112 106.62336) (width 0.109) (layer "In6.Cu") (net 94))
  (segment (start 83.9125 97.962814) (end 83.9125 91.897186) (width 0.109) (layer "In6.Cu") (net 94))
  (segment (start 88.52761 106.721239) (end 88.494429 106.742088) (width 0.109) (layer "In6.Cu") (net 94))
  (segment (start 88.239112 106.502558) (end 88.226169 106.46557) (width 0.109) (layer "In6.Cu") (net 94))
  (segment (start 88.457441 106.755031) (end 88.4185 106.759419) (width 0.109) (layer "In6.Cu") (net 94))
  (segment (start 88.576169 106.660348) (end 88.55532 106.693529) (width 0.109) (layer "In6.Cu") (net 94))
  (segment (start 88.144429 106.38383) (end 88.107441 106.370887) (width 0.109) (layer "In6.Cu") (net 94))
  (segment (start 84.4425 91.367186) (end 84.4425 86.832814) (width 0.109) (layer "In6.Cu") (net 94))
  (segment (start 88.34257 106.742088) (end 88.309389 106.721239) (width 0.109) (layer "In6.Cu") (net 94))
  (segment (start 88.226169 106.46557) (end 88.20532 106.432389) (width 0.109) (layer "In6.Cu") (net 94))
  (segment (start 88.631679 106.432389) (end 88.61083 106.46557) (width 0.109) (layer "In6.Cu") (net 94))
  (segment (start 83.9455 74.205814) (end 82.7725 73.032814) (width 0.109) (layer "In6.Cu") (net 94))
  (segment (start 88.61083 106.46557) (end 88.597887 106.502558) (width 0.109) (layer "In6.Cu") (net 94))
  (segment (start 88.2435 106.584419) (end 88.2435 106.5415) (width 0.109) (layer "In6.Cu") (net 94))
  (segment (start 85.178 72.725) (end 85.0325 72.5795) (width 0.109) (layer "In6.Cu") (net 94))
  (segment (start 85.19 72.725) (end 85.178 72.725) (width 0.109) (layer "In6.Cu") (net 94))
  (segment (start 82.7725 73.032814) (end 82.7725 71.877186) (width 0.109) (layer "In6.Cu") (net 94))
  (segment (start 88.247887 106.62336) (end 88.2435 106.584419) (width 0.109) (layer "In6.Cu") (net 94))
  (segment (start 93.19 106.72) (end 93.19 106.4795) (width 0.109) (layer "In6.Cu") (net 94))
  (segment (start 88.107441 106.370887) (end 88.0685 106.3665) (width 0.109) (layer "In6.Cu") (net 94))
  (segment (start 82.7725 71.877186) (end 83.347186 71.3025) (width 0.109) (layer "In6.Cu") (net 94))
  (segment (start 84.5825 104.142814) (end 84.5825 98.632814) (width 0.109) (layer "In6.Cu") (net 94))
  (segment (start 88.379558 106.755031) (end 88.34257 106.742088) (width 0.109) (layer "In6.Cu") (net 94))
  (segment (start 88.55532 106.693529) (end 88.52761 106.721239) (width 0.109) (layer "In6.Cu") (net 94))
  (segment (start 88.7685 106.3665) (end 88.729558 106.370887) (width 0.109) (layer "In6.Cu") (net 94))
  (segment (start 84.502814 71.3025) (end 85.0325 71.832186) (width 0.109) (layer "In6.Cu") (net 94))
  (segment (start 83.9455 86.335814) (end 83.9455 74.205814) (width 0.109) (layer "In6.Cu") (net 94))
  (segment (start 92.85 106.823) (end 93.087 106.823) (width 0.109) (layer "In6.Cu") (net 94))
  (segment (start 83.9125 91.897186) (end 84.4425 91.367186) (width 0.109) (layer "In6.Cu") (net 94))
  (segment (start 88.281679 106.693529) (end 88.26083 106.660348) (width 0.109) (layer "In6.Cu") (net 94))
  (segment (start 93.087 106.823) (end 93.19 106.72) (width 0.109) (layer "In6.Cu") (net 94))
  (segment (start 88.309389 106.721239) (end 88.281679 106.693529) (width 0.109) (layer "In6.Cu") (net 94))
  (segment (start 83.347186 71.3025) (end 84.502814 71.3025) (width 0.109) (layer "In6.Cu") (net 94))
  (segment (start 88.659389 106.404679) (end 88.631679 106.432389) (width 0.109) (layer "In6.Cu") (net 94))
  (segment (start 88.494429 106.742088) (end 88.457441 106.755031) (width 0.109) (layer "In6.Cu") (net 94))
  (segment (start 84.5825 98.632814) (end 83.9125 97.962814) (width 0.109) (layer "In6.Cu") (net 94))
  (segment (start 86.806186 106.3665) (end 84.5825 104.142814) (width 0.109) (layer "In6.Cu") (net 94))
  (segment (start 88.26083 106.660348) (end 88.247887 106.62336) (width 0.109) (layer "In6.Cu") (net 94))
  (segment (start 88.729558 106.370887) (end 88.69257 106.38383) (width 0.109) (layer "In6.Cu") (net 94))
  (segment (start 88.20532 106.432389) (end 88.17761 106.404679) (width 0.109) (layer "In6.Cu") (net 94))
  (segment (start 93.077 106.3665) (end 88.7685 106.3665) (width 0.109) (layer "In6.Cu") (net 94))
  (segment (start 93.19 106.4795) (end 93.077 106.3665) (width 0.109) (layer "In6.Cu") (net 94))
  (segment (start 85.345 70.832) (end 85.084 70.571) (width 0.182) (layer "F.Cu") (net 95))
  (segment (start 85.084 70.428552) (end 85.439 70.073552) (width 0.182) (layer "F.Cu") (net 95))
  (segment (start 85.5 69.1175) (end 85.5 69.541251) (width 0.182) (layer "F.Cu") (net 95))
  (segment (start 85.084 70.571) (end 85.084 70.428552) (width 0.182) (layer "F.Cu") (net 95))
  (segment (start 85.5 69.541251) (end 85.439 69.602251) (width 0.182) (layer "F.Cu") (net 95))
  (segment (start 85.439 70.073552) (end 85.439 69.602251) (width 0.182) (layer "F.Cu") (net 95))
  (segment (start 85.763 67.437) (end 85.5 67.7) (width 0.182) (layer "F.Cu") (net 95))
  (segment (start 85.763 65.618) (end 85.763 67.437) (width 0.182) (layer "F.Cu") (net 95))
  (segment (start 85.5 68.365) (end 85.5 69.137) (width 0.182) (layer "F.Cu") (net 95))
  (segment (start 85.5 67.7) (end 85.5 68.2825) (width 0.182) (layer "F.Cu") (net 95))
  (segment (start 91.973 74.4) (end 91.79 74.217) (width 0.178) (layer "F.Cu") (net 96))
  (segment (start 91.973 75.317) (end 91.973 74.4) (width 0.178) (layer "F.Cu") (net 96))
  (segment (start 91.973 73.47) (end 91.973 74.034) (width 0.178) (layer "F.Cu") (net 96))
  (segment (start 91.97 75.32) (end 91.973 75.317) (width 0.178) (layer "F.Cu") (net 96))
  (segment (start 91.973 74.034) (end 91.79 74.217) (width 0.178) (layer "F.Cu") (net 96))
  (segment (start 91.805 73.302) (end 91.973 73.47) (width 0.178) (layer "F.Cu") (net 96))
  (via (at 91.97 75.32) (size 0.45) (drill 0.1) (layers "F.Cu" "B.Cu") (net 96))
  (via (at 93.25 75.7) (size 0.45) (drill 0.1) (layers "F.Cu" "B.Cu") (net 96))
  (segment (start 93.25 75.7) (end 92.35 75.7) (width 0.109) (layer "In2.Cu") (net 96))
  (segment (start 92.35 75.7) (end 91.97 75.32) (width 0.109) (layer "In2.Cu") (net 96))
  (segment (start 93.25 76.8375) (end 93.25 75.7) (width 0.182) (layer "B.Cu") (net 96))
  (segment (start 91.993 75.336) (end 91.982 75.325) (width 0.178) (layer "B.Cu") (net 96))
  (segment (start 91.993 76.082) (end 91.993 75.336) (width 0.178) (layer "B.Cu") (net 96))
  (segment (start 91.993 76.7945) (end 91.993 76.082) (width 0.178) (layer "B.Cu") (net 96))
  (segment (start 91.95 76.8375) (end 91.993 76.7945) (width 0.178) (layer "B.Cu") (net 96))
  (segment (start 91.973 72.164) (end 91.805 72.332) (width 0.178) (layer "F.Cu") (net 97))
  (segment (start 92.1 68.775) (end 92.1 69.125) (width 0.178) (layer "F.Cu") (net 97))
  (segment (start 91.973 69.252) (end 91.973 71.234) (width 0.178) (layer "F.Cu") (net 97))
  (segment (start 92.1 69.125) (end 91.973 69.252) (width 0.178) (layer "F.Cu") (net 97))
  (segment (start 91.973 71.6) (end 91.973 72.164) (width 0.178) (layer "F.Cu") (net 97))
  (segment (start 91.973 71.234) (end 91.79 71.417) (width 0.178) (layer "F.Cu") (net 97))
  (segment (start 91.79 71.417) (end 91.973 71.6) (width 0.178) (layer "F.Cu") (net 97))
  (segment (start 92.537 75.317) (end 92.537 74.4) (width 0.178) (layer "F.Cu") (net 98))
  (segment (start 92.54 75.32) (end 92.537 75.317) (width 0.178) (layer "F.Cu") (net 98))
  (segment (start 92.537 73.47) (end 92.537 74.034) (width 0.178) (layer "F.Cu") (net 98))
  (segment (start 92.537 74.034) (end 92.72 74.217) (width 0.178) (layer "F.Cu") (net 98))
  (segment (start 92.705 73.302) (end 92.537 73.47) (width 0.178) (layer "F.Cu") (net 98))
  (segment (start 92.537 74.4) (end 92.72 74.217) (width 0.178) (layer "F.Cu") (net 98))
  (via (at 91.3 75.7) (size 0.45) (drill 0.1) (layers "F.Cu" "B.Cu") (net 98))
  (via (at 92.54 75.32) (size 0.45) (drill 0.1) (layers "F.Cu" "B.Cu") (net 98))
  (segment (start 92.16 75.7) (end 92.54 75.32) (width 0.109) (layer "In4.Cu") (net 98))
  (segment (start 91.3 75.7) (end 92.16 75.7) (width 0.109) (layer "In4.Cu") (net 98))
  (segment (start 92.528 75.325) (end 92.528 75.439) (width 0.178) (layer "B.Cu") (net 98))
  (segment (start 92.528 75.439) (end 92.557 75.468) (width 0.178) (layer "B.Cu") (net 98))
  (segment (start 91.3 76.8375) (end 91.3 75.7) (width 0.182) (layer "B.Cu") (net 98))
  (segment (start 92.557 76.7945) (end 92.557 75.468) (width 0.178) (layer "B.Cu") (net 98))
  (segment (start 92.6 76.8375) (end 92.557 76.7945) (width 0.178) (layer "B.Cu") (net 98))
  (segment (start 92.537 72.164) (end 92.705 72.332) (width 0.178) (layer "F.Cu") (net 99))
  (segment (start 92.45 69.126) (end 92.537 69.213) (width 0.178) (layer "F.Cu") (net 99))
  (segment (start 92.537 71.234) (end 92.537 69.213) (width 0.178) (layer "F.Cu") (net 99))
  (segment (start 92.72 71.417) (end 92.537 71.234) (width 0.178) (layer "F.Cu") (net 99))
  (segment (start 92.537 71.6) (end 92.537 72.164) (width 0.178) (layer "F.Cu") (net 99))
  (segment (start 92.72 71.417) (end 92.537 71.6) (width 0.178) (layer "F.Cu") (net 99))
  (segment (start 92.45 68.775) (end 92.45 69.126) (width 0.178) (layer "F.Cu") (net 99))
  (segment (start 92.3665 100.794) (end 92.846 100.483) (width 0.182) (layer "F.Cu") (net 100))
  (segment (start 86.916 72.118) (end 86.916 72.604) (width 0.182) (layer "F.Cu") (net 100))
  (segment (start 86.6 71.802) (end 86.916 72.118) (width 0.182) (layer "F.Cu") (net 100))
  (segment (start 86.916 72.604) (end 86.82 72.7) (width 0.182) (layer "F.Cu") (net 100))
  (via (at 86.82 72.7) (size 0.45) (drill 0.1) (layers "F.Cu" "B.Cu") (net 100))
  (via (at 92.846 100.483) (size 0.45) (drill 0.1) (layers "F.Cu" "B.Cu") (net 100))
  (segment (start 86.9775 71.902186) (end 86.9775 72.5545) (width 0.109) (layer "In6.Cu") (net 100))
  (segment (start 92.846 100.483) (end 92.543 100.483) (width 0.109) (layer "In6.Cu") (net 100))
  (segment (start 87.523186 71.3565) (end 86.9775 71.902186) (width 0.109) (layer "In6.Cu") (net 100))
  (segment (start 92.4905 100.4305) (end 92.4905 99.670186) (width 0.109) (layer "In6.Cu") (net 100))
  (segment (start 88.711478 77.6) (end 88.1025 77.6) (width 0.109) (layer "In6.Cu") (net 100))
  (segment (start 85.7275 92.907186) (end 85.7275 88.452814) (width 0.109) (layer "In6.Cu") (net 100))
  (segment (start 88.711478 76.1) (end 88.35 76.1) (width 0.109) (layer "In6.Cu") (net 100))
  (segment (start 88.1025 77.6) (end 87.238522 77.6) (width 0.109) (layer "In6.Cu") (net 100))
  (segment (start 88.1025 75.005989) (end 88.1025 74.232814) (width 0.109) (layer "In6.Cu") (net 100))
  (segment (start 89.2525 71.922186) (end 88.686814 71.3565) (width 0.109) (layer "In6.Cu") (net 100))
  (segment (start 88.1025 79.1) (end 87.238522 79.1) (width 0.109) (layer "In6.Cu") (net 100))
  (segment (start 85.7275 88.452814) (end 88.1025 86.077814) (width 0.109) (layer "In6.Cu") (net 100))
  (segment (start 88.1025 86.077814) (end 88.1025 81.1025) (width 0.109) (layer "In6.Cu") (net 100))
  (segment (start 88.686814 71.3565) (end 87.523186 71.3565) (width 0.109) (layer "In6.Cu") (net 100))
  (segment (start 87.8475 78.605) (end 88.711478 78.605) (width 0.109) (layer "In6.Cu") (net 100))
  (segment (start 86.832 72.7) (end 86.82 72.7) (width 0.109) (layer "In6.Cu") (net 100))
  (segment (start 88.1025 74.232814) (end 89.2525 73.082814) (width 0.109) (layer "In6.Cu") (net 100))
  (segment (start 87.6 80.105) (end 88.711478 80.105) (width 0.109) (layer "In6.Cu") (net 100))
  (segment (start 87.8475 77.105) (end 88.711478 77.105) (width 0.109) (layer "In6.Cu") (net 100))
  (segment (start 87.238522 78.605) (end 87.8475 78.605) (width 0.109) (layer "In6.Cu") (net 100))
  (segment (start 88.1025 75.8525) (end 88.1025 75.005989) (width 0.109) (layer "In6.Cu") (net 100))
  (segment (start 88.711478 79.1) (end 88.1025 79.1) (width 0.109) (layer "In6.Cu") (net 100))
  (segment (start 92.543 100.483) (end 92.4905 100.4305) (width 0.109) (layer "In6.Cu") (net 100))
  (segment (start 92.4905 99.670186) (end 85.7275 92.907186) (width 0.109) (layer "In6.Cu") (net 100))
  (segment (start 87.6 80.6) (end 87.238522 80.6) (width 0.109) (layer "In6.Cu") (net 100))
  (segment (start 86.9775 72.5545) (end 86.832 72.7) (width 0.109) (layer "In6.Cu") (net 100))
  (segment (start 87.238522 77.105) (end 87.8475 77.105) (width 0.109) (layer "In6.Cu") (net 100))
  (segment (start 87.238522 80.105) (end 87.6 80.105) (width 0.109) (layer "In6.Cu") (net 100))
  (segment (start 89.2525 73.082814) (end 89.2525 71.922186) (width 0.109) (layer "In6.Cu") (net 100))
  (arc (start 86.991022 78.8525) (mid 87.063513 78.677491) (end 87.238522 78.605) (width 0.109) (layer "In6.Cu") (net 100))
  (arc (start 89.213978 79.6025) (mid 89.066799 79.247179) (end 88.711478 79.1) (width 0.109) (layer "In6.Cu") (net 100))
  (arc (start 89.213978 76.6025) (mid 89.066799 76.247179) (end 88.711478 76.1) (width 0.109) (layer "In6.Cu") (net 100))
  (arc (start 86.991022 80.3525) (mid 87.063513 80.177491) (end 87.238522 80.105) (width 0.109) (layer "In6.Cu") (net 100))
  (arc (start 87.238522 80.6) (mid 87.063513 80.527509) (end 86.991022 80.3525) (width 0.109) (layer "In6.Cu") (net 100))
  (arc (start 88.711478 77.105) (mid 89.066799 76.957821) (end 89.213978 76.6025) (width 0.109) (layer "In6.Cu") (net 100))
  (arc (start 88.711478 80.105) (mid 89.066799 79.957821) (end 89.213978 79.6025) (width 0.109) (layer "In6.Cu") (net 100))
  (arc (start 89.213978 78.1025) (mid 89.066799 77.747179) (end 88.711478 77.6) (width 0.109) (layer "In6.Cu") (net 100))
  (arc (start 88.1025 81.1025) (mid 87.955321 80.747179) (end 87.6 80.6) (width 0.109) (layer "In6.Cu") (net 100))
  (arc (start 87.238522 77.6) (mid 87.063513 77.527509) (end 86.991022 77.3525) (width 0.109) (layer "In6.Cu") (net 100))
  (arc (start 88.35 76.1) (mid 88.174991 76.027509) (end 88.1025 75.8525) (width 0.109) (layer "In6.Cu") (net 100))
  (arc (start 86.991022 77.3525) (mid 87.063513 77.177491) (end 87.238522 77.105) (width 0.109) (layer "In6.Cu") (net 100))
  (arc (start 88.711478 78.605) (mid 89.066799 78.457821) (end 89.213978 78.1025) (width 0.109) (layer "In6.Cu") (net 100))
  (arc (start 87.238522 79.1) (mid 87.063513 79.027509) (end 86.991022 78.8525) (width 0.109) (layer "In6.Cu") (net 100))
  (segment (start 86.6 70.832) (end 86.916 70.516) (width 0.182) (layer "F.Cu") (net 101))
  (segment (start 86.916 70.428552) (end 86.561 70.073552) (width 0.182) (layer "F.Cu") (net 101))
  (segment (start 86.263 65.618) (end 86.263 67.438) (width 0.182) (layer "F.Cu") (net 101))
  (segment (start 86.916 70.516) (end 86.916 70.428552) (width 0.182) (layer "F.Cu") (net 101))
  (segment (start 86.561 69.602251) (end 86.5 69.541251) (width 0.182) (layer "F.Cu") (net 101))
  (segment (start 86.5 67.675) (end 86.5 68.2825) (width 0.182) (layer "F.Cu") (net 101))
  (segment (start 86.561 70.073552) (end 86.561 69.602251) (width 0.182) (layer "F.Cu") (net 101))
  (segment (start 86.263 67.438) (end 86.5 67.675) (width 0.182) (layer "F.Cu") (net 101))
  (segment (start 86.498 68.365) (end 86.498 69.137) (width 0.182) (layer "F.Cu") (net 101))
  (segment (start 86.5 69.541251) (end 86.5 69.1175) (width 0.182) (layer "F.Cu") (net 101))
  (segment (start 87.294 72.604) (end 87.39 72.7) (width 0.182) (layer "F.Cu") (net 102))
  (segment (start 87.294 72.098) (end 87.294 72.604) (width 0.182) (layer "F.Cu") (net 102))
  (segment (start 91.89 100.473) (end 92.3665 100.159) (width 0.182) (layer "F.Cu") (net 102))
  (segment (start 87.59 71.802) (end 87.294 72.098) (width 0.182) (layer "F.Cu") (net 102))
  (via (at 91.89 100.473) (size 0.45) (drill 0.1) (layers "F.Cu" "B.Cu") (net 102))
  (via (at 87.39 72.7) (size 0.45) (drill 0.1) (layers "F.Cu" "B.Cu") (net 102))
  (segment (start 88.711478 77.855) (end 88.1025 77.855) (width 0.109) (layer "In6.Cu") (net 102))
  (segment (start 88.935793 72.495294) (end 88.912754 72.487232) (width 0.109) (layer "In6.Cu") (net 102))
  (segment (start 88.973719 72.525539) (end 88.95646 72.50828) (width 0.109) (layer "In6.Cu") (net 102))
  (segment (start 88.248245 71.614232) (end 88.225206 71.622294) (width 0.109) (layer "In6.Cu") (net 102))
  (segment (start 87.883793 71.622294) (end 87.860754 71.614232) (width 0.109) (layer "In6.Cu") (net 102))
  (segment (start 88.9975 72.027814) (end 88.581186 71.6115) (width 0.109) (layer "In6.Cu") (net 102))
  (segment (start 88.69361 72.44346) (end 88.680624 72.422793) (width 0.109) (layer "In6.Cu") (net 102))
  (segment (start 88.204539 71.63528) (end 88.18728 71.652539) (width 0.109) (layer "In6.Cu") (net 102))
  (segment (start 87.8365 71.6115) (end 87.628814 71.6115) (width 0.109) (layer "In6.Cu") (net 102))
  (segment (start 88.973719 72.22546) (end 88.986705 72.204793) (width 0.109) (layer "In6.Cu") (net 102))
  (segment (start 87.628814 71.6115) (end 87.2325 72.007814) (width 0.109) (layer "In6.Cu") (net 102))
  (segment (start 88.711478 79.355) (end 88.1025 79.355) (width 0.109) (layer "In6.Cu") (net 102))
  (segment (start 88.994767 72.569245) (end 88.986705 72.546206) (width 0.109) (layer "In6.Cu") (net 102))
  (segment (start 87.942767 71.696245) (end 87.934705 71.673206) (width 0.109) (layer "In6.Cu") (net 102))
  (segment (start 87.8475 78.35) (end 88.711478 78.35) (width 0.109) (layer "In6.Cu") (net 102))
  (segment (start 88.1025 79.355) (end 87.238522 79.355) (width 0.109) (layer "In6.Cu") (net 102))
  (segment (start 88.8885 72.2665) (end 88.912754 72.263767) (width 0.109) (layer "In6.Cu") (net 102))
  (segment (start 88.2725 71.6115) (end 88.248245 71.614232) (width 0.109) (layer "In6.Cu") (net 102))
  (segment (start 88.935793 72.255705) (end 88.95646 72.242719) (width 0.109) (layer "In6.Cu") (net 102))
  (segment (start 88.77883 72.4845) (end 88.754575 72.481767) (width 0.109) (layer "In6.Cu") (net 102))
  (segment (start 88.986705 72.546206) (end 88.973719 72.525539) (width 0.109) (layer "In6.Cu") (net 102))
  (segment (start 88.680624 72.328206) (end 88.69361 72.307539) (width 0.109) (layer "In6.Cu") (net 102))
  (segment (start 88.225206 71.622294) (end 88.204539 71.63528) (width 0.109) (layer "In6.Cu") (net 102))
  (segment (start 88.030245 71.908767) (end 88.007206 71.900705) (width 0.109) (layer "In6.Cu") (net 102))
  (segment (start 87.986539 71.887719) (end 87.96928 71.87046) (width 0.109) (layer "In6.Cu") (net 102))
  (segment (start 85.4725 88.347186) (end 87.8475 85.972186) (width 0.109) (layer "In6.Cu") (net 102))
  (segment (start 88.581186 71.6115) (end 88.2725 71.6115) (width 0.109) (layer "In6.Cu") (net 102))
  (segment (start 88.007206 71.900705) (end 87.986539 71.887719) (width 0.109) (layer "In6.Cu") (net 102))
  (segment (start 88.8885 72.4845) (end 88.77883 72.4845) (width 0.109) (layer "In6.Cu") (net 102))
  (segment (start 92.162 100.473) (end 92.2355 100.3995) (width 0.109) (layer "In6.Cu") (net 102))
  (segment (start 87.8475 76.85) (end 88.711478 76.85) (width 0.109) (layer "In6.Cu") (net 102))
  (segment (start 88.9975 72.5935) (end 88.994767 72.569245) (width 0.109) (layer "In6.Cu") (net 102))
  (segment (start 87.6 80.855) (end 87.238522 80.855) (width 0.109) (layer "In6.Cu") (net 102))
  (segment (start 88.672562 72.399754) (end 88.66983 72.3755) (width 0.109) (layer "In6.Cu") (net 102))
  (segment (start 88.0545 71.9115) (end 88.030245 71.908767) (width 0.109) (layer "In6.Cu") (net 102))
  (segment (start 88.18728 71.652539) (end 88.174294 71.673206) (width 0.109) (layer "In6.Cu") (net 102))
  (segment (start 88.160767 71.826754) (end 88.152705 71.849793) (width 0.109) (layer "In6.Cu") (net 102))
  (segment (start 88.710869 72.460719) (end 88.69361 72.44346) (width 0.109) (layer "In6.Cu") (net 102))
  (segment (start 88.1025 77.855) (end 87.238522 77.855) (width 0.109) (layer "In6.Cu") (net 102))
  (segment (start 88.754575 72.269232) (end 88.77883 72.2665) (width 0.109) (layer "In6.Cu") (net 102))
  (segment (start 87.8475 74.127186) (end 88.9975 72.977186) (width 0.109) (layer "In6.Cu") (net 102))
  (segment (start 87.9455 71.8025) (end 87.9455 71.7205) (width 0.109) (layer "In6.Cu") (net 102))
  (segment (start 87.6 79.85) (end 88.711478 79.85) (width 0.109) (layer "In6.Cu") (net 102))
  (segment (start 87.934705 71.673206) (end 87.921719 71.652539) (width 0.109) (layer "In6.Cu") (net 102))
  (segment (start 88.912754 72.263767) (end 88.935793 72.255705) (width 0.109) (layer "In6.Cu") (net 102))
  (segment (start 88.710869 72.29028) (end 88.731536 72.277294) (width 0.109) (layer "In6.Cu") (net 102))
  (segment (start 88.672562 72.351245) (end 88.680624 72.328206) (width 0.109) (layer "In6.Cu") (net 102))
  (segment (start 88.731536 72.473705) (end 88.710869 72.460719) (width 0.109) (layer "In6.Cu") (net 102))
  (segment (start 87.90446 71.63528) (end 87.883793 71.622294) (width 0.109) (layer "In6.Cu") (net 102))
  (segment (start 88.69361 72.307539) (end 88.710869 72.29028) (width 0.109) (layer "In6.Cu") (net 102))
  (segment (start 88.912754 72.487232) (end 88.8885 72.4845) (width 0.109) (layer "In6.Cu") (net 102))
  (segment (start 87.956294 71.849793) (end 87.948232 71.826754) (width 0.109) (layer "In6.Cu") (net 102))
  (segment (start 87.948232 71.826754) (end 87.9455 71.8025) (width 0.109) (layer "In6.Cu") (net 102))
  (segment (start 87.2325 72.007814) (end 87.2325 72.5545) (width 0.109) (layer "In6.Cu") (net 102))
  (segment (start 88.731536 72.277294) (end 88.754575 72.269232) (width 0.109) (layer "In6.Cu") (net 102))
  (segment (start 88.166232 71.696245) (end 88.1635 71.7205) (width 0.109) (layer "In6.Cu") (net 102))
  (segment (start 88.1635 71.7205) (end 88.1635 71.8025) (width 0.109) (layer "In6.Cu") (net 102))
  (segment (start 88.139719 71.87046) (end 88.12246 71.887719) (width 0.109) (layer "In6.Cu") (net 102))
  (segment (start 88.77883 72.2665) (end 88.8885 72.2665) (width 0.109) (layer "In6.Cu") (net 102))
  (segment (start 87.378 72.7) (end 87.39 72.7) (width 0.109) (layer "In6.Cu") (net 102))
  (segment (start 88.152705 71.849793) (end 88.139719 71.87046) (width 0.109) (layer "In6.Cu") (net 102))
  (segment (start 87.8475 75.005989) (end 87.8475 74.127186) (width 0.109) (layer "In6.Cu") (net 102))
  (segment (start 87.238522 79.85) (end 87.6 79.85) (width 0.109) (layer "In6.Cu") (net 102))
  (segment (start 88.1635 71.8025) (end 88.160767 71.826754) (width 0.109) (layer "In6.Cu") (net 102))
  (segment (start 87.9455 71.7205) (end 87.942767 71.696245) (width 0.109) (layer "In6.Cu") (net 102))
  (segment (start 85.4725 93.012814) (end 85.4725 88.347186) (width 0.109) (layer "In6.Cu") (net 102))
  (segment (start 88.680624 72.422793) (end 88.672562 72.399754) (width 0.109) (layer "In6.Cu") (net 102))
  (segment (start 88.754575 72.481767) (end 88.731536 72.473705) (width 0.109) (layer "In6.Cu") (net 102))
  (segment (start 88.174294 71.673206) (end 88.166232 71.696245) (width 0.109) (layer "In6.Cu") (net 102))
  (segment (start 87.2325 72.5545) (end 87.378 72.7) (width 0.109) (layer "In6.Cu") (net 102))
  (segment (start 88.12246 71.887719) (end 88.101793 71.900705) (width 0.109) (layer "In6.Cu") (net 102))
  (segment (start 87.921719 71.652539) (end 87.90446 71.63528) (width 0.109) (layer "In6.Cu") (net 102))
  (segment (start 88.078754 71.908767) (end 88.0545 71.9115) (width 0.109) (layer "In6.Cu") (net 102))
  (segment (start 92.2355 100.3995) (end 92.2355 99.775814) (width 0.109) (layer "In6.Cu") (net 102))
  (segment (start 88.994767 72.181754) (end 88.9975 72.1575) (width 0.109) (layer "In6.Cu") (net 102))
  (segment (start 88.986705 72.204793) (end 88.994767 72.181754) (width 0.109) (layer "In6.Cu") (net 102))
  (segment (start 88.95646 72.50828) (end 88.935793 72.495294) (width 0.109) (layer "In6.Cu") (net 102))
  (segment (start 92.2355 99.775814) (end 85.4725 93.012814) (width 0.109) (layer "In6.Cu") (net 102))
  (segment (start 88.101793 71.900705) (end 88.078754 71.908767) (width 0.109) (layer "In6.Cu") (net 102))
  (segment (start 87.8475 85.972186) (end 87.8475 81.1025) (width 0.109) (layer "In6.Cu") (net 102))
  (segment (start 88.95646 72.242719) (end 88.973719 72.22546) (width 0.109) (layer "In6.Cu") (net 102))
  (segment (start 88.9975 72.1575) (end 88.9975 72.027814) (width 0.109) (layer "In6.Cu") (net 102))
  (segment (start 87.8475 75.8525) (end 87.8475 75.005989) (width 0.109) (layer "In6.Cu") (net 102))
  (segment (start 88.9975 72.977186) (end 88.9975 72.5935) (width 0.109) (layer "In6.Cu") (net 102))
  (segment (start 87.238522 76.85) (end 87.8475 76.85) (width 0.109) (layer "In6.Cu") (net 102))
  (segment (start 91.89 100.473) (end 92.162 100.473) (width 0.109) (layer "In6.Cu") (net 102))
  (segment (start 87.860754 71.614232) (end 87.8365 71.6115) (width 0.109) (layer "In6.Cu") (net 102))
  (segment (start 88.66983 72.3755) (end 88.672562 72.351245) (width 0.109) (layer "In6.Cu") (net 102))
  (segment (start 87.96928 71.87046) (end 87.956294 71.849793) (width 0.109) (layer "In6.Cu") (net 102))
  (segment (start 87.238522 78.35) (end 87.8475 78.35) (width 0.109) (layer "In6.Cu") (net 102))
  (segment (start 88.711478 76.355) (end 88.35 76.355) (width 0.109) (layer "In6.Cu") (net 102))
  (arc (start 88.711478 79.85) (mid 88.886487 79.777509) (end 88.958978 79.6025) (width 0.109) (layer "In6.Cu") (net 102))
  (arc (start 88.958978 79.6025) (mid 88.886487 79.427491) (end 88.711478 79.355) (width 0.109) (layer "In6.Cu") (net 102))
  (arc (start 88.711478 76.85) (mid 88.886487 76.777509) (end 88.958978 76.6025) (width 0.109) (layer "In6.Cu") (net 102))
  (arc (start 86.736022 77.3525) (mid 86.883201 76.997179) (end 87.238522 76.85) (width 0.109) (layer "In6.Cu") (net 102))
  (arc (start 87.238522 79.355) (mid 86.883201 79.207821) (end 86.736022 78.8525) (width 0.109) (layer "In6.Cu") (net 102))
  (arc (start 87.238522 77.855) (mid 86.883201 77.707821) (end 86.736022 77.3525) (width 0.109) (layer "In6.Cu") (net 102))
  (arc (start 87.238522 80.855) (mid 86.883201 80.707821) (end 86.736022 80.3525) (width 0.109) (layer "In6.Cu") (net 102))
  (arc (start 88.958978 78.1025) (mid 88.886487 77.927491) (end 88.711478 77.855) (width 0.109) (layer "In6.Cu") (net 102))
  (arc (start 86.736022 78.8525) (mid 86.883201 78.497179) (end 87.238522 78.35) (width 0.109) (layer "In6.Cu") (net 102))
  (arc (start 87.8475 81.1025) (mid 87.775009 80.927491) (end 87.6 80.855) (width 0.109) (layer "In6.Cu") (net 102))
  (arc (start 88.35 76.355) (mid 87.994679 76.207821) (end 87.8475 75.8525) (width 0.109) (layer "In6.Cu") (net 102))
  (arc (start 86.736022 80.3525) (mid 86.883201 79.997179) (end 87.238522 79.85) (width 0.109) (layer "In6.Cu") (net 102))
  (arc (start 88.711478 78.35) (mid 88.886487 78.277509) (end 88.958978 78.1025) (width 0.109) (layer "In6.Cu") (net 102))
  (arc (start 88.958978 76.6025) (mid 88.886487 76.427491) (end 88.711478 76.355) (width 0.109) (layer "In6.Cu") (net 102))
  (segment (start 87.59 70.832) (end 87.294 70.536) (width 0.182) (layer "F.Cu") (net 103))
  (segment (start 86.998 68.365) (end 86.998 69.137) (width 0.182) (layer "F.Cu") (net 103))
  (segment (start 87 69.541251) (end 87 69.1175) (width 0.182) (layer "F.Cu") (net 103))
  (segment (start 87 67.7) (end 87 68.2825) (width 0.182) (layer "F.Cu") (net 103))
  (segment (start 86.939 69.602251) (end 87 69.541251) (width 0.182) (layer "F.Cu") (net 103))
  (segment (start 87.263 67.437) (end 87 67.7) (width 0.182) (layer "F.Cu") (net 103))
  (segment (start 87.294 70.536) (end 87.294 70.271976) (width 0.182) (layer "F.Cu") (net 103))
  (segment (start 86.939 69.916976) (end 86.939 69.602251) (width 0.182) (layer "F.Cu") (net 103))
  (segment (start 87.263 65.618) (end 87.263 67.437) (width 0.182) (layer "F.Cu") (net 103))
  (segment (start 87.294 70.271976) (end 86.939 69.916976) (width 0.182) (layer "F.Cu") (net 103))
  (segment (start 132.315 137.2) (end 132.515 137.4) (width 0.2) (layer "F.Cu") (net 104))
  (segment (start 134.899981 138.3) (end 133.29 138.3) (width 0.2) (layer "F.Cu") (net 104))
  (segment (start 134.899991 138.30001) (end 134.899981 138.3) (width 0.2) (layer "F.Cu") (net 104))
  (segment (start 132.515 137.525) (end 132.515 137.4) (width 0.2) (layer "F.Cu") (net 104))
  (segment (start 137.233 137.982) (end 137.215 138) (width 0.2) (layer "F.Cu") (net 104))
  (segment (start 131.775 137.175) (end 131.8 137.2) (width 0.182) (layer "F.Cu") (net 104))
  (segment (start 137.2 138) (end 136.89999 138.30001) (width 0.2) (layer "F.Cu") (net 104))
  (segment (start 137.233 137.114001) (end 137.233 137.982) (width 0.2) (layer "F.Cu") (net 104))
  (segment (start 133.29 138.3) (end 132.515 137.525) (width 0.2) (layer "F.Cu") (net 104))
  (segment (start 136.89999 138.30001) (end 134.899991 138.30001) (width 0.2) (layer "F.Cu") (net 104))
  (segment (start 131.1 137.175) (end 131.775 137.175) (width 0.182) (layer "F.Cu") (net 104))
  (segment (start 132.515 137.4) (end 132.515 137.415) (width 0.182) (layer "F.Cu") (net 104))
  (segment (start 137.215 138) (end 137.2 138) (width 0.2) (layer "F.Cu") (net 104))
  (segment (start 131.8 137.2) (end 132.315 137.2) (width 0.2) (layer "F.Cu") (net 104))
  (segment (start 137.233 135.633999) (end 137.233 137.114001) (width 0.2) (layer "F.Cu") (net 104))
  (segment (start 93.263 67.213) (end 93.3 67.25) (width 0.182) (layer "F.Cu") (net 105))
  (segment (start 93.3 67.25) (end 93.3 67.825) (width 0.182) (layer "F.Cu") (net 105))
  (segment (start 93.263 67.924) (end 93.361 67.924) (width 0.182) (layer "F.Cu") (net 105))
  (segment (start 93.361 67.924) (end 93.38 67.905) (width 0.182) (layer "F.Cu") (net 105))
  (segment (start 93.3 67.825) (end 93.38 67.905) (width 0.182) (layer "F.Cu") (net 105))
  (segment (start 93.263 65.618) (end 93.263 67.213) (width 0.182) (layer "F.Cu") (net 105))
  (via (at 91.9 85.05) (size 0.45) (drill 0.1) (layers "F.Cu" "B.Cu") (net 105))
  (via (at 93.3 67.25) (size 0.45) (drill 0.1) (layers "F.Cu" "B.Cu") (net 105))
  (segment (start 93.3 67.55) (end 93.3 67.25) (width 0.109) (layer "In6.Cu") (net 105))
  (segment (start 91.9 85.05) (end 91.9 84) (width 0.109) (layer "In6.Cu") (net 105))
  (segment (start 91.9 84) (end 94.7 81.2) (width 0.109) (layer "In6.Cu") (net 105))
  (segment (start 94.7 68.95) (end 93.3 67.55) (width 0.109) (layer "In6.Cu") (net 105))
  (segment (start 94.7 81.2) (end 94.7 68.95) (width 0.109) (layer "In6.Cu") (net 105))
  (segment (start 92.755 85.3) (end 92.178682 85.3) (width 0.182) (layer "B.Cu") (net 105))
  (segment (start 92.178682 85.3) (end 91.928682 85.05) (width 0.182) (layer "B.Cu") (net 105))
  (segment (start 91.928682 85.05) (end 91.9 85.05) (width 0.182) (layer "B.Cu") (net 105))
  (segment (start 89.8265 116.034) (end 90.158032 115.702468) (width 0.182) (layer "F.Cu") (net 106))
  (segment (start 90.158032 115.702468) (end 90.3 115.702468) (width 0.182) (layer "F.Cu") (net 106))
  (segment (start 125.225 141.3) (end 125.225 137.62) (width 0.182) (layer "F.Cu") (net 106))
  (segment (start 125.205 137.6) (end 124.59 137.6) (width 0.182) (layer "F.Cu") (net 106))
  (segment (start 125.225 137.62) (end 125.205 137.6) (width 0.182) (layer "F.Cu") (net 106))
  (via (at 124.59 137.6) (size 0.45) (drill 0.1) (layers "F.Cu" "B.Cu") (net 106))
  (via (at 96 119.55) (size 0.45) (drill 0.1) (layers "F.Cu" "B.Cu") (net 106))
  (via (at 90.3 115.702468) (size 0.45) (drill 0.1) (layers "F.Cu" "B.Cu") (net 106))
  (segment (start 115.12 137.6) (end 101.593059 124.073059) (width 0.109) (layer "In2.Cu") (net 106))
  (segment (start 101.593059 123.372325) (end 101.594501 123.370883) (width 0.109) (layer "In2.Cu") (net 106))
  (segment (start 97.179779 119.220221) (end 96.85 119.55) (width 0.109) (layer "In2.Cu") (net 106))
  (segment (start 100.136161 119.220221) (end 97.179779 119.220221) (width 0.109) (layer "In2.Cu") (net 106))
  (segment (start 101.594501 120.678561) (end 100.136161 119.220221) (width 0.109) (layer "In2.Cu") (net 106))
  (segment (start 101.594501 123.370883) (end 101.594501 120.678561) (width 0.109) (layer "In2.Cu") (net 106))
  (segment (start 101.593059 124.073059) (end 101.593059 123.372325) (width 0.109) (layer "In2.Cu") (net 106))
  (segment (start 124.59 137.6) (end 115.12 137.6) (width 0.109) (layer "In2.Cu") (net 106))
  (segment (start 96.85 119.55) (end 96 119.55) (width 0.109) (layer "In2.Cu") (net 106))
  (segment (start 90.798766 116.201234) (end 90.3 115.702468) (width 0.109) (layer "In6.Cu") (net 106))
  (segment (start 92.301234 116.201234) (end 92.65 116.55) (width 0.109) (layer "In6.Cu") (net 106))
  (segment (start 90.798766 116.201234) (end 92.301234 116.201234) (width 0.109) (layer "In6.Cu") (net 106))
  (segment (start 95.075 117.375) (end 94.25 116.55) (width 0.109) (layer "In6.Cu") (net 106))
  (segment (start 94.25 116.55) (end 92.65 116.55) (width 0.109) (layer "In6.Cu") (net 106))
  (segment (start 95.075 119.365) (end 95.075 117.375) (width 0.109) (layer "In6.Cu") (net 106))
  (segment (start 95.26 119.55) (end 95.075 119.365) (width 0.109) (layer "In6.Cu") (net 106))
  (segment (start 96 119.55) (end 95.26 119.55) (width 0.109) (layer "In6.Cu") (net 106))
  (segment (start 93.3265 104.604) (end 93.806 104.293) (width 0.182) (layer "F.Cu") (net 107))
  (segment (start 115.150063 119.9054) (end 115.150063 118.492937) (width 0.178) (layer "F.Cu") (net 107))
  (segment (start 115.293 118.35) (end 115.150063 118.492937) (width 0.178) (layer "F.Cu") (net 107))
  (via (at 93.806 104.293) (size 0.45) (drill 0.1) (layers "F.Cu" "B.Cu") (net 107))
  (via (at 115.293 118.35) (size 0.45) (drill 0.1) (layers "F.Cu" "B.Cu") (net 107))
  (segment (start 92.9375 105.1615) (end 93.806 104.293) (width 0.107) (layer "In4.Cu") (net 107))
  (segment (start 87.250334 119.278624) (end 87.264855 119.2695) (width 0.107) (layer "In4.Cu") (net 107))
  (segment (start 108.90825 115.3785) (end 105.53325 118.7535) (width 0.107) (layer "In4.Cu") (net 107))
  (segment (start 87.331313 119.254331) (end 87.345834 119.245207) (width 0.107) (layer "In4.Cu") (net 107))
  (segment (start 87.345834 119.245207) (end 87.35796 119.233081) (width 0.107) (layer "In4.Cu") (net 107))
  (segment (start 87.2215 119.60825) (end 87.2215 119.3385) (width 0.107) (layer "In4.Cu") (net 107))
  (segment (start 97.44325 118.7535) (end 96.26825 119.9285) (width 0.107) (layer "In4.Cu") (net 107))
  (segment (start 115.1215 118.1785) (end 115.1215 117.25825) (width 0.107) (layer "In4.Cu") (net 107))
  (segment (start 105.53325 118.7535) (end 97.44325 118.7535) (width 0.107) (layer "In4.Cu") (net 107))
  (segment (start 87.250334 119.031207) (end 87.238208 119.019081) (width 0.107) (layer "In4.Cu") (net 107))
  (segment (start 87.315126 119.259995) (end 87.331313 119.254331) (width 0.107) (layer "In4.Cu") (net 107))
  (segment (start 87.2215 118.971332) (end 87.2215 105.94175) (width 0.107) (layer "In4.Cu") (net 107))
  (segment (start 87.281042 119.045995) (end 87.264855 119.040331) (width 0.107) (layer "In4.Cu") (net 107))
  (segment (start 87.238208 119.29075) (end 87.250334 119.278624) (width 0.107) (layer "In4.Cu") (net 107))
  (segment (start 87.345834 119.064624) (end 87.331313 119.0555) (width 0.107) (layer "In4.Cu") (net 107))
  (segment (start 87.372748 119.107458) (end 87.367084 119.091271) (width 0.107) (layer "In4.Cu") (net 107))
  (segment (start 96.26825 119.9285) (end 87.54175 119.9285) (width 0.107) (layer "In4.Cu") (net 107))
  (segment (start 87.35796 119.07675) (end 87.345834 119.064624) (width 0.107) (layer "In4.Cu") (net 107))
  (segment (start 87.264855 119.2695) (end 87.281042 119.263836) (width 0.107) (layer "In4.Cu") (net 107))
  (segment (start 115.293 118.35) (end 115.1215 118.1785) (width 0.107) (layer "In4.Cu") (net 107))
  (segment (start 87.367084 119.21856) (end 87.372748 119.202373) (width 0.107) (layer "In4.Cu") (net 107))
  (segment (start 87.22342 118.988373) (end 87.2215 118.971332) (width 0.107) (layer "In4.Cu") (net 107))
  (segment (start 115.1215 117.25825) (end 113.24175 115.3785) (width 0.107) (layer "In4.Cu") (net 107))
  (segment (start 87.2215 119.3385) (end 87.22342 119.321458) (width 0.107) (layer "In4.Cu") (net 107))
  (segment (start 87.315126 119.049836) (end 87.281042 119.045995) (width 0.107) (layer "In4.Cu") (net 107))
  (segment (start 87.367084 119.091271) (end 87.35796 119.07675) (width 0.107) (layer "In4.Cu") (net 107))
  (segment (start 87.281042 119.263836) (end 87.315126 119.259995) (width 0.107) (layer "In4.Cu") (net 107))
  (segment (start 113.24175 115.3785) (end 108.90825 115.3785) (width 0.107) (layer "In4.Cu") (net 107))
  (segment (start 87.54175 119.9285) (end 87.2215 119.60825) (width 0.107) (layer "In4.Cu") (net 107))
  (segment (start 87.374669 119.1245) (end 87.372748 119.107458) (width 0.107) (layer "In4.Cu") (net 107))
  (segment (start 87.229084 119.305271) (end 87.238208 119.29075) (width 0.107) (layer "In4.Cu") (net 107))
  (segment (start 87.229084 119.00456) (end 87.22342 118.988373) (width 0.107) (layer "In4.Cu") (net 107))
  (segment (start 87.374669 119.185332) (end 87.374669 119.1245) (width 0.107) (layer "In4.Cu") (net 107))
  (segment (start 87.35796 119.233081) (end 87.367084 119.21856) (width 0.107) (layer "In4.Cu") (net 107))
  (segment (start 87.2215 105.94175) (end 88.00175 105.1615) (width 0.107) (layer "In4.Cu") (net 107))
  (segment (start 87.22342 119.321458) (end 87.229084 119.305271) (width 0.107) (layer "In4.Cu") (net 107))
  (segment (start 87.238208 119.019081) (end 87.229084 119.00456) (width 0.107) (layer "In4.Cu") (net 107))
  (segment (start 87.264855 119.040331) (end 87.250334 119.031207) (width 0.107) (layer "In4.Cu") (net 107))
  (segment (start 88.00175 105.1615) (end 92.9375 105.1615) (width 0.107) (layer "In4.Cu") (net 107))
  (segment (start 87.331313 119.0555) (end 87.315126 119.049836) (width 0.107) (layer "In4.Cu") (net 107))
  (segment (start 87.372748 119.202373) (end 87.374669 119.185332) (width 0.107) (layer "In4.Cu") (net 107))
  (segment (start 92.85 104.283) (end 93.3265 103.969) (width 0.182) (layer "F.Cu") (net 108))
  (segment (start 114.507 118.35) (end 114.649937 118.492937) (width 0.178) (layer "F.Cu") (net 108))
  (segment (start 114.649937 119.9054) (end 114.649937 118.492937) (width 0.178) (layer "F.Cu") (net 108))
  (via (at 92.85 104.283) (size 0.45) (drill 0.1) (layers "F.Cu" "B.Cu") (net 108))
  (via (at 114.507 118.35) (size 0.45) (drill 0.1) (layers "F.Cu" "B.Cu") (net 108))
  (segment (start 113.448375 116.423757) (end 113.435265 116.436866) (width 0.107) (layer "In4.Cu") (net 108))
  (segment (start 113.469317 116.397495) (end 113.448375 116.423757) (width 0.107) (layer "In4.Cu") (net 108))
  (segment (start 113.558125 116.691988) (end 113.590872 116.684514) (width 0.107) (layer "In4.Cu") (net 108))
  (segment (start 113.491365 116.300896) (end 113.491365 116.334485) (width 0.107) (layer "In4.Cu") (net 108))
  (segment (start 113.816113 116.600372) (end 113.846376 116.614946) (width 0.107) (layer "In4.Cu") (net 108))
  (segment (start 113.71703 116.600372) (end 113.749777 116.592898) (width 0.107) (layer "In4.Cu") (net 108))
  (segment (start 113.590872 116.684514) (end 113.621135 116.66994) (width 0.107) (layer "In4.Cu") (net 108))
  (segment (start 113.491789 116.684514) (end 113.524536 116.691988) (width 0.107) (layer "In4.Cu") (net 108))
  (segment (start 86.7785 105.75825) (end 86.7785 119.79175) (width 0.107) (layer "In4.Cu") (net 108))
  (segment (start 113.647397 116.648998) (end 113.660506 116.635888) (width 0.107) (layer "In4.Cu") (net 108))
  (segment (start 114.6785 117.44175) (end 114.6785 118.1785) (width 0.107) (layer "In4.Cu") (net 108))
  (segment (start 113.686767 116.614946) (end 113.71703 116.600372) (width 0.107) (layer "In4.Cu") (net 108))
  (segment (start 113.399749 116.592473) (end 113.414323 116.622736) (width 0.107) (layer "In4.Cu") (net 108))
  (segment (start 113.469317 116.237886) (end 113.483891 116.268149) (width 0.107) (layer "In4.Cu") (net 108))
  (segment (start 113.448375 116.211625) (end 113.469317 116.237886) (width 0.107) (layer "In4.Cu") (net 108))
  (segment (start 113.749777 116.592898) (end 113.783366 116.592898) (width 0.107) (layer "In4.Cu") (net 108))
  (segment (start 105.71675 119.1965) (end 109.09175 115.8215) (width 0.107) (layer "In4.Cu") (net 108))
  (segment (start 87.81825 104.7185) (end 86.7785 105.75825) (width 0.107) (layer "In4.Cu") (net 108))
  (segment (start 113.846376 116.614946) (end 113.872639 116.635889) (width 0.107) (layer "In4.Cu") (net 108))
  (segment (start 113.491365 116.334485) (end 113.483891 116.367232) (width 0.107) (layer "In4.Cu") (net 108))
  (segment (start 113.392275 116.526137) (end 113.392275 116.559726) (width 0.107) (layer "In4.Cu") (net 108))
  (segment (start 113.392275 116.559726) (end 113.399749 116.592473) (width 0.107) (layer "In4.Cu") (net 108))
  (segment (start 113.435265 116.436866) (end 113.414323 116.463127) (width 0.107) (layer "In4.Cu") (net 108))
  (segment (start 113.414323 116.622736) (end 113.435265 116.648998) (width 0.107) (layer "In4.Cu") (net 108))
  (segment (start 113.483891 116.367232) (end 113.469317 116.397495) (width 0.107) (layer "In4.Cu") (net 108))
  (segment (start 113.461526 116.66994) (end 113.491789 116.684514) (width 0.107) (layer "In4.Cu") (net 108))
  (segment (start 113.05825 115.8215) (end 113.448375 116.211625) (width 0.107) (layer "In4.Cu") (net 108))
  (segment (start 96.45175 120.3715) (end 97.62675 119.1965) (width 0.107) (layer "In4.Cu") (net 108))
  (segment (start 114.6785 118.1785) (end 114.507 118.35) (width 0.107) (layer "In4.Cu") (net 108))
  (segment (start 113.783366 116.592898) (end 113.816113 116.600372) (width 0.107) (layer "In4.Cu") (net 108))
  (segment (start 97.62675 119.1965) (end 105.71675 119.1965) (width 0.107) (layer "In4.Cu") (net 108))
  (segment (start 113.872639 116.635889) (end 114.6785 117.44175) (width 0.107) (layer "In4.Cu") (net 108))
  (segment (start 86.7785 119.79175) (end 87.35825 120.3715) (width 0.107) (layer "In4.Cu") (net 108))
  (segment (start 109.09175 115.8215) (end 113.05825 115.8215) (width 0.107) (layer "In4.Cu") (net 108))
  (segment (start 92.85 104.283) (end 92.85 104.622503) (width 0.107) (layer "In4.Cu") (net 108))
  (segment (start 113.435265 116.648998) (end 113.461526 116.66994) (width 0.107) (layer "In4.Cu") (net 108))
  (segment (start 113.414323 116.463127) (end 113.399749 116.49339) (width 0.107) (layer "In4.Cu") (net 108))
  (segment (start 113.399749 116.49339) (end 113.392275 116.526137) (width 0.107) (layer "In4.Cu") (net 108))
  (segment (start 113.524536 116.691988) (end 113.558125 116.691988) (width 0.107) (layer "In4.Cu") (net 108))
  (segment (start 92.754003 104.7185) (end 87.81825 104.7185) (width 0.107) (layer "In4.Cu") (net 108))
  (segment (start 92.85 104.622503) (end 92.754003 104.7185) (width 0.107) (layer "In4.Cu") (net 108))
  (segment (start 113.660506 116.635888) (end 113.686767 116.614946) (width 0.107) (layer "In4.Cu") (net 108))
  (segment (start 113.621135 116.66994) (end 113.647397 116.648998) (width 0.107) (layer "In4.Cu") (net 108))
  (segment (start 113.483891 116.268149) (end 113.491365 116.300896) (width 0.107) (layer "In4.Cu") (net 108))
  (segment (start 87.35825 120.3715) (end 96.45175 120.3715) (width 0.107) (layer "In4.Cu") (net 108))
  (segment (start 136.232999 135.633999) (end 136.232999 135.032999) (width 0.182) (layer "F.Cu") (net 109))
  (segment (start 92.685509 115.714991) (end 92.84 115.714991) (width 0.182) (layer "F.Cu") (net 109))
  (segment (start 136.232999 135.032999) (end 136.2 135) (width 0.182) (layer "F.Cu") (net 109))
  (segment (start 92.3665 116.034) (end 92.685509 115.714991) (width 0.182) (layer "F.Cu") (net 109))
  (via (at 92.84 115.714991) (size 0.45) (drill 0.1) (layers "F.Cu" "B.Cu") (net 109))
  (via (at 136.2 135) (size 0.45) (drill 0.1) (layers "F.Cu" "B.Cu") (net 109))
  (segment (start 113.1 124.8) (end 107.3 124.8) (width 0.109) (layer "In6.Cu") (net 109))
  (segment (start 123.220499 134.920499) (end 113.1 124.8) (width 0.109) (layer "In6.Cu") (net 109))
  (segment (start 96.640557 117.951723) (end 95.840557 117.951723) (width 0.109) (layer "In6.Cu") (net 109))
  (segment (start 95.840557 117.951723) (end 95.390557 117.501723) (width 0.109) (layer "In6.Cu") (net 109))
  (segment (start 136.2 135) (end 127.886662 135) (width 0.109) (layer "In6.Cu") (net 109))
  (segment (start 127.886662 135) (end 127.807161 134.920499) (width 0.109) (layer "In6.Cu") (net 109))
  (segment (start 93.325009 116.2) (end 92.84 115.714991) (width 0.109) (layer "In6.Cu") (net 109))
  (segment (start 127.807161 134.920499) (end 123.220499 134.920499) (width 0.109) (layer "In6.Cu") (net 109))
  (segment (start 94.49228 116.2) (end 93.325009 116.2) (width 0.109) (layer "In6.Cu") (net 109))
  (segment (start 95.390557 117.501723) (end 95.390557 117.098277) (width 0.109) (layer "In6.Cu") (net 109))
  (segment (start 107.3 124.8) (end 101.69614 119.19614) (width 0.109) (layer "In6.Cu") (net 109))
  (segment (start 97.884974 119.19614) (end 96.640557 117.951723) (width 0.109) (layer "In6.Cu") (net 109))
  (segment (start 95.390557 117.098277) (end 94.49228 116.2) (width 0.109) (layer "In6.Cu") (net 109))
  (segment (start 101.69614 119.19614) (end 97.884974 119.19614) (width 0.109) (layer "In6.Cu") (net 109))
  (segment (start 96.768198 116.6) (end 96.568198 116.4) (width 0.182) (layer "F.Cu") (net 110))
  (segment (start 92.3665 114.129) (end 92.84 113.815) (width 0.182) (layer "F.Cu") (net 110))
  (segment (start 96.568198 116.4) (end 96.25 116.4) (width 0.182) (layer "F.Cu") (net 110))
  (segment (start 96.768198 116.6) (end 97.24 116.6) (width 0.182) (layer "F.Cu") (net 110))
  (via (at 96.25 116.4) (size 0.45) (drill 0.1) (layers "F.Cu" "B.Cu") (net 110))
  (via (at 92.84 113.815) (size 0.45) (drill 0.1) (layers "F.Cu" "B.Cu") (net 110))
  (segment (start 93.81 113.7) (end 93.81 113.65) (width 0.109) (layer "In4.Cu") (net 110))
  (segment (start 93.813134 113.622185) (end 93.822378 113.595765) (width 0.109) (layer "In4.Cu") (net 110))
  (segment (start 93.739235 113.812622) (end 93.762936 113.797729) (width 0.109) (layer "In4.Cu") (net 110))
  (segment (start 93.489235 113.537379) (end 93.512936 113.552272) (width 0.109) (layer "In4.Cu") (net 110))
  (segment (start 93.337271 113.572064) (end 93.357063 113.552272) (width 0.109) (layer "In4.Cu") (net 110))
  (segment (start 93.572378 113.754236) (end 93.587271 113.777937) (width 0.109) (layer "In4.Cu") (net 110))
  (segment (start 95.245825 114.002383) (end 95.239597 114.029673) (width 0.109) (layer "In4.Cu") (net 110))
  (segment (start 94.407184 113.478135) (end 94.435 113.475) (width 0.109) (layer "In4.Cu") (net 110))
  (segment (start 94.56 113.925) (end 94.562507 113.947252) (width 0.109) (layer "In4.Cu") (net 110))
  (segment (start 94.06 113.7) (end 94.063134 113.727816) (width 0.109) (layer "In4.Cu") (net 110))
  (segment (start 95.629318 114.028511) (end 95.656608 114.022284) (width 0.109) (layer "In4.Cu") (net 110))
  (segment (start 95.794816 114.160491) (end 95.788588 114.187781) (width 0.109) (layer "In4.Cu") (net 110))
  (segment (start 94.831816 113.862651) (end 94.847651 113.846816) (width 0.109) (layer "In4.Cu") (net 110))
  (segment (start 95.238438 114.301814) (end 95.265727 114.308042) (width 0.109) (layer "In4.Cu") (net 110))
  (segment (start 95.776443 114.213) (end 95.758991 114.234884) (width 0.109) (layer "In4.Cu") (net 110))
  (segment (start 95.155509 114.169833) (end 95.155509 114.197824) (width 0.109) (layer "In4.Cu") (net 110))
  (segment (start 94.047621 113.595765) (end 94.056865 113.622185) (width 0.109) (layer "In4.Cu") (net 110))
  (segment (start 95.788588 114.105211) (end 95.794817 114.132501) (width 0.109) (layer "In4.Cu") (net 110))
  (segment (start 93.907184 113.528135) (end 93.935 113.525) (width 0.109) (layer "In4.Cu") (net 110))
  (segment (start 94.380764 113.487379) (end 94.407184 113.478135) (width 0.109) (layer "In4.Cu") (net 110))
  (segment (start 94.06 113.65) (end 94.06 113.7) (width 0.109) (layer "In4.Cu") (net 110))
  (segment (start 94.357063 113.502272) (end 94.380764 113.487379) (width 0.109) (layer "In4.Cu") (net 110))
  (segment (start 93.313134 113.622185) (end 93.322378 113.595765) (width 0.109) (layer "In4.Cu") (net 110))
  (segment (start 95.227452 113.921884) (end 95.239597 113.947103) (width 0.109) (layer "In4.Cu") (net 110))
  (segment (start 93.462815 113.528135) (end 93.489235 113.537379) (width 0.109) (layer "In4.Cu") (net 110))
  (segment (start 93.380764 113.537379) (end 93.407184 113.528135) (width 0.109) (layer "In4.Cu") (net 110))
  (segment (start 93.407184 113.528135) (end 93.435 113.525) (width 0.109) (layer "In4.Cu") (net 110))
  (segment (start 95.740327 114.253549) (end 95.722874 114.275433) (width 0.109) (layer "In4.Cu") (net 110))
  (segment (start 96.75 115.44) (end 96.75 116.175) (width 0.109) (layer "In4.Cu") (net 110))
  (segment (start 94.800096 113.968388) (end 94.807492 113.947252) (width 0.109) (layer "In4.Cu") (net 110))
  (segment (start 93.512936 113.552272) (end 93.532728 113.572064) (width 0.109) (layer "In4.Cu") (net 110))
  (segment (start 95.293718 114.308042) (end 95.321008 114.301814) (width 0.109) (layer "In4.Cu") (net 110))
  (segment (start 93.857063 113.552272) (end 93.880764 113.537379) (width 0.109) (layer "In4.Cu") (net 110))
  (segment (start 93.306865 113.727816) (end 93.31 113.7) (width 0.109) (layer "In4.Cu") (net 110))
  (segment (start 94.239235 113.812622) (end 94.262936 113.797729) (width 0.109) (layer "In4.Cu") (net 110))
  (segment (start 94.812507 113.902747) (end 94.819903 113.881611) (width 0.109) (layer "In4.Cu") (net 110))
  (segment (start 94.562507 113.947252) (end 94.569903 113.968388) (width 0.109) (layer "In4.Cu") (net 110))
  (segment (start 94.282728 113.777937) (end 94.297621 113.754236) (width 0.109) (layer "In4.Cu") (net 110))
  (segment (start 96.525 116.4) (end 96.25 116.4) (width 0.109) (layer "In4.Cu") (net 110))
  (segment (start 93.685 113.825) (end 93.712815 113.821866) (width 0.109) (layer "In4.Cu") (net 110))
  (segment (start 95.245825 113.974392) (end 95.245825 114.002383) (width 0.109) (layer "In4.Cu") (net 110))
  (segment (start 95.740326 114.430325) (end 96.75 115.44) (width 0.109) (layer "In4.Cu") (net 110))
  (segment (start 95.161738 114.142544) (end 95.155509 114.169833) (width 0.109) (layer "In4.Cu") (net 110))
  (segment (start 93.797621 113.754236) (end 93.806865 113.727816) (width 0.109) (layer "In4.Cu") (net 110))
  (segment (start 93.563134 113.727816) (end 93.572378 113.754236) (width 0.109) (layer "In4.Cu") (net 110))
  (segment (start 93.806865 113.727816) (end 93.81 113.7) (width 0.109) (layer "In4.Cu") (net 110))
  (segment (start 93.630764 113.812622) (end 93.657184 113.821866) (width 0.109) (layer "In4.Cu") (net 110))
  (segment (start 94.337271 113.522064) (end 94.357063 113.502272) (width 0.109) (layer "In4.Cu") (net 110))
  (segment (start 93.962815 113.528135) (end 93.989235 113.537379) (width 0.109) (layer "In4.Cu") (net 110))
  (segment (start 94.753388 114.015096) (end 94.772348 114.003183) (width 0.109) (layer "In4.Cu") (net 110))
  (segment (start 94.31 113.7) (end 94.31 113.6) (width 0.109) (layer "In4.Cu") (net 110))
  (segment (start 94.866611 113.834903) (end 94.887747 113.827507) (width 0.109) (layer "In4.Cu") (net 110))
  (segment (start 94.772348 114.003183) (end 94.788183 113.987348) (width 0.109) (layer "In4.Cu") (net 110))
  (segment (start 95.704501 114.355933) (end 95.710729 114.383222) (width 0.109) (layer "In4.Cu") (net 110))
  (segment (start 95.227452 114.054892) (end 95.21 114.076776) (width 0.109) (layer "In4.Cu") (net 110))
  (segment (start 93.56 113.7) (end 93.563134 113.727816) (width 0.109) (layer "In4.Cu") (net 110))
  (segment (start 95.191335 114.09544) (end 95.173883 114.117325) (width 0.109) (layer "In4.Cu") (net 110))
  (segment (start 95.710729 114.300652) (end 95.7045 114.327941) (width 0.109) (layer "In4.Cu") (net 110))
  (segment (start 94.157184 113.821866) (end 94.185 113.825) (width 0.109) (layer "In4.Cu") (net 110))
  (segment (start 94.462815 113.478135) (end 94.489235 113.487379) (width 0.109) (layer "In4.Cu") (net 110))
  (segment (start 94.107063 113.797729) (end 94.130764 113.812622) (width 0.109) (layer "In4.Cu") (net 110))
  (segment (start 94.556865 113.572185) (end 94.56 113.6) (width 0.109) (layer "In4.Cu") (net 110))
  (segment (start 93.989235 113.537379) (end 94.012936 113.552272) (width 0.109) (layer "In4.Cu") (net 110))
  (segment (start 93.935 113.525) (end 93.962815 113.528135) (width 0.109) (layer "In4.Cu") (net 110))
  (segment (start 94.819903 113.881611) (end 94.831816 113.862651) (width 0.109) (layer "In4.Cu") (net 110))
  (segment (start 93.657184 113.821866) (end 93.685 113.825) (width 0.109) (layer "In4.Cu") (net 110))
  (segment (start 95.386775 114.253552) (end 95.582217 114.05811) (width 0.109) (layer "In4.Cu") (net 110))
  (segment (start 94.788183 113.987348) (end 94.800096 113.968388) (width 0.109) (layer "In4.Cu") (net 110))
  (segment (start 94.012936 113.552272) (end 94.032728 113.572064) (width 0.109) (layer "In4.Cu") (net 110))
  (segment (start 94.66 114.025) (end 94.71 114.025) (width 0.109) (layer "In4.Cu") (net 110))
  (segment (start 95.161738 114.225114) (end 95.173883 114.250333) (width 0.109) (layer "In4.Cu") (net 110))
  (segment (start 94.435 113.475) (end 94.462815 113.478135) (width 0.109) (layer "In4.Cu") (net 110))
  (segment (start 96.75 116.175) (end 96.525 116.4) (width 0.109) (layer "In4.Cu") (net 110))
  (segment (start 94.887747 113.827507) (end 94.91 113.825) (width 0.109) (layer "In4.Cu") (net 110))
  (segment (start 95.346227 114.289669) (end 95.368111 114.272217) (width 0.109) (layer "In4.Cu") (net 110))
  (segment (start 94.322378 113.545765) (end 94.337271 113.522064) (width 0.109) (layer "In4.Cu") (net 110))
  (segment (start 95.6846 114.022284) (end 95.711888 114.028511) (width 0.109) (layer "In4.Cu") (net 110))
  (segment (start 92.85 113.825) (end 93.185 113.825) (width 0.109) (layer "In4.Cu") (net 110))
  (segment (start 95.656608 114.022284) (end 95.6846 114.022284) (width 0.109) (layer "In4.Cu") (net 110))
  (segment (start 94.130764 113.812622) (end 94.157184 113.821866) (width 0.109) (layer "In4.Cu") (net 110))
  (segment (start 94.512936 113.502272) (end 94.532728 113.522064) (width 0.109) (layer "In4.Cu") (net 110))
  (segment (start 93.435 113.525) (end 93.462815 113.528135) (width 0.109) (layer "In4.Cu") (net 110))
  (segment (start 95.239597 114.029673) (end 95.227452 114.054892) (width 0.109) (layer "In4.Cu") (net 110))
  (segment (start 94.616611 114.015096) (end 94.637747 114.022492) (width 0.109) (layer "In4.Cu") (net 110))
  (segment (start 95.711888 114.028511) (end 95.737107 114.040656) (width 0.109) (layer "In4.Cu") (net 110))
  (segment (start 95.239597 113.947103) (end 95.245825 113.974392) (width 0.109) (layer "In4.Cu") (net 110))
  (segment (start 94.262936 113.797729) (end 94.282728 113.777937) (width 0.109) (layer "In4.Cu") (net 110))
  (segment (start 93.556865 113.622185) (end 93.56 113.65) (width 0.109) (layer "In4.Cu") (net 110))
  (segment (start 93.282728 113.777937) (end 93.297621 113.754236) (width 0.109) (layer "In4.Cu") (net 110))
  (segment (start 95.758991 114.234884) (end 95.740327 114.253549) (width 0.109) (layer "In4.Cu") (net 110))
  (segment (start 94.063134 113.727816) (end 94.072378 113.754236) (width 0.109) (layer "In4.Cu") (net 110))
  (segment (start 95.21 113.9) (end 95.227452 113.921884) (width 0.109) (layer "In4.Cu") (net 110))
  (segment (start 95.265727 114.308042) (end 95.293718 114.308042) (width 0.109) (layer "In4.Cu") (net 110))
  (segment (start 95.7045 114.327941) (end 95.704501 114.355933) (width 0.109) (layer "In4.Cu") (net 110))
  (segment (start 94.032728 113.572064) (end 94.047621 113.595765) (width 0.109) (layer "In4.Cu") (net 110))
  (segment (start 95.213219 114.289669) (end 95.238438 114.301814) (width 0.109) (layer "In4.Cu") (net 110))
  (segment (start 94.847651 113.846816) (end 94.866611 113.834903) (width 0.109) (layer "In4.Cu") (net 110))
  (segment (start 94.637747 114.022492) (end 94.66 114.025) (width 0.109) (layer "In4.Cu") (net 110))
  (segment (start 95.737107 114.040656) (end 95.758991 114.058108) (width 0.109) (layer "In4.Cu") (net 110))
  (segment (start 94.056865 113.622185) (end 94.06 113.65) (width 0.109) (layer "In4.Cu") (net 110))
  (segment (start 93.607063 113.797729) (end 93.630764 113.812622) (width 0.109) (layer "In4.Cu") (net 110))
  (segment (start 94.087271 113.777937) (end 94.107063 113.797729) (width 0.109) (layer "In4.Cu") (net 110))
  (segment (start 94.91 113.825) (end 95.135 113.825) (width 0.109) (layer "In4.Cu") (net 110))
  (segment (start 93.532728 113.572064) (end 93.547621 113.595765) (width 0.109) (layer "In4.Cu") (net 110))
  (segment (start 95.21 114.076776) (end 95.191335 114.09544) (width 0.109) (layer "In4.Cu") (net 110))
  (segment (start 95.321008 114.301814) (end 95.346227 114.289669) (width 0.109) (layer "In4.Cu") (net 110))
  (segment (start 93.837271 113.572064) (end 93.857063 113.552272) (width 0.109) (layer "In4.Cu") (net 110))
  (segment (start 94.569903 113.968388) (end 94.581816 113.987348) (width 0.109) (layer "In4.Cu") (net 110))
  (segment (start 95.758991 114.058108) (end 95.776443 114.079992) (width 0.109) (layer "In4.Cu") (net 110))
  (segment (start 94.185 113.825) (end 94.212815 113.821866) (width 0.109) (layer "In4.Cu") (net 110))
  (segment (start 93.212815 113.821866) (end 93.239235 113.812622) (width 0.109) (layer "In4.Cu") (net 110))
  (segment (start 95.710729 114.383222) (end 95.722874 114.408441) (width 0.109) (layer "In4.Cu") (net 110))
  (segment (start 95.604099 114.040656) (end 95.629318 114.028511) (width 0.109) (layer "In4.Cu") (net 110))
  (segment (start 95.722874 114.408441) (end 95.740326 114.430325) (width 0.109) (layer "In4.Cu") (net 110))
  (segment (start 94.489235 113.487379) (end 94.512936 113.502272) (width 0.109) (layer "In4.Cu") (net 110))
  (segment (start 93.31 113.65) (end 93.313134 113.622185) (width 0.109) (layer "In4.Cu") (net 110))
  (segment (start 95.788588 114.187781) (end 95.776443 114.213) (width 0.109) (layer "In4.Cu") (net 110))
  (segment (start 94.732252 114.022492) (end 94.753388 114.015096) (width 0.109) (layer "In4.Cu") (net 110))
  (segment (start 93.587271 113.777937) (end 93.607063 113.797729) (width 0.109) (layer "In4.Cu") (net 110))
  (segment (start 93.547621 113.595765) (end 93.556865 113.622185) (width 0.109) (layer "In4.Cu") (net 110))
  (segment (start 93.185 113.825) (end 93.212815 113.821866) (width 0.109) (layer "In4.Cu") (net 110))
  (segment (start 93.357063 113.552272) (end 93.380764 113.537379) (width 0.109) (layer "In4.Cu") (net 110))
  (segment (start 95.776443 114.079992) (end 95.788588 114.105211) (width 0.109) (layer "In4.Cu") (net 110))
  (segment (start 94.072378 113.754236) (end 94.087271 113.777937) (width 0.109) (layer "In4.Cu") (net 110))
  (segment (start 93.56 113.65) (end 93.56 113.7) (width 0.109) (layer "In4.Cu") (net 110))
  (segment (start 93.322378 113.595765) (end 93.337271 113.572064) (width 0.109) (layer "In4.Cu") (net 110))
  (segment (start 93.880764 113.537379) (end 93.907184 113.528135) (width 0.109) (layer "In4.Cu") (net 110))
  (segment (start 93.782728 113.777937) (end 93.797621 113.754236) (width 0.109) (layer "In4.Cu") (net 110))
  (segment (start 94.597651 114.003183) (end 94.616611 114.015096) (width 0.109) (layer "In4.Cu") (net 110))
  (segment (start 93.239235 113.812622) (end 93.262936 113.797729) (width 0.109) (layer "In4.Cu") (net 110))
  (segment (start 95.794817 114.132501) (end 95.794816 114.160491) (width 0.109) (layer "In4.Cu") (net 110))
  (segment (start 93.81 113.65) (end 93.813134 113.622185) (width 0.109) (layer "In4.Cu") (net 110))
  (segment (start 95.155509 114.197824) (end 95.161738 114.225114) (width 0.109) (layer "In4.Cu") (net 110))
  (segment (start 95.173883 114.250333) (end 95.191335 114.272217) (width 0.109) (layer "In4.Cu") (net 110))
  (segment (start 92.84 113.815) (end 92.85 113.825) (width 0.109) (layer "In4.Cu") (net 110))
  (segment (start 94.532728 113.522064) (end 94.547621 113.545765) (width 0.109) (layer "In4.Cu") (net 110))
  (segment (start 94.297621 113.754236) (end 94.306865 113.727816) (width 0.109) (layer "In4.Cu") (net 110))
  (segment (start 94.56 113.6) (end 94.56 113.925) (width 0.109) (layer "In4.Cu") (net 110))
  (segment (start 93.712815 113.821866) (end 93.739235 113.812622) (width 0.109) (layer "In4.Cu") (net 110))
  (segment (start 94.71 114.025) (end 94.732252 114.022492) (width 0.109) (layer "In4.Cu") (net 110))
  (segment (start 93.297621 113.754236) (end 93.306865 113.727816) (width 0.109) (layer "In4.Cu") (net 110))
  (segment (start 93.262936 113.797729) (end 93.282728 113.777937) (width 0.109) (layer "In4.Cu") (net 110))
  (segment (start 93.762936 113.797729) (end 93.782728 113.777937) (width 0.109) (layer "In4.Cu") (net 110))
  (segment (start 95.582217 114.05811) (end 95.604099 114.040656) (width 0.109) (layer "In4.Cu") (net 110))
  (segment (start 94.547621 113.545765) (end 94.556865 113.572185) (width 0.109) (layer "In4.Cu") (net 110))
  (segment (start 93.822378 113.595765) (end 93.837271 113.572064) (width 0.109) (layer "In4.Cu") (net 110))
  (segment (start 93.31 113.7) (end 93.31 113.65) (width 0.109) (layer "In4.Cu") (net 110))
  (segment (start 95.191335 114.272217) (end 95.213219 114.289669) (width 0.109) (layer "In4.Cu") (net 110))
  (segment (start 94.212815 113.821866) (end 94.239235 113.812622) (width 0.109) (layer "In4.Cu") (net 110))
  (segment (start 94.313134 113.572185) (end 94.322378 113.545765) (width 0.109) (layer "In4.Cu") (net 110))
  (segment (start 95.722874 114.275433) (end 95.710729 114.300652) (width 0.109) (layer "In4.Cu") (net 110))
  (segment (start 94.807492 113.947252) (end 94.812507 113.902747) (width 0.109) (layer "In4.Cu") (net 110))
  (segment (start 95.368111 114.272217) (end 95.386775 114.253552) (width 0.109) (layer "In4.Cu") (net 110))
  (segment (start 95.173883 114.117325) (end 95.161738 114.142544) (width 0.109) (layer "In4.Cu") (net 110))
  (segment (start 94.306865 113.727816) (end 94.31 113.7) (width 0.109) (layer "In4.Cu") (net 110))
  (segment (start 94.31 113.6) (end 94.313134 113.572185) (width 0.109) (layer "In4.Cu") (net 110))
  (segment (start 95.135 113.825) (end 95.21 113.9) (width 0.109) (layer "In4.Cu") (net 110))
  (segment (start 94.581816 113.987348) (end 94.597651 114.003183) (width 0.109) (layer "In4.Cu") (net 110))
  (segment (start 90.7865 117.939) (end 91.1715 117.629) (width 0.182) (layer "F.Cu") (net 111))
  (via (at 93.309702 88.343088) (size 0.45) (drill 0.1) (layers "F.Cu" "B.Cu") (net 111))
  (via (at 91.1715 117.629) (size 0.45) (drill 0.1) (layers "F.Cu" "B.Cu") (net 111))
  (segment (start 93.944364 95.769185) (end 93.963796 95.728834) (width 0.109) (layer "In2.Cu") (net 111))
  (segment (start 93.382306 95.6594) (end 93.427092 95.6594) (width 0.109) (layer "In2.Cu") (net 111))
  (segment (start 93.973762 95.640385) (end 93.963796 95.596722) (width 0.109) (layer "In2.Cu") (net 111))
  (segment (start 94.111807 94.868196) (end 95.2 93.78) (width 0.109) (layer "In2.Cu") (net 111))
  (segment (start 93.54612 95.716722) (end 93.633598 95.8042) (width 0.109) (layer "In2.Cu") (net 111))
  (segment (start 93.973762 95.685171) (end 93.973762 95.640385) (width 0.109) (layer "In2.Cu") (net 111))
  (segment (start 93.648382 94.794107) (end 93.693168 94.794107) (width 0.109) (layer "In2.Cu") (net 111))
  (segment (start 93.298292 95.688798) (end 93.338643 95.669366) (width 0.109) (layer "In2.Cu") (net 111))
  (segment (start 93.863979 94.89612) (end 93.90433 94.915551) (width 0.109) (layer "In2.Cu") (net 111))
  (segment (start 93.881426 95.832123) (end 93.916441 95.8042) (width 0.109) (layer "In2.Cu") (net 111))
  (segment (start 93.263278 95.716722) (end 93.298292 95.688798) (width 0.109) (layer "In2.Cu") (net 111))
  (segment (start 93.944364 95.556372) (end 93.916441 95.521357) (width 0.109) (layer "In2.Cu") (net 111))
  (segment (start 90.7542 116.7892) (end 90.255989 116.290989) (width 0.109) (layer "In2.Cu") (net 111))
  (segment (start 85.710989 116.290989) (end 83.75 114.33) (width 0.109) (layer "In2.Cu") (net 111))
  (segment (start 90.7542 117.2117) (end 90.7542 116.7892) (width 0.109) (layer "In2.Cu") (net 111))
  (segment (start 93.736832 94.804072) (end 93.777182 94.823504) (width 0.109) (layer "In2.Cu") (net 111))
  (segment (start 93.777182 94.823504) (end 93.812197 94.851427) (width 0.109) (layer "In2.Cu") (net 111))
  (segment (start 93.963796 95.728834) (end 93.973762 95.685171) (width 0.109) (layer "In2.Cu") (net 111))
  (segment (start 95.2 87.99) (end 94.61 87.4) (width 0.109) (layer "In2.Cu") (net 111))
  (segment (start 93.427092 95.6594) (end 93.470755 95.669366) (width 0.109) (layer "In2.Cu") (net 111))
  (segment (start 93.472031 94.970456) (end 93.481998 94.926792) (width 0.109) (layer "In2.Cu") (net 111))
  (segment (start 93.529354 95.13427) (end 93.501429 95.099256) (width 0.109) (layer "In2.Cu") (net 111))
  (segment (start 83.75 101.63) (end 89.4 95.98) (width 0.109) (layer "In2.Cu") (net 111))
  (segment (start 93.812197 94.851427) (end 93.828965 94.868195) (width 0.109) (layer "In2.Cu") (net 111))
  (segment (start 93.90433 94.915551) (end 93.947994 94.925516) (width 0.109) (layer "In2.Cu") (net 111))
  (segment (start 93.916441 95.521357) (end 93.529354 95.13427) (width 0.109) (layer "In2.Cu") (net 111))
  (segment (start 93.263278 95.716725) (end 93.263278 95.716722) (width 0.109) (layer "In2.Cu") (net 111))
  (segment (start 93.564368 94.823505) (end 93.60472 94.804072) (width 0.109) (layer "In2.Cu") (net 111))
  (segment (start 94.036442 94.91555) (end 94.076793 94.896119) (width 0.109) (layer "In2.Cu") (net 111))
  (segment (start 93.472031 95.015242) (end 93.472031 94.970456) (width 0.109) (layer "In2.Cu") (net 111))
  (segment (start 93 95.98) (end 93.263278 95.716725) (width 0.109) (layer "In2.Cu") (net 111))
  (segment (start 93.481998 94.926792) (end 93.50143 94.886442) (width 0.109) (layer "In2.Cu") (net 111))
  (segment (start 93.501429 95.099256) (end 93.481998 95.058904) (width 0.109) (layer "In2.Cu") (net 111))
  (segment (start 93.828965 94.868195) (end 93.863979 94.89612) (width 0.109) (layer "In2.Cu") (net 111))
  (segment (start 93.529353 94.851428) (end 93.564368 94.823505) (width 0.109) (layer "In2.Cu") (net 111))
  (segment (start 93.50143 94.886442) (end 93.529353 94.851428) (width 0.109) (layer "In2.Cu") (net 111))
  (segment (start 94.61 87.4) (end 94.25279 87.4) (width 0.109) (layer "In2.Cu") (net 111))
  (segment (start 90.255989 116.290989) (end 85.710989 116.290989) (width 0.109) (layer "In2.Cu") (net 111))
  (segment (start 93.797412 95.861521) (end 93.841075 95.851555) (width 0.109) (layer "In2.Cu") (net 111))
  (segment (start 89.4 95.98) (end 93 95.98) (width 0.109) (layer "In2.Cu") (net 111))
  (segment (start 93.708963 95.851555) (end 93.752626 95.861521) (width 0.109) (layer "In2.Cu") (net 111))
  (segment (start 93.752626 95.861521) (end 93.797412 95.861521) (width 0.109) (layer "In2.Cu") (net 111))
  (segment (start 93.947994 94.925516) (end 93.992778 94.925517) (width 0.109) (layer "In2.Cu") (net 111))
  (segment (start 93.633598 95.8042) (end 93.668613 95.832123) (width 0.109) (layer "In2.Cu") (net 111))
  (segment (start 93.992778 94.925517) (end 94.036442 94.91555) (width 0.109) (layer "In2.Cu") (net 111))
  (segment (start 93.481998 95.058904) (end 93.472031 95.015242) (width 0.109) (layer "In2.Cu") (net 111))
  (segment (start 93.470755 95.669366) (end 93.511105 95.688798) (width 0.109) (layer "In2.Cu") (net 111))
  (segment (start 94.076793 94.896119) (end 94.111807 94.868196) (width 0.109) (layer "In2.Cu") (net 111))
  (segment (start 94.25279 87.4) (end 93.309702 88.343088) (width 0.109) (layer "In2.Cu") (net 111))
  (segment (start 93.693168 94.794107) (end 93.736832 94.804072) (width 0.109) (layer "In2.Cu") (net 111))
  (segment (start 91.1715 117.629) (end 90.7542 117.2117) (width 0.109) (layer "In2.Cu") (net 111))
  (segment (start 93.511105 95.688798) (end 93.54612 95.716722) (width 0.109) (layer "In2.Cu") (net 111))
  (segment (start 93.963796 95.596722) (end 93.944364 95.556372) (width 0.109) (layer "In2.Cu") (net 111))
  (segment (start 93.841075 95.851555) (end 93.881426 95.832123) (width 0.109) (layer "In2.Cu") (net 111))
  (segment (start 93.668613 95.832123) (end 93.708963 95.851555) (width 0.109) (layer "In2.Cu") (net 111))
  (segment (start 93.338643 95.669366) (end 93.382306 95.6594) (width 0.109) (layer "In2.Cu") (net 111))
  (segment (start 83.75 114.33) (end 83.75 101.63) (width 0.109) (layer "In2.Cu") (net 111))
  (segment (start 95.2 93.78) (end 95.2 87.99) (width 0.109) (layer "In2.Cu") (net 111))
  (segment (start 93.60472 94.804072) (end 93.648382 94.794107) (width 0.109) (layer "In2.Cu") (net 111))
  (segment (start 93.916441 95.8042) (end 93.944364 95.769185) (width 0.109) (layer "In2.Cu") (net 111))
  (segment (start 93.4 88.25279) (end 93.309702 88.343088) (width 0.182) (layer "B.Cu") (net 111))
  (segment (start 93.4 87.145) (end 93.4 88.25279) (width 0.182) (layer "B.Cu") (net 111))
  (segment (start 90.7865 117.304) (end 91.1715 116.993999) (width 0.182) (layer "F.Cu") (net 112))
  (via (at 91.1715 116.993999) (size 0.45) (drill 0.1) (layers "F.Cu" "B.Cu") (net 112))
  (via (at 92.875 87.95) (size 0.45) (drill 0.1) (layers "F.Cu" "B.Cu") (net 112))
  (segment (start 95.025784 95.491977) (end 94.976663 95.503188) (width 0.109) (layer "In2.Cu") (net 112))
  (segment (start 96 88.18) (end 96 94.448338) (width 0.109) (layer "In2.Cu") (net 112))
  (segment (start 95.740506 95.482009) (end 95.751717 95.53113) (width 0.109) (layer "In2.Cu") (net 112))
  (segment (start 95.369032 95.715422) (end 95.210074 95.556464) (width 0.109) (layer "In2.Cu") (net 112))
  (segment (start 95.712561 94.666355) (end 95.662177 94.666355) (width 0.109) (layer "In2.Cu") (net 112))
  (segment (start 94.92 87.1) (end 96 88.18) (width 0.109) (layer "In2.Cu") (net 112))
  (segment (start 96 94.448338) (end 95.846469 94.601869) (width 0.109) (layer "In2.Cu") (net 112))
  (segment (start 95.231926 94.552918) (end 95.192534 94.584332) (width 0.109) (layer "In2.Cu") (net 112))
  (segment (start 95.376826 94.519845) (end 95.326442 94.519845) (width 0.109) (layer "In2.Cu") (net 112))
  (segment (start 95.761682 94.655143) (end 95.712561 94.666355) (width 0.109) (layer "In2.Cu") (net 112))
  (segment (start 88.613544 115.6775) (end 89.018022 116.081978) (width 0.109) (layer "In2.Cu") (net 112))
  (segment (start 95.751717 95.581514) (end 95.740506 95.630635) (width 0.109) (layer "In2.Cu") (net 112))
  (segment (start 95.718644 95.67603) (end 95.68723 95.715422) (width 0.109) (layer "In2.Cu") (net 112))
  (segment (start 94.931268 95.52505) (end 94.891876 95.556464) (width 0.109) (layer "In2.Cu") (net 112))
  (segment (start 95.471341 94.552918) (end 95.425946 94.531057) (width 0.109) (layer "In2.Cu") (net 112))
  (segment (start 95.68723 95.397224) (end 95.718644 95.436616) (width 0.109) (layer "In2.Cu") (net 112))
  (segment (start 93.725 87.1) (end 94.92 87.1) (width 0.109) (layer "In2.Cu") (net 112))
  (segment (start 84.3 102.28) (end 84.3 113.38) (width 0.109) (layer "In2.Cu") (net 112))
  (segment (start 95.128047 94.768623) (end 95.139259 94.817743) (width 0.109) (layer "In2.Cu") (net 112))
  (segment (start 95.846469 94.601869) (end 95.807077 94.633282) (width 0.109) (layer "In2.Cu") (net 112))
  (segment (start 89.93 96.65) (end 84.3 102.28) (width 0.109) (layer "In2.Cu") (net 112))
  (segment (start 89.018022 116.081978) (end 90.577678 116.081979) (width 0.109) (layer "In2.Cu") (net 112))
  (segment (start 92.875 87.95) (end 93.725 87.1) (width 0.109) (layer "In2.Cu") (net 112))
  (segment (start 93.798338 96.65) (end 94.891876 95.556464) (width 0.109) (layer "In2.Cu") (net 112))
  (segment (start 95.553323 95.779909) (end 95.502939 95.779909) (width 0.109) (layer "In2.Cu") (net 112))
  (segment (start 91.1715 116.675801) (end 91.1715 116.993999) (width 0.109) (layer "In2.Cu") (net 112))
  (segment (start 93.798338 96.65) (end 89.93 96.65) (width 0.109) (layer "In2.Cu") (net 112))
  (segment (start 95.408424 95.746836) (end 95.369032 95.715422) (width 0.109) (layer "In2.Cu") (net 112))
  (segment (start 90.577678 116.081979) (end 91.1715 116.675801) (width 0.109) (layer "In2.Cu") (net 112))
  (segment (start 95.567662 94.633282) (end 95.52827 94.601869) (width 0.109) (layer "In2.Cu") (net 112))
  (segment (start 95.277321 94.531057) (end 95.231926 94.552918) (width 0.109) (layer "In2.Cu") (net 112))
  (segment (start 95.192534 94.90253) (end 95.68723 95.397224) (width 0.109) (layer "In2.Cu") (net 112))
  (segment (start 95.139259 94.817743) (end 95.16112 94.863138) (width 0.109) (layer "In2.Cu") (net 112))
  (segment (start 86.5975 115.6775) (end 88.613544 115.6775) (width 0.109) (layer "In2.Cu") (net 112))
  (segment (start 95.740506 95.630635) (end 95.718644 95.67603) (width 0.109) (layer "In2.Cu") (net 112))
  (segment (start 95.170682 95.52505) (end 95.125289 95.503188) (width 0.109) (layer "In2.Cu") (net 112))
  (segment (start 95.52827 94.601869) (end 95.510733 94.584332) (width 0.109) (layer "In2.Cu") (net 112))
  (segment (start 95.510733 94.584332) (end 95.471341 94.552918) (width 0.109) (layer "In2.Cu") (net 112))
  (segment (start 95.502939 95.779909) (end 95.453819 95.768697) (width 0.109) (layer "In2.Cu") (net 112))
  (segment (start 95.139259 94.669118) (end 95.128047 94.718239) (width 0.109) (layer "In2.Cu") (net 112))
  (segment (start 95.16112 94.863138) (end 95.192534 94.90253) (width 0.109) (layer "In2.Cu") (net 112))
  (segment (start 95.16112 94.623723) (end 95.139259 94.669118) (width 0.109) (layer "In2.Cu") (net 112))
  (segment (start 95.425946 94.531057) (end 95.376826 94.519845) (width 0.109) (layer "In2.Cu") (net 112))
  (segment (start 95.192534 94.584332) (end 95.16112 94.623723) (width 0.109) (layer "In2.Cu") (net 112))
  (segment (start 95.128047 94.718239) (end 95.128047 94.768623) (width 0.109) (layer "In2.Cu") (net 112))
  (segment (start 95.125289 95.503188) (end 95.076168 95.491977) (width 0.109) (layer "In2.Cu") (net 112))
  (segment (start 94.976663 95.503188) (end 94.931268 95.52505) (width 0.109) (layer "In2.Cu") (net 112))
  (segment (start 95.662177 94.666355) (end 95.613057 94.655143) (width 0.109) (layer "In2.Cu") (net 112))
  (segment (start 95.68723 95.715422) (end 95.64784 95.746835) (width 0.109) (layer "In2.Cu") (net 112))
  (segment (start 95.326442 94.519845) (end 95.277321 94.531057) (width 0.109) (layer "In2.Cu") (net 112))
  (segment (start 95.613057 94.655143) (end 95.567662 94.633282) (width 0.109) (layer "In2.Cu") (net 112))
  (segment (start 95.751717 95.53113) (end 95.751717 95.581514) (width 0.109) (layer "In2.Cu") (net 112))
  (segment (start 84.3 113.38) (end 86.5975 115.6775) (width 0.109) (layer "In2.Cu") (net 112))
  (segment (start 95.076168 95.491977) (end 95.025784 95.491977) (width 0.109) (layer "In2.Cu") (net 112))
  (segment (start 95.718644 95.436616) (end 95.740506 95.482009) (width 0.109) (layer "In2.Cu") (net 112))
  (segment (start 95.602445 95.768696) (end 95.553323 95.779909) (width 0.109) (layer "In2.Cu") (net 112))
  (segment (start 95.453819 95.768697) (end 95.408424 95.746836) (width 0.109) (layer "In2.Cu") (net 112))
  (segment (start 95.64784 95.746835) (end 95.602445 95.768696) (width 0.109) (layer "In2.Cu") (net 112))
  (segment (start 95.210074 95.556464) (end 95.170682 95.52505) (width 0.109) (layer "In2.Cu") (net 112))
  (segment (start 95.807077 94.633282) (end 95.761682 94.655143) (width 0.109) (layer "In2.Cu") (net 112))
  (segment (start 93 87.825) (end 92.875 87.95) (width 0.182) (layer "B.Cu") (net 112))
  (segment (start 93 87.145) (end 93 87.825) (width 0.182) (layer "B.Cu") (net 112))
  (segment (start 96.224998 118.4) (end 96.418598 118.2064) (width 0.182) (layer "F.Cu") (net 113))
  (segment (start 97.4425 118.2064) (end 97.4457 118.2032) (width 0.182) (layer "F.Cu") (net 113))
  (segment (start 96.418598 118.2064) (end 97.4425 118.2064) (width 0.182) (layer "F.Cu") (net 113))
  (segment (start 90.7865 115.399) (end 91.1715 115.088999) (width 0.182) (layer "F.Cu") (net 113))
  (via (at 91.1715 115.088999) (size 0.45) (drill 0.1) (layers "F.Cu" "B.Cu") (net 113))
  (via (at 96.224998 118.4) (size 0.45) (drill 0.1) (layers "F.Cu" "B.Cu") (net 113))
  (segment (start 93.370096 116.381612) (end 93.358183 116.362652) (width 0.109) (layer "In4.Cu") (net 113))
  (segment (start 93.262 116.325) (end 93.239747 116.327508) (width 0.109) (layer "In4.Cu") (net 113))
  (segment (start 95.250602 117.100812) (end 95.231519 117.116031) (width 0.109) (layer "In4.Cu") (net 113))
  (segment (start 93.574219 116.78396) (end 93.55696 116.801219) (width 0.109) (layer "In4.Cu") (net 113))
  (segment (start 93.164507 116.402748) (end 93.162 116.425) (width 0.109) (layer "In4.Cu") (net 113))
  (segment (start 92.944 116.716) (end 92.944 116.634) (width 0.109) (layer "In4.Cu") (net 113))
  (segment (start 93.639039 116.54878) (end 93.62178 116.566039) (width 0.109) (layer "In4.Cu") (net 113))
  (segment (start 92.859254 116.527732) (end 92.835 116.525) (width 0.109) (layer "In4.Cu") (net 113))
  (segment (start 95.302281 117.473416) (end 95.291691 117.451425) (width 0.109) (layer "In4.Cu") (net 113))
  (segment (start 95.344594 117.090222) (end 95.320798 117.084791) (width 0.109) (layer "In4.Cu") (net 113))
  (segment (start 93.659706 116.535794) (end 93.639039 116.54878) (width 0.109) (layer "In4.Cu") (net 113))
  (segment (start 92.835 116.525) (end 92.62 116.525) (width 0.109) (layer "In4.Cu") (net 113))
  (segment (start 93.40378 116.78396) (end 93.390794 116.763293) (width 0.109) (layer "In4.Cu") (net 113))
  (segment (start 92.90296 116.54878) (end 92.882293 116.535794) (width 0.109) (layer "In4.Cu") (net 113))
  (segment (start 95.411477 117.229106) (end 95.416909 117.20531) (width 0.109) (layer "In4.Cu") (net 113))
  (segment (start 95.231519 117.116031) (end 95.163349 117.1842) (width 0.109) (layer "In4.Cu") (net 113))
  (segment (start 95.272593 117.090222) (end 95.250602 117.100812) (width 0.109) (layer "In4.Cu") (net 113))
  (segment (start 93.38 116.716) (end 93.38 116.425) (width 0.109) (layer "In4.Cu") (net 113))
  (segment (start 93.536293 116.814205) (end 93.513254 116.822267) (width 0.109) (layer "In4.Cu") (net 113))
  (segment (start 95.028283 117.199418) (end 95.009201 117.184201) (width 0.109) (layer "In4.Cu") (net 113))
  (segment (start 93.12096 116.801219) (end 93.100293 116.814205) (width 0.109) (layer "In4.Cu") (net 113))
  (segment (start 93.441706 116.814205) (end 93.421039 116.801219) (width 0.109) (layer "In4.Cu") (net 113))
  (segment (start 93.151205 116.763293) (end 93.138219 116.78396) (width 0.109) (layer "In4.Cu") (net 113))
  (segment (start 93.600732 116.609745) (end 93.598 116.634) (width 0.109) (layer "In4.Cu") (net 113))
  (segment (start 93.028745 116.822267) (end 93.005706 116.814205) (width 0.109) (layer "In4.Cu") (net 113))
  (segment (start 92.941267 116.609745) (end 92.933205 116.586706) (width 0.109) (layer "In4.Cu") (net 113))
  (segment (start 95.320798 117.084791) (end 95.29639 117.084791) (width 0.109) (layer "In4.Cu") (net 113))
  (segment (start 93.302252 116.327508) (end 93.28 116.325) (width 0.109) (layer "In4.Cu") (net 113))
  (segment (start 92.1925 116.0975) (end 91.7725 116.0975) (width 0.109) (layer "In4.Cu") (net 113))
  (segment (start 93.162 116.716) (end 93.159267 116.740254) (width 0.109) (layer "In4.Cu") (net 113))
  (segment (start 93.323388 116.334904) (end 93.302252 116.327508) (width 0.109) (layer "In4.Cu") (net 113))
  (segment (start 95.122275 117.210008) (end 95.098479 117.21544) (width 0.109) (layer "In4.Cu") (net 113))
  (segment (start 93.587205 116.763293) (end 93.574219 116.78396) (width 0.109) (layer "In4.Cu") (net 113))
  (segment (start 92.933205 116.586706) (end 92.920219 116.566039) (width 0.109) (layer "In4.Cu") (net 113))
  (segment (start 95.416909 117.180901) (end 95.411477 117.157105) (width 0.109) (layer "In4.Cu") (net 113))
  (segment (start 95.144266 117.199418) (end 95.122275 117.210008) (width 0.109) (layer "In4.Cu") (net 113))
  (segment (start 95.07407 117.21544) (end 95.050274 117.210008) (width 0.109) (layer "In4.Cu") (net 113))
  (segment (start 95.29639 117.084791) (end 95.272593 117.090222) (width 0.109) (layer "In4.Cu") (net 113))
  (segment (start 92.946732 116.740254) (end 92.944 116.716) (width 0.109) (layer "In4.Cu") (net 113))
  (segment (start 92.882293 116.535794) (end 92.859254 116.527732) (width 0.109) (layer "In4.Cu") (net 113))
  (segment (start 93.382732 116.740254) (end 93.38 116.716) (width 0.109) (layer "In4.Cu") (net 113))
  (segment (start 93.62178 116.566039) (end 93.608794 116.586706) (width 0.109) (layer "In4.Cu") (net 113))
  (segment (start 92.954794 116.763293) (end 92.946732 116.740254) (width 0.109) (layer "In4.Cu") (net 113))
  (segment (start 95.385669 117.116031) (end 95.366585 117.100812) (width 0.109) (layer "In4.Cu") (net 113))
  (segment (start 96.224998 118.4) (end 96.224998 118.399998) (width 0.109) (layer "In4.Cu") (net 113))
  (segment (start 95.098479 117.21544) (end 95.07407 117.21544) (width 0.109) (layer "In4.Cu") (net 113))
  (segment (start 93.005706 116.814205) (end 92.985039 116.801219) (width 0.109) (layer "In4.Cu") (net 113))
  (segment (start 93.053 116.825) (end 93.028745 116.822267) (width 0.109) (layer "In4.Cu") (net 113))
  (segment (start 93.598 116.634) (end 93.598 116.716) (width 0.109) (layer "In4.Cu") (net 113))
  (segment (start 95.050274 117.210008) (end 95.028283 117.199418) (width 0.109) (layer "In4.Cu") (net 113))
  (segment (start 93.171903 116.381612) (end 93.164507 116.402748) (width 0.109) (layer "In4.Cu") (net 113))
  (segment (start 92.985039 116.801219) (end 92.96778 116.78396) (width 0.109) (layer "In4.Cu") (net 113))
  (segment (start 93.183816 116.362652) (end 93.171903 116.381612) (width 0.109) (layer "In4.Cu") (net 113))
  (segment (start 95.400887 117.135114) (end 95.385669 117.116031) (width 0.109) (layer "In4.Cu") (net 113))
  (segment (start 92.920219 116.566039) (end 92.90296 116.54878) (width 0.109) (layer "In4.Cu") (net 113))
  (segment (start 91.7725 116.0975) (end 91.575 115.9) (width 0.109) (layer "In4.Cu") (net 113))
  (segment (start 93.239747 116.327508) (end 93.218611 116.334904) (width 0.109) (layer "In4.Cu") (net 113))
  (segment (start 93.513254 116.822267) (end 93.489 116.825) (width 0.109) (layer "In4.Cu") (net 113))
  (segment (start 95.3175 117.33835) (end 95.385669 117.27018) (width 0.109) (layer "In4.Cu") (net 113))
  (segment (start 95.385669 117.27018) (end 95.400887 117.251097) (width 0.109) (layer "In4.Cu") (net 113))
  (segment (start 93.138219 116.78396) (end 93.12096 116.801219) (width 0.109) (layer "In4.Cu") (net 113))
  (segment (start 92.944 116.634) (end 92.941267 116.609745) (width 0.109) (layer "In4.Cu") (net 113))
  (segment (start 95.163349 117.1842) (end 95.144266 117.199418) (width 0.109) (layer "In4.Cu") (net 113))
  (segment (start 93.377492 116.402748) (end 93.370096 116.381612) (width 0.109) (layer "In4.Cu") (net 113))
  (segment (start 93.707 116.525) (end 93.682745 116.527732) (width 0.109) (layer "In4.Cu") (net 113))
  (segment (start 95.291691 117.451425) (end 95.28626 117.427629) (width 0.109) (layer "In4.Cu") (net 113))
  (segment (start 95.411477 117.157105) (end 95.400887 117.135114) (width 0.109) (layer "In4.Cu") (net 113))
  (segment (start 93.598 116.716) (end 93.595267 116.740254) (width 0.109) (layer "In4.Cu") (net 113))
  (segment (start 95.291691 117.379424) (end 95.302281 117.357433) (width 0.109) (layer "In4.Cu") (net 113))
  (segment (start 95.009201 117.184201) (end 94.35 116.525) (width 0.109) (layer "In4.Cu") (net 113))
  (segment (start 96.224998 118.399998) (end 95.3175 117.4925) (width 0.109) (layer "In4.Cu") (net 113))
  (segment (start 93.682745 116.527732) (end 93.659706 116.535794) (width 0.109) (layer "In4.Cu") (net 113))
  (segment (start 93.608794 116.586706) (end 93.600732 116.609745) (width 0.109) (layer "In4.Cu") (net 113))
  (segment (start 95.302281 117.357433) (end 95.3175 117.33835) (width 0.109) (layer "In4.Cu") (net 113))
  (segment (start 93.421039 116.801219) (end 93.40378 116.78396) (width 0.109) (layer "In4.Cu") (net 113))
  (segment (start 93.489 116.825) (end 93.464745 116.822267) (width 0.109) (layer "In4.Cu") (net 113))
  (segment (start 93.162 116.425) (end 93.162 116.716) (width 0.109) (layer "In4.Cu") (net 113))
  (segment (start 93.218611 116.334904) (end 93.199651 116.346817) (width 0.109) (layer "In4.Cu") (net 113))
  (segment (start 93.159267 116.740254) (end 93.151205 116.763293) (width 0.109) (layer "In4.Cu") (net 113))
  (segment (start 95.400887 117.251097) (end 95.411477 117.229106) (width 0.109) (layer "In4.Cu") (net 113))
  (segment (start 93.199651 116.346817) (end 93.183816 116.362652) (width 0.109) (layer "In4.Cu") (net 113))
  (segment (start 91.575 115.9) (end 91.575 115.492499) (width 0.109) (layer "In4.Cu") (net 113))
  (segment (start 93.55696 116.801219) (end 93.536293 116.814205) (width 0.109) (layer "In4.Cu") (net 113))
  (segment (start 93.077254 116.822267) (end 93.053 116.825) (width 0.109) (layer "In4.Cu") (net 113))
  (segment (start 95.3175 117.4925) (end 95.302281 117.473416) (width 0.109) (layer "In4.Cu") (net 113))
  (segment (start 93.342348 116.346817) (end 93.323388 116.334904) (width 0.109) (layer "In4.Cu") (net 113))
  (segment (start 92.96778 116.78396) (end 92.954794 116.763293) (width 0.109) (layer "In4.Cu") (net 113))
  (segment (start 91.575 115.492499) (end 91.1715 115.088999) (width 0.109) (layer "In4.Cu") (net 113))
  (segment (start 93.100293 116.814205) (end 93.077254 116.822267) (width 0.109) (layer "In4.Cu") (net 113))
  (segment (start 93.464745 116.822267) (end 93.441706 116.814205) (width 0.109) (layer "In4.Cu") (net 113))
  (segment (start 95.28626 117.427629) (end 95.28626 117.403221) (width 0.109) (layer "In4.Cu") (net 113))
  (segment (start 95.28626 117.403221) (end 95.291691 117.379424) (width 0.109) (layer "In4.Cu") (net 113))
  (segment (start 93.38 116.425) (end 93.377492 116.402748) (width 0.109) (layer "In4.Cu") (net 113))
  (segment (start 93.595267 116.740254) (end 93.587205 116.763293) (width 0.109) (layer "In4.Cu") (net 113))
  (segment (start 93.358183 116.362652) (end 93.342348 116.346817) (width 0.109) (layer "In4.Cu") (net 113))
  (segment (start 93.28 116.325) (end 93.262 116.325) (width 0.109) (layer "In4.Cu") (net 113))
  (segment (start 95.366585 117.100812) (end 95.344594 117.090222) (width 0.109) (layer "In4.Cu") (net 113))
  (segment (start 92.62 116.525) (end 92.1925 116.0975) (width 0.109) (layer "In4.Cu") (net 113))
  (segment (start 95.416909 117.20531) (end 95.416909 117.180901) (width 0.109) (layer "In4.Cu") (net 113))
  (segment (start 94.35 116.525) (end 93.707 116.525) (width 0.109) (layer "In4.Cu") (net 113))
  (segment (start 93.390794 116.763293) (end 93.382732 116.740254) (width 0.109) (layer "In4.Cu") (net 113))
  (segment (start 96.423723 117.8) (end 96.195936 117.572213) (width 0.182) (layer "F.Cu") (net 114))
  (segment (start 90.3 115.08) (end 90.7865 114.764) (width 0.182) (layer "F.Cu") (net 114))
  (segment (start 96.423723 117.8) (end 97.4425 117.8) (width 0.182) (layer "F.Cu") (net 114))
  (segment (start 97.4425 117.8) (end 97.4457 117.8032) (width 0.182) (layer "F.Cu") (net 114))
  (via (at 90.3 115.08) (size 0.45) (drill 0.1) (layers "F.Cu" "B.Cu") (net 114))
  (via (at 96.195936 117.572213) (size 0.45) (drill 0.1) (layers "F.Cu" "B.Cu") (net 114))
  (segment (start 94.777157 116.477256) (end 94.771725 116.501052) (width 0.109) (layer "In4.Cu") (net 114))
  (segment (start 94.787747 116.455265) (end 94.777157 116.477256) (width 0.109) (layer "In4.Cu") (net 114))
  (segment (start 95.049583 116.513127) (end 95.073379 116.507695) (width 0.109) (layer "In4.Cu") (net 114))
  (segment (start 94.771725 116.525461) (end 94.777157 116.549257) (width 0.109) (layer "In4.Cu") (net 114))
  (segment (start 94.8856 116.295508) (end 94.8856 116.319916) (width 0.109) (layer "In4.Cu") (net 114))
  (segment (start 94.880169 116.271712) (end 94.8856 116.295508) (width 0.109) (layer "In4.Cu") (net 114))
  (segment (start 94.802965 116.590331) (end 94.822048 116.605549) (width 0.109) (layer "In4.Cu") (net 114))
  (segment (start 92.17 114.67) (end 92.41 114.91) (width 0.109) (layer "In4.Cu") (net 114))
  (segment (start 95.121584 116.513127) (end 95.143575 116.523717) (width 0.109) (layer "In4.Cu") (net 114))
  (segment (start 92.41 115.84) (end 92.667626 116.097626) (width 0.109) (layer "In4.Cu") (net 114))
  (segment (start 94.880169 116.343713) (end 94.869579 116.365704) (width 0.109) (layer "In4.Cu") (net 114))
  (segment (start 94.854361 116.230638) (end 94.869579 116.249721) (width 0.109) (layer "In4.Cu") (net 114))
  (segment (start 94.8856 116.319916) (end 94.880169 116.343713) (width 0.109) (layer "In4.Cu") (net 114))
  (segment (start 95.073379 116.507695) (end 95.097788 116.507695) (width 0.109) (layer "In4.Cu") (net 114))
  (segment (start 94.869579 116.249721) (end 94.880169 116.271712) (width 0.109) (layer "In4.Cu") (net 114))
  (segment (start 94.867835 116.62157) (end 94.892243 116.62157) (width 0.109) (layer "In4.Cu") (net 114))
  (segment (start 94.844039 116.616139) (end 94.867835 116.62157) (width 0.109) (layer "In4.Cu") (net 114))
  (segment (start 94.787747 116.571248) (end 94.802965 116.590331) (width 0.109) (layer "In4.Cu") (net 114))
  (segment (start 94.721349 116.097626) (end 94.854361 116.230638) (width 0.109) (layer "In4.Cu") (net 114))
  (segment (start 95.097788 116.507695) (end 95.121584 116.513127) (width 0.109) (layer "In4.Cu") (net 114))
  (segment (start 94.822048 116.605549) (end 94.844039 116.616139) (width 0.109) (layer "In4.Cu") (net 114))
  (segment (start 95.162659 116.538936) (end 96.195936 117.572213) (width 0.109) (layer "In4.Cu") (net 114))
  (segment (start 90.3 115.08) (end 90.71 114.67) (width 0.109) (layer "In4.Cu") (net 114))
  (segment (start 94.91604 116.616139) (end 94.938031 116.605549) (width 0.109) (layer "In4.Cu") (net 114))
  (segment (start 92.41 114.91) (end 92.41 115.84) (width 0.109) (layer "In4.Cu") (net 114))
  (segment (start 94.957114 116.590331) (end 95.008509 116.538935) (width 0.109) (layer "In4.Cu") (net 114))
  (segment (start 90.71 114.67) (end 92.17 114.67) (width 0.109) (layer "In4.Cu") (net 114))
  (segment (start 94.854361 116.384787) (end 94.802965 116.436182) (width 0.109) (layer "In4.Cu") (net 114))
  (segment (start 94.777157 116.549257) (end 94.787747 116.571248) (width 0.109) (layer "In4.Cu") (net 114))
  (segment (start 95.027592 116.523717) (end 95.049583 116.513127) (width 0.109) (layer "In4.Cu") (net 114))
  (segment (start 92.667626 116.097626) (end 94.721349 116.097626) (width 0.109) (layer "In4.Cu") (net 114))
  (segment (start 94.771725 116.501052) (end 94.771725 116.525461) (width 0.109) (layer "In4.Cu") (net 114))
  (segment (start 95.143575 116.523717) (end 95.162659 116.538936) (width 0.109) (layer "In4.Cu") (net 114))
  (segment (start 95.008509 116.538935) (end 95.027592 116.523717) (width 0.109) (layer "In4.Cu") (net 114))
  (segment (start 94.892243 116.62157) (end 94.91604 116.616139) (width 0.109) (layer "In4.Cu") (net 114))
  (segment (start 94.938031 116.605549) (end 94.957114 116.590331) (width 0.109) (layer "In4.Cu") (net 114))
  (segment (start 94.869579 116.365704) (end 94.854361 116.384787) (width 0.109) (layer "In4.Cu") (net 114))
  (segment (start 94.802965 116.436182) (end 94.787747 116.455265) (width 0.109) (layer "In4.Cu") (net 114))
  (segment (start 96.718594 117.3936) (end 96.299997 116.975003) (width 0.182) (layer "F.Cu") (net 115))
  (segment (start 97.4361 117.3936) (end 97.4457 117.4032) (width 0.182) (layer "F.Cu") (net 115))
  (segment (start 96.718594 117.3936) (end 97.4361 117.3936) (width 0.182) (layer "F.Cu") (net 115))
  (segment (start 90.7865 114.129) (end 91.1715 113.819) (width 0.182) (layer "F.Cu") (net 115))
  (via (at 91.1715 113.819) (size 0.45) (drill 0.1) (layers "F.Cu" "B.Cu") (net 115))
  (via (at 96.299997 116.975003) (size 0.45) (drill 0.1) (layers "F.Cu" "B.Cu") (net 115))
  (segment (start 94.7148 114.882476) (end 94.744053 114.875798) (width 0.109) (layer "In4.Cu") (net 115))
  (segment (start 94.1277 115.113147) (end 94.1277 115.143153) (width 0.109) (layer "In4.Cu") (net 115))
  (segment (start 94.166105 115.222902) (end 94.189565 115.24161) (width 0.109) (layer "In4.Cu") (net 115))
  (segment (start 94.355609 115.222902) (end 94.362172 115.216338) (width 0.109) (layer "In4.Cu") (net 115))
  (segment (start 95.081782 115.7051) (end 95.088459 115.734355) (width 0.109) (layer "In4.Cu") (net 115))
  (segment (start 95.081782 115.675094) (end 95.081782 115.7051) (width 0.109) (layer "In4.Cu") (net 115))
  (segment (start 95.101477 115.761388) (end 95.120189 115.784851) (width 0.109) (layer "In4.Cu") (net 115))
  (segment (start 95.120187 115.595345) (end 95.101477 115.618804) (width 0.109) (layer "In4.Cu") (net 115))
  (segment (start 94.892215 115.023959) (end 94.885537 115.053212) (width 0.109) (layer "In4.Cu") (net 115))
  (segment (start 94.189565 115.24161) (end 94.216599 115.25463) (width 0.109) (layer "In4.Cu") (net 115))
  (segment (start 94.74118 115.405842) (end 94.76464 115.42455) (width 0.109) (layer "In4.Cu") (net 115))
  (segment (start 94.744053 114.875798) (end 94.774061 114.875799) (width 0.109) (layer "In4.Cu") (net 115))
  (segment (start 94.85381 115.103708) (end 94.741179 115.216336) (width 0.109) (layer "In4.Cu") (net 115))
  (segment (start 95.232816 115.293211) (end 95.251524 115.316671) (width 0.109) (layer "In4.Cu") (net 115))
  (segment (start 94.803314 114.882475) (end 94.830349 114.895494) (width 0.109) (layer "In4.Cu") (net 115))
  (segment (start 94.134377 115.172408) (end 94.147396 115.199442) (width 0.109) (layer "In4.Cu") (net 115))
  (segment (start 94.035338 114.7) (end 94.172669 114.837331) (width 0.109) (layer "In4.Cu") (net 115))
  (segment (start 94.1277 115.143153) (end 94.134377 115.172408) (width 0.109) (layer "In4.Cu") (net 115))
  (segment (start 94.191377 115.003375) (end 94.172669 115.026835) (width 0.109) (layer "In4.Cu") (net 115))
  (segment (start 94.172669 115.026835) (end 94.166105 115.033398) (width 0.109) (layer "In4.Cu") (net 115))
  (segment (start 94.85381 114.914204) (end 94.872518 114.937664) (width 0.109) (layer "In4.Cu") (net 115))
  (segment (start 95.088459 115.734355) (end 95.101477 115.761388) (width 0.109) (layer "In4.Cu") (net 115))
  (segment (start 95.271221 115.402966) (end 95.264545 115.432221) (width 0.109) (layer "In4.Cu") (net 115))
  (segment (start 94.885537 115.053212) (end 94.872518 115.080248) (width 0.109) (layer "In4.Cu") (net 115))
  (segment (start 95.123061 115.254806) (end 95.153067 115.254806) (width 0.109) (layer "In4.Cu") (net 115))
  (segment (start 94.687765 114.895495) (end 94.7148 114.882476) (width 0.109) (layer "In4.Cu") (net 115))
  (segment (start 95.975003 116.975003) (end 96.299997 116.975003) (width 0.109) (layer "In4.Cu") (net 115))
  (segment (start 94.27586 115.261307) (end 94.305114 115.25463) (width 0.109) (layer "In4.Cu") (net 115))
  (segment (start 94.930684 115.405842) (end 95.043312 115.293211) (width 0.109) (layer "In4.Cu") (net 115))
  (segment (start 94.709451 115.355346) (end 94.722471 115.382381) (width 0.109) (layer "In4.Cu") (net 115))
  (segment (start 95.182322 115.261483) (end 95.209357 115.274503) (width 0.109) (layer "In4.Cu") (net 115))
  (segment (start 94.245854 115.261307) (end 94.27586 115.261307) (width 0.109) (layer "In4.Cu") (net 115))
  (segment (start 94.204397 114.887825) (end 94.211074 114.91708) (width 0.109) (layer "In4.Cu") (net 115))
  (segment (start 95.066773 115.274503) (end 95.093808 115.261484) (width 0.109) (layer "In4.Cu") (net 115))
  (segment (start 94.872518 114.937664) (end 94.885538 114.964698) (width 0.109) (layer "In4.Cu") (net 115))
  (segment (start 95.043312 115.293211) (end 95.066773 115.274503) (width 0.109) (layer "In4.Cu") (net 115))
  (segment (start 94.820929 115.444247) (end 94.850935 115.444247) (width 0.109) (layer "In4.Cu") (net 115))
  (segment (start 94.172669 114.837331) (end 94.191377 114.860791) (width 0.109) (layer "In4.Cu") (net 115))
  (segment (start 94.702774 115.326091) (end 94.709451 115.355346) (width 0.109) (layer "In4.Cu") (net 115))
  (segment (start 94.722471 115.382381) (end 94.74118 115.405842) (width 0.109) (layer "In4.Cu") (net 115))
  (segment (start 94.216599 115.25463) (end 94.245854 115.261307) (width 0.109) (layer "In4.Cu") (net 115))
  (segment (start 95.821036 116.485698) (end 95.821036 116.821036) (width 0.109) (layer "In4.Cu") (net 115))
  (segment (start 95.264545 115.432221) (end 95.251524 115.459255) (width 0.109) (layer "In4.Cu") (net 115))
  (segment (start 94.362172 115.216338) (end 94.664306 114.914205) (width 0.109) (layer "In4.Cu") (net 115))
  (segment (start 92.6825 114.7) (end 94.035338 114.7) (width 0.109) (layer "In4.Cu") (net 115))
  (segment (start 94.147396 115.056858) (end 94.134377 115.083893) (width 0.109) (layer "In4.Cu") (net 115))
  (segment (start 94.664306 114.914205) (end 94.687765 114.895495) (width 0.109) (layer "In4.Cu") (net 115))
  (segment (start 94.741179 115.216336) (end 94.722471 115.239797) (width 0.109) (layer "In4.Cu") (net 115))
  (segment (start 94.791674 115.43757) (end 94.820929 115.444247) (width 0.109) (layer "In4.Cu") (net 115))
  (segment (start 95.264544 115.343705) (end 95.271221 115.37296) (width 0.109) (layer "In4.Cu") (net 115))
  (segment (start 94.830349 114.895494) (end 94.85381 114.914204) (width 0.109) (layer "In4.Cu") (net 115))
  (segment (start 94.722471 115.239797) (end 94.709452 115.266832) (width 0.109) (layer "In4.Cu") (net 115))
  (segment (start 94.211074 114.947086) (end 94.204397 114.97634) (width 0.109) (layer "In4.Cu") (net 115))
  (segment (start 94.885538 114.964698) (end 94.892215 114.993953) (width 0.109) (layer "In4.Cu") (net 115))
  (segment (start 94.892215 114.993953) (end 94.892215 115.023959) (width 0.109) (layer "In4.Cu") (net 115))
  (segment (start 91.6775 114.325) (end 92.3075 114.325) (width 0.109) (layer "In4.Cu") (net 115))
  (segment (start 94.907224 115.42455) (end 94.930684 115.405842) (width 0.109) (layer "In4.Cu") (net 115))
  (segment (start 95.251524 115.459255) (end 95.232816 115.482715) (width 0.109) (layer "In4.Cu") (net 115))
  (segment (start 94.332149 115.24161) (end 94.355609 115.222902) (width 0.109) (layer "In4.Cu") (net 115))
  (segment (start 95.120189 115.784851) (end 95.821036 116.485698) (width 0.109) (layer "In4.Cu") (net 115))
  (segment (start 92.3075 114.325) (end 92.6825 114.7) (width 0.109) (layer "In4.Cu") (net 115))
  (segment (start 94.204397 114.97634) (end 94.191377 115.003375) (width 0.109) (layer "In4.Cu") (net 115))
  (segment (start 94.166105 115.033398) (end 94.147396 115.056858) (width 0.109) (layer "In4.Cu") (net 115))
  (segment (start 95.088458 115.645839) (end 95.081782 115.675094) (width 0.109) (layer "In4.Cu") (net 115))
  (segment (start 95.821036 116.821036) (end 95.975003 116.975003) (width 0.109) (layer "In4.Cu") (net 115))
  (segment (start 94.702774 115.296085) (end 94.702774 115.326091) (width 0.109) (layer "In4.Cu") (net 115))
  (segment (start 95.251524 115.316671) (end 95.264544 115.343705) (width 0.109) (layer "In4.Cu") (net 115))
  (segment (start 94.211074 114.91708) (end 94.211074 114.947086) (width 0.109) (layer "In4.Cu") (net 115))
  (segment (start 95.271221 115.37296) (end 95.271221 115.402966) (width 0.109) (layer "In4.Cu") (net 115))
  (segment (start 94.774061 114.875799) (end 94.803314 114.882475) (width 0.109) (layer "In4.Cu") (net 115))
  (segment (start 95.209357 115.274503) (end 95.232816 115.293211) (width 0.109) (layer "In4.Cu") (net 115))
  (segment (start 95.101477 115.618804) (end 95.088458 115.645839) (width 0.109) (layer "In4.Cu") (net 115))
  (segment (start 95.232816 115.482715) (end 95.120187 115.595345) (width 0.109) (layer "In4.Cu") (net 115))
  (segment (start 95.153067 115.254806) (end 95.182322 115.261483) (width 0.109) (layer "In4.Cu") (net 115))
  (segment (start 94.147396 115.199442) (end 94.166105 115.222902) (width 0.109) (layer "In4.Cu") (net 115))
  (segment (start 94.191377 114.860791) (end 94.204397 114.887825) (width 0.109) (layer "In4.Cu") (net 115))
  (segment (start 94.709452 115.266832) (end 94.702774 115.296085) (width 0.109) (layer "In4.Cu") (net 115))
  (segment (start 94.134377 115.083893) (end 94.1277 115.113147) (width 0.109) (layer "In4.Cu") (net 115))
  (segment (start 91.1715 113.819) (end 91.6775 114.325) (width 0.109) (layer "In4.Cu") (net 115))
  (segment (start 94.880188 115.437569) (end 94.907224 115.42455) (width 0.109) (layer "In4.Cu") (net 115))
  (segment (start 94.850935 115.444247) (end 94.880188 115.437569) (width 0.109) (layer "In4.Cu") (net 115))
  (segment (start 94.76464 115.42455) (end 94.791674 115.43757) (width 0.109) (layer "In4.Cu") (net 115))
  (segment (start 94.305114 115.25463) (end 94.332149 115.24161) (width 0.109) (layer "In4.Cu") (net 115))
  (segment (start 94.872518 115.080248) (end 94.85381 115.103708) (width 0.109) (layer "In4.Cu") (net 115))
  (segment (start 95.093808 115.261484) (end 95.123061 115.254806) (width 0.109) (layer "In4.Cu") (net 115))
  (segment (start 89.4415 118.884) (end 89.8265 118.574) (width 0.182) (layer "F.Cu") (net 116))
  (via (at 89.4415 118.884) (size 0.45) (drill 0.1) (layers "F.Cu" "B.Cu") (net 116))
  (via (at 93.8 89.2) (size 0.45) (drill 0.1) (layers "F.Cu" "B.Cu") (net 116))
  (segment (start 89.4415 118.884) (end 88.860293 118.302793) (width 0.109) (layer "In2.Cu") (net 116))
  (segment (start 85.167623 95.306963) (end 86.243555 96.382895) (width 0.109) (layer "In2.Cu") (net 116))
  (segment (start 86.69 96.29) (end 88.4 94.58) (width 0.109) (layer "In2.Cu") (net 116))
  (segment (start 86.597108 96.382893) (end 86.69 96.29) (width 0.109) (layer "In2.Cu") (net 116))
  (segment (start 86.597109 96.382894) (end 86.597108 96.382893) (width 0.109) (layer "In2.Cu") (net 116))
  (segment (start 85.89 96.736448) (end 85.890001 96.736446) (width 0.109) (layer "In2.Cu") (net 116))
  (segment (start 85.890001 96.736446) (end 84.81407 95.660515) (width 0.109) (layer "In2.Cu") (net 116))
  (segment (start 86.597109 96.382895) (end 86.597109 96.382894) (width 0.109) (layer "In2.Cu") (net 116))
  (segment (start 88.4 94.58) (end 91.8 94.58) (width 0.109) (layer "In2.Cu") (net 116))
  (segment (start 93.8 92.579998) (end 93.8 89.2) (width 0.109) (layer "In2.Cu") (net 116))
  (segment (start 85.222793 118.297793) (end 82.1 115.175) (width 0.109) (layer "In2.Cu") (net 116))
  (segment (start 92.155067 94.224931) (end 93.8 92.579998) (width 0.109) (layer "In2.Cu") (net 116))
  (segment (start 91.8 94.58) (end 92.155067 94.224931) (width 0.109) (layer "In2.Cu") (net 116))
  (segment (start 88.860293 118.302793) (end 88.860293 118.297793) (width 0.109) (layer "In2.Cu") (net 116))
  (segment (start 88.860293 118.297793) (end 85.222793 118.297793) (width 0.109) (layer "In2.Cu") (net 116))
  (segment (start 84.81407 95.306961) (end 84.814069 95.306963) (width 0.109) (layer "In2.Cu") (net 116))
  (segment (start 82.1 115.175) (end 82.1 100.88) (width 0.109) (layer "In2.Cu") (net 116))
  (segment (start 82.1 100.88) (end 85.89 97.09) (width 0.109) (layer "In2.Cu") (net 116))
  (arc (start 86.243555 96.382895) (mid 86.420332 96.456118) (end 86.597109 96.382895) (width 0.109) (layer "In2.Cu") (net 116))
  (arc (start 84.814069 95.306963) (mid 84.990846 95.23374) (end 85.167623 95.306963) (width 0.109) (layer "In2.Cu") (net 116))
  (arc (start 84.81407 95.660515) (mid 84.740847 95.483738) (end 84.81407 95.306961) (width 0.109) (layer "In2.Cu") (net 116))
  (arc (start 85.89 97.09) (mid 85.963224 96.913223) (end 85.89 96.736448) (width 0.109) (layer "In2.Cu") (net 116))
  (segment (start 93.8 87.145) (end 93.8 89.2) (width 0.182) (layer "B.Cu") (net 116))
  (segment (start 89.8265 117.939) (end 90.3 117.625) (width 0.182) (layer "F.Cu") (net 117))
  (via (at 90.3 117.625) (size 0.45) (drill 0.1) (layers "F.Cu" "B.Cu") (net 117))
  (via (at 91.9 86.7) (size 0.45) (drill 0.1) (layers "F.Cu" "B.Cu") (net 117))
  (segment (start 91.9 87.68) (end 93.02 88.8) (width 0.109) (layer "In2.Cu") (net 117))
  (segment (start 92.4 95.28) (end 88.9 95.28) (width 0.109) (layer "In2.Cu") (net 117))
  (segment (start 89.8906 116.7638) (end 89.8906 117.2156) (width 0.109) (layer "In2.Cu") (net 117))
  (segment (start 89.8906 117.2156) (end 90.3 117.625) (width 0.109) (layer "In2.Cu") (net 117))
  (segment (start 91.9 86.7) (end 91.9 87.68) (width 0.109) (layer "In2.Cu") (net 117))
  (segment (start 85.405 117.28) (end 87.4 117.28) (width 0.109) (layer "In2.Cu") (net 117))
  (segment (start 94.5 93.18) (end 92.4 95.28) (width 0.109) (layer "In2.Cu") (net 117))
  (segment (start 94.5 89.08) (end 94.5 93.18) (width 0.109) (layer "In2.Cu") (net 117))
  (segment (start 88.9 95.28) (end 82.7 101.48) (width 0.109) (layer "In2.Cu") (net 117))
  (segment (start 82.7 114.575) (end 85.405 117.28) (width 0.109) (layer "In2.Cu") (net 117))
  (segment (start 89.644821 116.518021) (end 89.8906 116.7638) (width 0.109) (layer "In2.Cu") (net 117))
  (segment (start 82.7 101.48) (end 82.7 114.575) (width 0.109) (layer "In2.Cu") (net 117))
  (segment (start 87.4 117.28) (end 88.161979 116.518021) (width 0.109) (layer "In2.Cu") (net 117))
  (segment (start 88.161979 116.518021) (end 89.644821 116.518021) (width 0.109) (layer "In2.Cu") (net 117))
  (segment (start 94.22 88.8) (end 94.5 89.08) (width 0.109) (layer "In2.Cu") (net 117))
  (segment (start 93.02 88.8) (end 94.22 88.8) (width 0.109) (layer "In2.Cu") (net 117))
  (segment (start 92.1 86.5) (end 91.9 86.7) (width 0.182) (layer "B.Cu") (net 117))
  (segment (start 92.755 86.5) (end 92.1 86.5) (width 0.182) (layer "B.Cu") (net 117))
  (segment (start 96.3 119) (end 96.6872 118.6128) (width 0.182) (layer "F.Cu") (net 118))
  (segment (start 97.4361 118.6128) (end 97.4457 118.6032) (width 0.182) (layer "F.Cu") (net 118))
  (segment (start 89.523032 115.702468) (end 89.4415 115.702468) (width 0.182) (layer "F.Cu") (net 118))
  (segment (start 89.8265 115.399) (end 89.523032 115.702468) (width 0.182) (layer "F.Cu") (net 118))
  (segment (start 96.6872 118.6128) (end 97.4361 118.6128) (width 0.182) (layer "F.Cu") (net 118))
  (via (at 89.4415 115.702468) (size 0.45) (drill 0.1) (layers "F.Cu" "B.Cu") (net 118))
  (via (at 96.3 119) (size 0.45) (drill 0.1) (layers "F.Cu" "B.Cu") (net 118))
  (segment (start 90.28651 116.54901) (end 90.28651 116.547478) (width 0.109) (layer "In4.Cu") (net 118))
  (segment (start 95.75 118.6) (end 95.75 118.75) (width 0.109) (layer "In4.Cu") (net 118))
  (segment (start 90.28651 116.547478) (end 89.4415 115.702468) (width 0.109) (layer "In4.Cu") (net 118))
  (segment (start 90.28651 116.54901) (end 92.24901 116.54901) (width 0.109) (layer "In4.Cu") (net 118))
  (segment (start 92.24901 116.54901) (end 92.745 117.045) (width 0.109) (layer "In4.Cu") (net 118))
  (segment (start 92.745 117.045) (end 94.195 117.045) (width 0.109) (layer "In4.Cu") (net 118))
  (segment (start 95.75 118.75) (end 96 119) (width 0.109) (layer "In4.Cu") (net 118))
  (segment (start 94.195 117.045) (end 95.75 118.6) (width 0.109) (layer "In4.Cu") (net 118))
  (segment (start 96 119) (end 96.3 119) (width 0.109) (layer "In4.Cu") (net 118))
  (segment (start 89.8265 105.874) (end 90.306 105.563) (width 0.182) (layer "F.Cu") (net 119))
  (via (at 90.306 105.563) (size 0.45) (drill 0.1) (layers "F.Cu" "B.Cu") (net 119))
  (via (at 134.431877 120.812245) (size 0.45) (drill 0.1) (layers "F.Cu" "B.Cu") (net 119))
  (segment (start 87.8475 105.2525) (end 88.3025 104.7975) (width 0.109) (layer "In2.Cu") (net 119))
  (segment (start 94.447186 112.6775) (end 88.547186 112.6775) (width 0.109) (layer "In2.Cu") (net 119))
  (segment (start 131.617186 119.5475) (end 125.497186 119.5475) (width 0.109) (layer "In2.Cu") (net 119))
  (segment (start 90.033 105.563) (end 90.306 105.563) (width 0.109) (layer "In2.Cu") (net 119))
  (segment (start 125.497186 119.5475) (end 119.377186 113.4275) (width 0.109) (layer "In2.Cu") (net 119))
  (segment (start 119.377186 113.4275) (end 95.197186 113.4275) (width 0.109) (layer "In2.Cu") (net 119))
  (segment (start 134.286378 120.666746) (end 132.736432 120.666746) (width 0.109) (layer "In2.Cu") (net 119))
  (segment (start 95.197186 113.4275) (end 94.447186 112.6775) (width 0.109) (layer "In2.Cu") (net 119))
  (segment (start 88.547186 112.6775) (end 87.8475 111.977814) (width 0.109) (layer "In2.Cu") (net 119))
  (segment (start 88.3025 104.7975) (end 89.672814 104.7975) (width 0.109) (layer "In2.Cu") (net 119))
  (segment (start 87.8475 111.977814) (end 87.8475 105.2525) (width 0.109) (layer "In2.Cu") (net 119))
  (segment (start 132.736432 120.666746) (end 131.617186 119.5475) (width 0.109) (layer "In2.Cu") (net 119))
  (segment (start 89.9505 105.4805) (end 90.033 105.563) (width 0.109) (layer "In2.Cu") (net 119))
  (segment (start 89.9505 105.075186) (end 89.9505 105.4805) (width 0.109) (layer "In2.Cu") (net 119))
  (segment (start 134.431877 120.812245) (end 134.286378 120.666746) (width 0.109) (layer "In2.Cu") (net 119))
  (segment (start 89.672814 104.7975) (end 89.9505 105.075186) (width 0.109) (layer "In2.Cu") (net 119))
  (segment (start 134.319877 120.700245) (end 133.827445 120.700245) (width 0.182) (layer "B.Cu") (net 119))
  (segment (start 133.34169 121.186) (end 133.002559 121.186) (width 0.182) (layer "B.Cu") (net 119))
  (segment (start 133.002559 121.186) (end 132.913559 121.275) (width 0.182) (layer "B.Cu") (net 119))
  (segment (start 134.431877 120.812245) (end 134.319877 120.700245) (width 0.182) (layer "B.Cu") (net 119))
  (segment (start 133.827445 120.700245) (end 133.34169 121.186) (width 0.182) (layer "B.Cu") (net 119))
  (segment (start 132.913559 121.275) (end 132.288559 121.275) (width 0.182) (layer "B.Cu") (net 119))
  (segment (start 89.35 105.553) (end 89.8265 105.239) (width 0.182) (layer "F.Cu") (net 120))
  (via (at 89.35 105.553) (size 0.45) (drill 0.1) (layers "F.Cu" "B.Cu") (net 120))
  (via (at 134.431877 120.262742) (size 0.45) (drill 0.1) (layers "F.Cu" "B.Cu") (net 120))
  (segment (start 88.293231 111.97565) (end 88.269434 111.981081) (width 0.109) (layer "In2.Cu") (net 120))
  (segment (start 89.617 105.553) (end 89.35 105.553) (width 0.109) (layer "In2.Cu") (net 120))
  (segment (start 88.119831 106.48657) (end 88.14068 106.453389) (width 0.109) (layer "In2.Cu") (net 120))
  (segment (start 88.461204 106.0375) (end 88.2775 106.0375) (width 0.109) (layer "In2.Cu") (net 120))
  (segment (start 88.570315 106.34932) (end 88.598025 106.32161) (width 0.109) (layer "In2.Cu") (net 120))
  (segment (start 89.6955 105.4745) (end 89.617 105.553) (width 0.109) (layer "In2.Cu") (net 120))
  (segment (start 88.524522 111.817663) (end 88.500114 111.817663) (width 0.109) (layer "In2.Cu") (net 120))
  (segment (start 88.488455 112.258141) (end 88.473235 112.239056) (width 0.109) (layer "In2.Cu") (net 120))
  (segment (start 88.461204 106.3875) (end 88.500146 106.383112) (width 0.109) (layer "In2.Cu") (net 120))
  (segment (start 88.570315 106.075679) (end 88.537134 106.05483) (width 0.109) (layer "In2.Cu") (net 120))
  (segment (start 88.631817 106.251441) (end 88.636204 106.2125) (width 0.109) (layer "In2.Cu") (net 120))
  (segment (start 88.1025 111.872186) (end 88.1025 106.5625) (width 0.109) (layer "In2.Cu") (net 120))
  (segment (start 88.1025 105.377814) (end 88.427814 105.0525) (width 0.109) (layer "In2.Cu") (net 120))
  (segment (start 125.602814 119.2925) (end 119.482814 113.1725) (width 0.109) (layer "In2.Cu") (net 120))
  (segment (start 88.106888 106.523558) (end 88.119831 106.48657) (width 0.109) (layer "In2.Cu") (net 120))
  (segment (start 88.500146 106.383112) (end 88.537134 106.370169) (width 0.109) (layer "In2.Cu") (net 120))
  (segment (start 88.201571 106.020169) (end 88.16839 105.99932) (width 0.109) (layer "In2.Cu") (net 120))
  (segment (start 88.537134 106.05483) (end 88.500146 106.041887) (width 0.109) (layer "In2.Cu") (net 120))
  (segment (start 88.620632 111.938181) (end 88.620632 111.913773) (width 0.109) (layer "In2.Cu") (net 120))
  (segment (start 88.589394 111.848904) (end 88.570309 111.833684) (width 0.109) (layer "In2.Cu") (net 120))
  (segment (start 88.604611 111.867986) (end 88.589394 111.848904) (width 0.109) (layer "In2.Cu") (net 120))
  (segment (start 88.119831 105.938429) (end 88.106888 105.901441) (width 0.109) (layer "In2.Cu") (net 120))
  (segment (start 88.457214 112.168861) (end 88.462646 112.145066) (width 0.109) (layer "In2.Cu") (net 120))
  (segment (start 88.334305 111.949842) (end 88.315223 111.965061) (width 0.109) (layer "In2.Cu") (net 120))
  (segment (start 88.618874 106.13657) (end 88.598025 106.103389) (width 0.109) (layer "In2.Cu") (net 120))
  (segment (start 88.598025 106.32161) (end 88.618874 106.288429) (width 0.109) (layer "In2.Cu") (net 120))
  (segment (start 88.631817 106.173558) (end 88.618874 106.13657) (width 0.109) (layer "In2.Cu") (net 120))
  (segment (start 95.302814 113.1725) (end 94.552814 112.4225) (width 0.109) (layer "In2.Cu") (net 120))
  (segment (start 131.722814 119.2925) (end 125.602814 119.2925) (width 0.109) (layer "In2.Cu") (net 120))
  (segment (start 88.201571 106.40483) (end 88.238559 106.391887) (width 0.109) (layer "In2.Cu") (net 120))
  (segment (start 89.567186 105.0525) (end 89.6955 105.180814) (width 0.109) (layer "In2.Cu") (net 120))
  (segment (start 88.473236 112.123074) (end 88.488455 112.103991) (width 0.109) (layer "In2.Cu") (net 120))
  (segment (start 88.2775 106.0375) (end 88.238559 106.033112) (width 0.109) (layer "In2.Cu") (net 120))
  (segment (start 88.462646 112.145066) (end 88.473236 112.123074) (width 0.109) (layer "In2.Cu") (net 120))
  (segment (start 88.269434 111.981081) (end 88.245026 111.981081) (width 0.109) (layer "In2.Cu") (net 120))
  (segment (start 88.652814 112.4225) (end 88.488455 112.258141) (width 0.109) (layer "In2.Cu") (net 120))
  (segment (start 94.552814 112.4225) (end 88.652814 112.4225) (width 0.109) (layer "In2.Cu") (net 120))
  (segment (start 88.14068 106.453389) (end 88.16839 106.425679) (width 0.109) (layer "In2.Cu") (net 120))
  (segment (start 88.488455 112.103991) (end 88.589393 112.003052) (width 0.109) (layer "In2.Cu") (net 120))
  (segment (start 134.431877 120.262742) (end 134.282875 120.411744) (width 0.109) (layer "In2.Cu") (net 120))
  (segment (start 88.548319 111.823095) (end 88.524522 111.817663) (width 0.109) (layer "In2.Cu") (net 120))
  (segment (start 88.1025 106.5625) (end 88.106888 106.523558) (width 0.109) (layer "In2.Cu") (net 120))
  (segment (start 88.2775 106.3875) (end 88.461204 106.3875) (width 0.109) (layer "In2.Cu") (net 120))
  (segment (start 88.618874 106.288429) (end 88.631817 106.251441) (width 0.109) (layer "In2.Cu") (net 120))
  (segment (start 88.476319 111.823095) (end 88.454327 111.833685) (width 0.109) (layer "In2.Cu") (net 120))
  (segment (start 88.1025 105.8625) (end 88.1025 105.377814) (width 0.109) (layer "In2.Cu") (net 120))
  (segment (start 134.282875 120.411744) (end 132.842058 120.411744) (width 0.109) (layer "In2.Cu") (net 120))
  (segment (start 88.427814 105.0525) (end 89.567186 105.0525) (width 0.109) (layer "In2.Cu") (net 120))
  (segment (start 88.180157 111.949843) (end 88.1025 111.872186) (width 0.109) (layer "In2.Cu") (net 120))
  (segment (start 88.454327 111.833685) (end 88.435244 111.848904) (width 0.109) (layer "In2.Cu") (net 120))
  (segment (start 88.245026 111.981081) (end 88.221231 111.975651) (width 0.109) (layer "In2.Cu") (net 120))
  (segment (start 88.570309 111.833684) (end 88.548319 111.823095) (width 0.109) (layer "In2.Cu") (net 120))
  (segment (start 89.6955 105.180814) (end 89.6955 105.4745) (width 0.109) (layer "In2.Cu") (net 120))
  (segment (start 88.500114 111.817663) (end 88.476319 111.823095) (width 0.109) (layer "In2.Cu") (net 120))
  (segment (start 88.16839 106.425679) (end 88.201571 106.40483) (width 0.109) (layer "In2.Cu") (net 120))
  (segment (start 88.315223 111.965061) (end 88.293231 111.97565) (width 0.109) (layer "In2.Cu") (net 120))
  (segment (start 88.636204 106.2125) (end 88.631817 106.173558) (width 0.109) (layer "In2.Cu") (net 120))
  (segment (start 88.615201 111.961978) (end 88.620632 111.938181) (width 0.109) (layer "In2.Cu") (net 120))
  (segment (start 88.221231 111.975651) (end 88.199239 111.96506) (width 0.109) (layer "In2.Cu") (net 120))
  (segment (start 88.14068 105.97161) (end 88.119831 105.938429) (width 0.109) (layer "In2.Cu") (net 120))
  (segment (start 88.589393 112.003052) (end 88.604612 111.98397) (width 0.109) (layer "In2.Cu") (net 120))
  (segment (start 88.238559 106.391887) (end 88.2775 106.3875) (width 0.109) (layer "In2.Cu") (net 120))
  (segment (start 88.604612 111.98397) (end 88.615201 111.961978) (width 0.109) (layer "In2.Cu") (net 120))
  (segment (start 119.482814 113.1725) (end 95.302814 113.1725) (width 0.109) (layer "In2.Cu") (net 120))
  (segment (start 88.620632 111.913773) (end 88.615202 111.889978) (width 0.109) (layer "In2.Cu") (net 120))
  (segment (start 88.500146 106.041887) (end 88.461204 106.0375) (width 0.109) (layer "In2.Cu") (net 120))
  (segment (start 88.598025 106.103389) (end 88.570315 106.075679) (width 0.109) (layer "In2.Cu") (net 120))
  (segment (start 88.435244 111.848904) (end 88.334305 111.949842) (width 0.109) (layer "In2.Cu") (net 120))
  (segment (start 88.238559 106.033112) (end 88.201571 106.020169) (width 0.109) (layer "In2.Cu") (net 120))
  (segment (start 88.537134 106.370169) (end 88.570315 106.34932) (width 0.109) (layer "In2.Cu") (net 120))
  (segment (start 88.462646 112.217066) (end 88.457214 112.193269) (width 0.109) (layer "In2.Cu") (net 120))
  (segment (start 88.473235 112.239056) (end 88.462646 112.217066) (width 0.109) (layer "In2.Cu") (net 120))
  (segment (start 88.457214 112.193269) (end 88.457214 112.168861) (width 0.109) (layer "In2.Cu") (net 120))
  (segment (start 88.16839 105.99932) (end 88.14068 105.97161) (width 0.109) (layer "In2.Cu") (net 120))
  (segment (start 88.106888 105.901441) (end 88.1025 105.8625) (width 0.109) (layer "In2.Cu") (net 120))
  (segment (start 132.842058 120.411744) (end 131.722814 119.2925) (width 0.109) (layer "In2.Cu") (net 120))
  (segment (start 88.199239 111.96506) (end 88.180157 111.949843) (width 0.109) (layer "In2.Cu") (net 120))
  (segment (start 88.615202 111.889978) (end 88.604611 111.867986) (width 0.109) (layer "In2.Cu") (net 120))
  (segment (start 133.694065 120.378245) (end 133.20831 120.864) (width 0.182) (layer "B.Cu") (net 120))
  (segment (start 133.002559 120.864) (end 132.913559 120.775) (width 0.182) (layer "B.Cu") (net 120))
  (segment (start 134.431877 120.262742) (end 134.316374 120.378245) (width 0.182) (layer "B.Cu") (net 120))
  (segment (start 134.316374 120.378245) (end 133.694065 120.378245) (width 0.182) (layer "B.Cu") (net 120))
  (segment (start 132.913559 120.775) (end 132.288559 120.775) (width 0.182) (layer "B.Cu") (net 120))
  (segment (start 133.20831 120.864) (end 133.002559 120.864) (width 0.182) (layer "B.Cu") (net 120))
  (segment (start 114.649937 122.6946) (end 114.649937 123.857063) (width 0.178) (layer "F.Cu") (net 121))
  (segment (start 114.649937 123.857063) (end 114.507 124) (width 0.178) (layer "F.Cu") (net 121))
  (via (at 134.245 118.801446) (size 0.45) (drill 0.1) (layers "F.Cu" "B.Cu") (net 121))
  (via (at 114.507 124) (size 0.45) (drill 0.1) (layers "F.Cu" "B.Cu") (net 121))
  (segment (start 114.6785 123.8285) (end 114.507 124) (width 0.107) (layer "In4.Cu") (net 121))
  (segment (start 122.14175 119.3285) (end 121.69175 118.8785) (width 0.107) (layer "In4.Cu") (net 121))
  (segment (start 132.65825 119.3285) (end 122.14175 119.3285) (width 0.107) (layer "In4.Cu") (net 121))
  (segment (start 121.69175 118.8785) (end 118.70825 118.8785) (width 0.107) (layer "In4.Cu") (net 121))
  (segment (start 134.245 118.801446) (end 134.1685 118.877946) (width 0.107) (layer "In4.Cu") (net 121))
  (segment (start 134.1685 118.877946) (end 133.108804 118.877946) (width 0.107) (layer "In4.Cu") (net 121))
  (segment (start 118.70825 118.8785) (end 114.6785 122.90825) (width 0.107) (layer "In4.Cu") (net 121))
  (segment (start 133.108804 118.877946) (end 132.65825 119.3285) (width 0.107) (layer "In4.Cu") (net 121))
  (segment (start 114.6785 122.90825) (end 114.6785 123.8285) (width 0.107) (layer "In4.Cu") (net 121))
  (segment (start 133.246435 119.335723) (end 133.671712 118.910446) (width 0.182) (layer "B.Cu") (net 121))
  (segment (start 134.245 118.801446) (end 134.136 118.910446) (width 0.182) (layer "B.Cu") (net 121))
  (segment (start 132.974559 119.335723) (end 133.246435 119.335723) (width 0.182) (layer "B.Cu") (net 121))
  (segment (start 132.913559 119.274723) (end 132.974559 119.335723) (width 0.182) (layer "B.Cu") (net 121))
  (segment (start 133.671712 118.910446) (end 134.136 118.910446) (width 0.182) (layer "B.Cu") (net 121))
  (segment (start 132.288559 119.274723) (end 132.913559 119.274723) (width 0.182) (layer "B.Cu") (net 121))
  (segment (start 115.150063 122.6946) (end 115.150063 123.857063) (width 0.178) (layer "F.Cu") (net 122))
  (segment (start 115.150063 123.857063) (end 115.293 124) (width 0.178) (layer "F.Cu") (net 122))
  (via (at 134.245 119.397446) (size 0.45) (drill 0.1) (layers "F.Cu" "B.Cu") (net 122))
  (via (at 115.293 124) (size 0.45) (drill 0.1) (layers "F.Cu" "B.Cu") (net 122))
  (segment (start 118.609976 119.789947) (end 118.591547 119.766837) (width 0.107) (layer "In4.Cu") (net 122))
  (segment (start 118.591547 119.766837) (end 118.578722 119.740206) (width 0.107) (layer "In4.Cu") (net 122))
  (segment (start 115.293 124) (end 115.1215 123.8285) (width 0.107) (layer "In4.Cu") (net 122))
  (segment (start 118.576868 120.130192) (end 118.599978 120.148621) (width 0.107) (layer "In4.Cu") (net 122))
  (segment (start 118.599978 120.148621) (end 118.626609 120.161446) (width 0.107) (layer "In4.Cu") (net 122))
  (segment (start 118.578722 119.740206) (end 118.572144 119.711388) (width 0.107) (layer "In4.Cu") (net 122))
  (segment (start 118.286366 119.94537) (end 118.315183 119.938793) (width 0.107) (layer "In4.Cu") (net 122))
  (segment (start 121.95825 119.7715) (end 132.84175 119.7715) (width 0.107) (layer "In4.Cu") (net 122))
  (segment (start 133.292304 119.320946) (end 134.1685 119.320946) (width 0.107) (layer "In4.Cu") (net 122))
  (segment (start 118.578722 119.653012) (end 118.591547 119.626381) (width 0.107) (layer "In4.Cu") (net 122))
  (segment (start 118.609977 119.603272) (end 118.89175 119.3215) (width 0.107) (layer "In4.Cu") (net 122))
  (segment (start 118.713803 120.161446) (end 118.740434 120.148621) (width 0.107) (layer "In4.Cu") (net 122))
  (segment (start 118.259734 119.958195) (end 118.286366 119.94537) (width 0.107) (layer "In4.Cu") (net 122))
  (segment (start 118.763544 119.943515) (end 118.609976 119.789947) (width 0.107) (layer "In4.Cu") (net 122))
  (segment (start 118.373559 119.94537) (end 118.400191 119.958195) (width 0.107) (layer "In4.Cu") (net 122))
  (segment (start 118.763544 120.130192) (end 118.781973 120.107082) (width 0.107) (layer "In4.Cu") (net 122))
  (segment (start 118.89175 119.3215) (end 121.50825 119.3215) (width 0.107) (layer "In4.Cu") (net 122))
  (segment (start 118.781973 119.966625) (end 118.763544 119.943515) (width 0.107) (layer "In4.Cu") (net 122))
  (segment (start 118.794798 119.993257) (end 118.781973 119.966625) (width 0.107) (layer "In4.Cu") (net 122))
  (segment (start 118.344742 119.938793) (end 118.373559 119.94537) (width 0.107) (layer "In4.Cu") (net 122))
  (segment (start 115.1215 123.8285) (end 115.1215 123.09175) (width 0.107) (layer "In4.Cu") (net 122))
  (segment (start 121.50825 119.3215) (end 121.95825 119.7715) (width 0.107) (layer "In4.Cu") (net 122))
  (segment (start 118.684985 120.168024) (end 118.713803 120.161446) (width 0.107) (layer "In4.Cu") (net 122))
  (segment (start 134.1685 119.320946) (end 134.245 119.397446) (width 0.107) (layer "In4.Cu") (net 122))
  (segment (start 118.626609 120.161446) (end 118.655427 120.168024) (width 0.107) (layer "In4.Cu") (net 122))
  (segment (start 118.236625 119.976625) (end 118.259734 119.958195) (width 0.107) (layer "In4.Cu") (net 122))
  (segment (start 118.794798 120.08045) (end 118.801375 120.051633) (width 0.107) (layer "In4.Cu") (net 122))
  (segment (start 118.591547 119.626381) (end 118.609977 119.603272) (width 0.107) (layer "In4.Cu") (net 122))
  (segment (start 132.84175 119.7715) (end 133.292304 119.320946) (width 0.107) (layer "In4.Cu") (net 122))
  (segment (start 118.315183 119.938793) (end 118.344742 119.938793) (width 0.107) (layer "In4.Cu") (net 122))
  (segment (start 118.400191 119.958195) (end 118.423301 119.976625) (width 0.107) (layer "In4.Cu") (net 122))
  (segment (start 115.1215 123.09175) (end 118.236625 119.976625) (width 0.107) (layer "In4.Cu") (net 122))
  (segment (start 118.655427 120.168024) (end 118.684985 120.168024) (width 0.107) (layer "In4.Cu") (net 122))
  (segment (start 118.423301 119.976625) (end 118.576868 120.130192) (width 0.107) (layer "In4.Cu") (net 122))
  (segment (start 118.740434 120.148621) (end 118.763544 120.130192) (width 0.107) (layer "In4.Cu") (net 122))
  (segment (start 118.801375 120.051633) (end 118.801375 120.022074) (width 0.107) (layer "In4.Cu") (net 122))
  (segment (start 118.781973 120.107082) (end 118.794798 120.08045) (width 0.107) (layer "In4.Cu") (net 122))
  (segment (start 118.801375 120.022074) (end 118.794798 119.993257) (width 0.107) (layer "In4.Cu") (net 122))
  (segment (start 118.572144 119.68183) (end 118.578722 119.653012) (width 0.107) (layer "In4.Cu") (net 122))
  (segment (start 118.572144 119.711388) (end 118.572144 119.68183) (width 0.107) (layer "In4.Cu") (net 122))
  (segment (start 132.913559 119.774723) (end 132.974559 119.713723) (width 0.182) (layer "B.Cu") (net 122))
  (segment (start 133.403011 119.713723) (end 133.828288 119.288446) (width 0.182) (layer "B.Cu") (net 122))
  (segment (start 134.245 119.397446) (end 134.136 119.288446) (width 0.182) (layer "B.Cu") (net 122))
  (segment (start 132.288559 119.774723) (end 132.913559 119.774723) (width 0.182) (layer "B.Cu") (net 122))
  (segment (start 133.828288 119.288446) (end 134.136 119.288446) (width 0.182) (layer "B.Cu") (net 122))
  (segment (start 132.974559 119.713723) (end 133.403011 119.713723) (width 0.182) (layer "B.Cu") (net 122))
  (segment (start 91.9815 113.804) (end 92.3665 113.494) (width 0.182) (layer "F.Cu") (net 123))
  (segment (start 96.575 115.85) (end 96.250004 115.85) (width 0.182) (layer "F.Cu") (net 123))
  (segment (start 96.725 115.7) (end 96.575 115.85) (width 0.182) (layer "F.Cu") (net 123))
  (segment (start 96.725 115.7) (end 97.24 115.7) (width 0.182) (layer "F.Cu") (net 123))
  (segment (start 96.250004 115.85) (end 96.225004 115.825) (width 0.182) (layer "F.Cu") (net 123))
  (via (at 91.9815 113.804) (size 0.45) (drill 0.1) (layers "F.Cu" "B.Cu") (net 123))
  (via (at 96.225004 115.825) (size 0.45) (drill 0.1) (layers "F.Cu" "B.Cu") (net 123))
  (segment (start 95.550534 115.483562) (end 95.539945 115.461572) (width 0.109) (layer "In4.Cu") (net 123))
  (segment (start 95.655032 115.533886) (end 95.630624 115.533886) (width 0.109) (layer "In4.Cu") (net 123))
  (segment (start 93.601348 114.453183) (end 93.582388 114.465096) (width 0.109) (layer "In4.Cu") (net 123))
  (segment (start 94.330651 114.253184) (end 94.314816 114.237349) (width 0.109) (layer "In4.Cu") (net 123))
  (segment (start 96.042502 115.488348) (end 96.127511 115.403338) (width 0.109) (layer "In4.Cu") (net 123))
  (segment (start 95.700821 115.517866) (end 95.678829 115.528455) (width 0.109) (layer "In4.Cu") (net 123))
  (segment (start 94.152747 114.077508) (end 94.131611 114.084904) (width 0.109) (layer "In4.Cu") (net 123))
  (segment (start 93.442816 114.437348) (end 93.430903 114.418388) (width 0.109) (layer "In4.Cu") (net 123))
  (segment (start 93.399183 114.112652) (end 93.383348 114.096817) (width 0.109) (layer "In4.Cu") (net 123))
  (segment (start 94.037348 114.453183) (end 94.018388 114.465096) (width 0.109) (layer "In4.Cu") (net 123))
  (segment (start 93.181183 114.437348) (end 93.165348 114.453183) (width 0.109) (layer "In4.Cu") (net 123))
  (segment (start 93.695611 114.084904) (end 93.676651 114.096817) (width 0.109) (layer "In4.Cu") (net 123))
  (segment (start 95.992444 115.233969) (end 95.973361 115.249188) (width 0.109) (layer "In4.Cu") (net 123))
  (segment (start 93.203 114.175) (end 93.203 114.375) (width 0.109) (layer "In4.Cu") (net 123))
  (segment (start 93.022651 114.453183) (end 93.006816 114.437348) (width 0.109) (layer "In4.Cu") (net 123))
  (segment (start 93.224816 114.112652) (end 93.212903 114.131612) (width 0.109) (layer "In4.Cu") (net 123))
  (segment (start 94.065096 114.418388) (end 94.053183 114.437348) (width 0.109) (layer "In4.Cu") (net 123))
  (segment (start 96.14273 115.268272) (end 96.127511 115.249188) (width 0.109) (layer "In4.Cu") (net 123))
  (segment (start 95.565754 115.502647) (end 95.550534 115.483562) (width 0.109) (layer "In4.Cu") (net 123))
  (segment (start 93.103 114.475) (end 93.085 114.475) (width 0.109) (layer "In4.Cu") (net 123))
  (segment (start 95.778137 114.915081) (end 95.754341 114.90965) (width 0.109) (layer "In4.Cu") (net 123))
  (segment (start 96.027283 115.623414) (end 96.016693 115.601423) (width 0.109) (layer "In4.Cu") (net 123))
  (segment (start 92.269342 113.804) (end 91.9815 113.804) (width 0.109) (layer "In4.Cu") (net 123))
  (segment (start 93.835183 114.112652) (end 93.819348 114.096817) (width 0.109) (layer "In4.Cu") (net 123))
  (segment (start 93.303 114.075) (end 93.280747 114.077508) (width 0.109) (layer "In4.Cu") (net 123))
  (segment (start 96.086436 115.223379) (end 96.06264 115.217948) (width 0.109) (layer "In4.Cu") (net 123))
  (segment (start 94.018388 114.465096) (end 93.997252 114.472492) (width 0.109) (layer "In4.Cu") (net 123))
  (segment (start 94.084903 114.131612) (end 94.077507 114.152748) (width 0.109) (layer "In4.Cu") (net 123))
  (segment (start 95.538977 115.051708) (end 95.515181 115.057139) (width 0.109) (layer "In4.Cu") (net 123))
  (segment (start 95.606829 115.528456) (end 95.584837 115.517865) (width 0.109) (layer "In4.Cu") (net 123))
  (segment (start 93.006816 114.437348) (end 92.994903 114.418388) (width 0.109) (layer "In4.Cu") (net 123))
  (segment (start 93.934747 114.472492) (end 93.913611 114.465096) (width 0.109) (layer "In4.Cu") (net 123))
  (segment (start 94.131611 114.084904) (end 94.112651 114.096817) (width 0.109) (layer "In4.Cu") (net 123))
  (segment (start 92.928388 114.284903) (end 92.907252 114.277507) (width 0.109) (layer "In4.Cu") (net 123))
  (segment (start 96.158751 115.314059) (end 96.15332 115.290263) (width 0.109) (layer "In4.Cu") (net 123))
  (segment (start 93.648903 114.131612) (end 93.641507 114.152748) (width 0.109) (layer "In4.Cu") (net 123))
  (segment (start 95.845021 115.053965) (end 95.850452 115.030169) (width 0.109) (layer "In4.Cu") (net 123))
  (segment (start 93.041611 114.465096) (end 93.022651 114.453183) (width 0.109) (layer "In4.Cu") (net 123))
  (segment (start 95.560969 115.041118) (end 95.538977 115.051708) (width 0.109) (layer "In4.Cu") (net 123))
  (segment (start 94.075 114.175) (end 94.075 114.375) (width 0.109) (layer "In4.Cu") (net 123))
  (segment (start 93.200492 114.397252) (end 93.193096 114.418388) (width 0.109) (layer "In4.Cu") (net 123))
  (segment (start 93.561252 114.472492) (end 93.539 114.475) (width 0.109) (layer "In4.Cu") (net 123))
  (segment (start 95.83443 114.959973) (end 95.819212 114.94089) (width 0.109) (layer "In4.Cu") (net 123))
  (segment (start 94.370747 114.272493) (end 94.349611 114.265097) (width 0.109) (layer "In4.Cu") (net 123))
  (segment (start 93.878816 114.437348) (end 93.866903 114.418388) (width 0.109) (layer "In4.Cu") (net 123))
  (segment (start 93.629096 114.418388) (end 93.617183 114.437348) (width 0.109) (layer "In4.Cu") (net 123))
  (segment (start 93.636492 114.397252) (end 93.629096 114.418388) (width 0.109) (layer "In4.Cu") (net 123))
  (segment (start 95.444986 115.041118) (end 95.425902 115.025899) (width 0.109) (layer "In4.Cu") (net 123))
  (segment (start 93.997252 114.472492) (end 93.975 114.475) (width 0.109) (layer "In4.Cu") (net 123))
  (segment (start 93.857 114.375) (end 93.857 114.175) (width 0.109) (layer "In4.Cu") (net 123))
  (segment (start 95.811276 115.411272) (end 95.811277 115.411273) (width 0.109) (layer "In4.Cu") (net 123))
  (segment (start 95.819212 115.095039) (end 95.83443 115.075956) (width 0.109) (layer "In4.Cu") (net 123))
  (segment (start 95.706136 114.915081) (end 95.684145 114.925671) (width 0.109) (layer "In4.Cu") (net 123))
  (segment (start 96.042502 115.642498) (end 96.027283 115.623414) (width 0.109) (layer "In4.Cu") (net 123))
  (segment (start 93.779252 114.077508) (end 93.757 114.075) (width 0.109) (layer "In4.Cu") (net 123))
  (segment (start 96.127511 115.249188) (end 96.108427 115.233969) (width 0.109) (layer "In4.Cu") (net 123))
  (segment (start 93.240651 114.096817) (end 93.224816 114.112652) (width 0.109) (layer "In4.Cu") (net 123))
  (segment (start 95.539945 115.461572) (end 95.534513 115.437775) (width 0.109) (layer "In4.Cu") (net 123))
  (segment (start 93.212903 114.131612) (end 93.205507 114.152748) (width 0.109) (layer "In4.Cu") (net 123))
  (segment (start 94.283096 114.131612) (end 94.271183 114.112652) (width 0.109) (layer "In4.Cu") (net 123))
  (segment (start 96.06264 115.217948) (end 96.038232 115.217948) (width 0.109) (layer "In4.Cu") (net 123))
  (segment (start 93.800388 114.084904) (end 93.779252 114.077508) (width 0.109) (layer "In4.Cu") (net 123))
  (segment (start 94.349611 114.265097) (end 94.330651 114.253184) (width 0.109) (layer "In4.Cu") (net 123))
  (segment (start 93.854492 114.152748) (end 93.847096 114.131612) (width 0.109) (layer "In4.Cu") (net 123))
  (segment (start 93.539 114.475) (end 93.521 114.475) (width 0.109) (layer "In4.Cu") (net 123))
  (segment (start 93.383348 114.096817) (end 93.364388 114.084904) (width 0.109) (layer "In4.Cu") (net 123))
  (segment (start 95.565754 115.348497) (end 95.657126 115.257122) (width 0.109) (layer "In4.Cu") (net 123))
  (segment (start 93.894651 114.453183) (end 93.878816 114.437348) (width 0.109) (layer "In4.Cu") (net 123))
  (segment (start 95.83443 115.075956) (end 95.845021 115.053965) (width 0.109) (layer "In4.Cu") (net 123))
  (segment (start 92.963183 114.312651) (end 92.947348 114.296816) (width 0.109) (layer "In4.Cu") (net 123))
  (segment (start 94.072492 114.397252) (end 94.065096 114.418388) (width 0.109) (layer "In4.Cu") (net 123))
  (segment (start 95.630624 115.533886) (end 95.606829 115.528456) (width 0.109) (layer "In4.Cu") (net 123))
  (segment (start 94.393 114.275) (end 94.370747 114.272493) (width 0.109) (layer "In4.Cu") (net 123))
  (segment (start 96.225004 115.825) (end 96.042502 115.642498) (width 0.109) (layer "In4.Cu") (net 123))
  (segment (start 93.521 114.475) (end 93.498747 114.472492) (width 0.109) (layer "In4.Cu") (net 123))
  (segment (start 96.158751 115.338467) (end 96.158751 115.314059) (width 0.109) (layer "In4.Cu") (net 123))
  (segment (start 93.205507 114.152748) (end 93.203 114.175) (width 0.109) (layer "In4.Cu") (net 123))
  (segment (start 93.421 114.375) (end 93.421 114.175) (width 0.109) (layer "In4.Cu") (net 123))
  (segment (start 93.866903 114.418388) (end 93.859507 114.397252) (width 0.109) (layer "In4.Cu") (net 123))
  (segment (start 93.498747 114.472492) (end 93.477611 114.465096) (width 0.109) (layer "In4.Cu") (net 123))
  (segment (start 92.982492 114.352747) (end 92.975096 114.331611) (width 0.109) (layer "In4.Cu") (net 123))
  (segment (start 93.859507 114.397252) (end 93.857 114.375) (width 0.109) (layer "In4.Cu") (net 123))
  (segment (start 95.580052 115.025899) (end 95.560969 115.041118) (width 0.109) (layer "In4.Cu") (net 123))
  (segment (start 93.062747 114.472492) (end 93.041611 114.465096) (width 0.109) (layer "In4.Cu") (net 123))
  (segment (start 95.800128 114.925671) (end 95.778137 114.915081) (width 0.109) (layer "In4.Cu") (net 123))
  (segment (start 96.127511 115.403338) (end 96.14273 115.384255) (width 0.109) (layer "In4.Cu") (net 123))
  (segment (start 93.676651 114.096817) (end 93.660816 114.112652) (width 0.109) (layer "In4.Cu") (net 123))
  (segment (start 94.675004 114.275) (end 94.393 114.275) (width 0.109) (layer "In4.Cu") (net 123))
  (segment (start 93.259611 114.084904) (end 93.240651 114.096817) (width 0.109) (layer "In4.Cu") (net 123))
  (segment (start 95.845021 114.981964) (end 95.83443 114.959973) (width 0.109) (layer "In4.Cu") (net 123))
  (segment (start 93.203 114.375) (end 93.200492 114.397252) (width 0.109) (layer "In4.Cu") (net 123))
  (segment (start 94.075 114.375) (end 94.072492 114.397252) (width 0.109) (layer "In4.Cu") (net 123))
  (segment (start 92.885 114.275) (end 92.740342 114.275) (width 0.109) (layer "In4.Cu") (net 123))
  (segment (start 95.729933 114.90965) (end 95.706136 114.915081) (width 0.109) (layer "In4.Cu") (net 123))
  (segment (start 93.582388 114.465096) (end 93.561252 114.472492) (width 0.109) (layer "In4.Cu") (net 123))
  (segment (start 93.757 114.075) (end 93.739 114.075) (width 0.109) (layer "In4.Cu") (net 123))
  (segment (start 96.016693 115.529422) (end 96.027283 115.507431) (width 0.109) (layer "In4.Cu") (net 123))
  (segment (start 95.490773 115.057139) (end 95.466977 115.051708) (width 0.109) (layer "In4.Cu") (net 123))
  (segment (start 93.411096 114.131612) (end 93.399183 114.112652) (width 0.109) (layer "In4.Cu") (net 123))
  (segment (start 92.947348 114.296816) (end 92.928388 114.284903) (width 0.109) (layer "In4.Cu") (net 123))
  (segment (start 93.716747 114.077508) (end 93.695611 114.084904) (width 0.109) (layer "In4.Cu") (net 123))
  (segment (start 95.665062 114.94089) (end 95.580052 115.025899) (width 0.109) (layer "In4.Cu") (net 123))
  (segment (start 96.011262 115.553219) (end 96.016693 115.529422) (width 0.109) (layer "In4.Cu") (net 123))
  (segment (start 93.913611 114.465096) (end 93.894651 114.453183) (width 0.109) (layer "In4.Cu") (net 123))
  (segment (start 95.539944 115.38957) (end 95.550535 115.36758) (width 0.109) (layer "In4.Cu") (net 123))
  (segment (start 94.077507 114.152748) (end 94.075 114.175) (width 0.109) (layer "In4.Cu") (net 123))
  (segment (start 95.534513 115.413367) (end 95.539944 115.38957) (width 0.109) (layer "In4.Cu") (net 123))
  (segment (start 96.016693 115.601423) (end 96.011262 115.577627) (width 0.109) (layer "In4.Cu") (net 123))
  (segment (start 95.811277 115.411273) (end 95.719904 115.502647) (width 0.109) (layer "In4.Cu") (net 123))
  (segment (start 93.321 114.075) (end 93.303 114.075) (width 0.109) (layer "In4.Cu") (net 123))
  (segment (start 92.907252 114.277507) (end 92.885 114.275) (width 0.109) (layer "In4.Cu") (net 123))
  (segment (start 96.011262 115.577627) (end 96.011262 115.553219) (width 0.109) (layer "In4.Cu") (net 123))
  (segment (start 93.280747 114.077508) (end 93.259611 114.084904) (width 0.109) (layer "In4.Cu") (net 123))
  (segment (start 93.857 114.175) (end 93.854492 114.152748) (width 0.109) (layer "In4.Cu") (net 123))
  (segment (start 93.125252 114.472492) (end 93.103 114.475) (width 0.109) (layer "In4.Cu") (net 123))
  (segment (start 93.739 114.075) (end 93.716747 114.077508) (width 0.109) (layer "In4.Cu") (net 123))
  (segment (start 94.271183 114.112652) (end 94.255348 114.096817) (width 0.109) (layer "In4.Cu") (net 123))
  (segment (start 96.108427 115.233969) (end 96.086436 115.223379) (width 0.109) (layer "In4.Cu") (net 123))
  (segment (start 95.534513 115.437775) (end 95.534513 115.413367) (width 0.109) (layer "In4.Cu") (net 123))
  (segment (start 94.053183 114.437348) (end 94.037348 114.453183) (width 0.109) (layer "In4.Cu") (net 123))
  (segment (start 94.314816 114.237349) (end 94.302903 114.218389) (width 0.109) (layer "In4.Cu") (net 123))
  (segment (start 92.975096 114.331611) (end 92.963183 114.312651) (width 0.109) (layer "In4.Cu") (net 123))
  (segment (start 96.15332 115.290263) (end 96.14273 115.268272) (width 0.109) (layer "In4.Cu") (net 123))
  (segment (start 93.957 114.475) (end 93.934747 114.472492) (width 0.109) (layer "In4.Cu") (net 123))
  (segment (start 94.302903 114.218389) (end 94.295507 114.197253) (width 0.109) (layer "In4.Cu") (net 123))
  (segment (start 93.165348 114.453183) (end 93.146388 114.465096) (width 0.109) (layer "In4.Cu") (net 123))
  (segment (start 94.193 114.075) (end 94.175 114.075) (width 0.109) (layer "In4.Cu") (net 123))
  (segment (start 93.423507 114.397252) (end 93.421 114.375) (width 0.109) (layer "In4.Cu") (net 123))
  (segment (start 93.343252 114.077508) (end 93.321 114.075) (width 0.109) (layer "In4.Cu") (net 123))
  (segment (start 93.639 114.175) (end 93.639 114.375) (width 0.109) (layer "In4.Cu") (net 123))
  (segment (start 95.584837 115.517865) (end 95.565754 115.502647) (width 0.109) (layer "In4.Cu") (net 123))
  (segment (start 95.973361 115.249188) (end 95.811276 115.411272) (width 0.109) (layer "In4.Cu") (net 123))
  (segment (start 95.754341 114.90965) (end 95.729933 114.90965) (width 0.109) (layer "In4.Cu") (net 123))
  (segment (start 95.684145 114.925671) (end 95.665062 114.94089) (width 0.109) (layer "In4.Cu") (net 123))
  (segment (start 95.550535 115.36758) (end 95.565754 115.348497) (width 0.109) (layer "In4.Cu") (net 123))
  (segment (start 96.14273 115.384255) (end 96.15332 115.362263) (width 0.109) (layer "In4.Cu") (net 123))
  (segment (start 94.175 114.075) (end 94.152747 114.077508) (width 0.109) (layer "In4.Cu") (net 123))
  (segment (start 93.975 114.475) (end 93.957 114.475) (width 0.109) (layer "In4.Cu") (net 123))
  (segment (start 92.994903 114.418388) (end 92.987507 114.397252) (width 0.109) (layer "In4.Cu") (net 123))
  (segment (start 96.15332 115.362263) (end 96.158751 115.338467) (width 0.109) (layer "In4.Cu") (net 123))
  (segment (start 95.466977 115.051708) (end 95.444986 115.041118) (width 0.109) (layer "In4.Cu") (net 123))
  (segment (start 93.639 114.375) (end 93.636492 114.397252) (width 0.109) (layer "In4.Cu") (net 123))
  (segment (start 95.515181 115.057139) (end 95.490773 115.057139) (width 0.109) (layer "In4.Cu") (net 123))
  (segment (start 92.987507 114.397252) (end 92.982492 114.352747) (width 0.109) (layer "In4.Cu") (net 123))
  (segment (start 94.236388 114.084904) (end 94.236344 114.084888) (width 0.109) (layer "In4.Cu") (net 123))
  (segment (start 93.193096 114.418388) (end 93.181183 114.437348) (width 0.109) (layer "In4.Cu") (net 123))
  (segment (start 92.740342 114.275) (end 92.269342 113.804) (width 0.109) (layer "In4.Cu") (net 123))
  (segment (start 95.819212 114.94089) (end 95.800128 114.925671) (width 0.109) (layer "In4.Cu") (net 123))
  (segment (start 96.038232 115.217948) (end 96.014435 115.223379) (width 0.109) (layer "In4.Cu") (net 123))
  (segment (start 93.617183 114.437348) (end 93.601348 114.453183) (width 0.109) (layer "In4.Cu") (net 123))
  (segment (start 94.236344 114.084888) (end 94.215252 114.077508) (width 0.109) (layer "In4.Cu") (net 123))
  (segment (start 94.096816 114.112652) (end 94.084903 114.131612) (width 0.109) (layer "In4.Cu") (net 123))
  (segment (start 94.112651 114.096817) (end 94.096816 114.112652) (width 0.109) (layer "In4.Cu") (net 123))
  (segment (start 93.641507 114.152748) (end 93.639 114.175) (width 0.109) (layer "In4.Cu") (net 123))
  (segment (start 95.657128 115.257124) (end 95.819212 115.095039) (width 0.109) (layer "In4.Cu") (net 123))
  (segment (start 95.425902 115.025899) (end 94.675004 114.275) (width 0.109) (layer "In4.Cu") (net 123))
  (segment (start 96.014435 115.223379) (end 95.992444 115.233969) (width 0.109) (layer "In4.Cu") (net 123))
  (segment (start 93.477611 114.465096) (end 93.458651 114.453183) (width 0.109) (layer "In4.Cu") (net 123))
  (segment (start 93.847096 114.131612) (end 93.835183 114.112652) (width 0.109) (layer "In4.Cu") (net 123))
  (segment (start 93.364388 114.084904) (end 93.343252 114.077508) (width 0.109) (layer "In4.Cu") (net 123))
  (segment (start 93.458651 114.453183) (end 93.442816 114.437348) (width 0.109) (layer "In4.Cu") (net 123))
  (segment (start 95.850452 115.00576) (end 95.845021 114.981964) (width 0.109) (layer "In4.Cu") (net 123))
  (segment (start 93.819348 114.096817) (end 93.800388 114.084904) (width 0.109) (layer "In4.Cu") (net 123))
  (segment (start 94.290492 114.152748) (end 94.283096 114.131612) (width 0.109) (layer "In4.Cu") (net 123))
  (segment (start 93.430903 114.418388) (end 93.423507 114.397252) (width 0.109) (layer "In4.Cu") (net 123))
  (segment (start 95.657126 115.257122) (end 95.657128 115.257124) (width 0.109) (layer "In4.Cu") (net 123))
  (segment (start 93.418492 114.152748) (end 93.411096 114.131612) (width 0.109) (layer "In4.Cu") (net 123))
  (segment (start 93.660816 114.112652) (end 93.648903 114.131612) (width 0.109) (layer "In4.Cu") (net 123))
  (segment (start 94.215252 114.077508) (end 94.193 114.075) (width 0.109) (layer "In4.Cu") (net 123))
  (segment (start 93.146388 114.465096) (end 93.125252 114.472492) (width 0.109) (layer "In4.Cu") (net 123))
  (segment (start 95.719904 115.502647) (end 95.700821 115.517866) (width 0.109) (layer "In4.Cu") (net 123))
  (segment (start 93.421 114.175) (end 93.418492 114.152748) (width 0.109) (layer "In4.Cu") (net 123))
  (segment (start 94.255348 114.096817) (end 94.236388 114.084904) (width 0.109) (layer "In4.Cu") (net 123))
  (segment (start 96.027283 115.507431) (end 96.042502 115.488348) (width 0.109) (layer "In4.Cu") (net 123))
  (segment (start 93.085 114.475) (end 93.062747 114.472492) (width 0.109) (layer "In4.Cu") (net 123))
  (segment (start 95.678829 115.528455) (end 95.655032 115.533886) (width 0.109) (layer "In4.Cu") (net 123))
  (segment (start 95.850452 115.030169) (end 95.850452 115.00576) (width 0.109) (layer "In4.Cu") (net 123))
  (segment (start 94.295507 114.197253) (end 94.290492 114.152748) (width 0.109) (layer "In4.Cu") (net 123))
  (segment (start 93.9 83.7) (end 93.9 82.5625) (width 0.182) (layer "B.Cu") (net 124))
  (segment (start 93.8 83.8) (end 93.9 83.7) (width 0.182) (layer "B.Cu") (net 124))
  (segment (start 93.8 84.655) (end 93.8 83.8) (width 0.182) (layer "B.Cu") (net 124))
  (via (at 90.225 75.325) (size 0.45) (drill 0.1) (layers "F.Cu" "B.Cu") (net 125))
  (via (at 94.5 83.7) (size 0.45) (drill 0.1) (layers "F.Cu" "B.Cu") (net 125))
  (via (at 93.400002 83.63) (size 0.45) (drill 0.1) (layers "F.Cu" "B.Cu") (net 125))
  (segment (start 93.4 83.7) (end 93.4 83.630002) (width 0.109) (layer "In2.Cu") (net 125))
  (segment (start 90.215557 76.401723) (end 93.400002 79.586168) (width 0.109) (layer "In2.Cu") (net 125))
  (segment (start 93.400002 83.63) (end 93.400002 79.586168) (width 0.109) (layer "In2.Cu") (net 125))
  (segment (start 90.223277 75.326723) (end 90.225 75.325) (width 0.109) (layer "In2.Cu") (net 125))
  (segment (start 94.5 83.7) (end 93.4 83.7) (width 0.109) (layer "In2.Cu") (net 125))
  (segment (start 93.4 83.630002) (end 93.400002 83.63) (width 0.109) (layer "In2.Cu") (net 125))
  (segment (start 90.215557 75.326723) (end 90.215557 76.401723) (width 0.109) (layer "In2.Cu") (net 125))
  (segment (start 90.215557 75.326723) (end 90.223277 75.326723) (width 0.109) (layer "In2.Cu") (net 125))
  (segment (start 93.4 84.655) (end 93.4 83.7) (width 0.182) (layer "B.Cu") (net 125))
  (segment (start 94.55 83.65) (end 94.5 83.7) (width 0.182) (layer "B.Cu") (net 125))
  (segment (start 93.4 83.7) (end 93.4 83.630002) (width 0.182) (layer "B.Cu") (net 125))
  (segment (start 90.65 75.761166) (end 90.215557 75.326723) (width 0.182) (layer "B.Cu") (net 125))
  (segment (start 90.65 76.8375) (end 90.65 75.761166) (width 0.182) (layer "B.Cu") (net 125))
  (segment (start 94.55 82.5625) (end 94.55 83.65) (width 0.182) (layer "B.Cu") (net 125))
  (segment (start 93.4 83.630002) (end 93.400002 83.63) (width 0.182) (layer "B.Cu") (net 125))
  (segment (start 92.6 83.6) (end 92.6 82.5625) (width 0.182) (layer "B.Cu") (net 126))
  (segment (start 93 84.655) (end 93 84) (width 0.182) (layer "B.Cu") (net 126))
  (segment (start 93 84) (end 92.6 83.6) (width 0.182) (layer "B.Cu") (net 126))
  (segment (start 106.505 140.8) (end 105.825 140.8) (width 0.182) (layer "F.Cu") (net 127))
  (segment (start 105.825 140.8) (end 105.625 141) (width 0.182) (layer "F.Cu") (net 127))
  (segment (start 94.49 114.99) (end 94.49 115.714991) (width 0.182) (layer "F.Cu") (net 127))
  (segment (start 93.629 114.129) (end 94.49 114.99) (width 0.182) (layer "F.Cu") (net 127))
  (segment (start 93.3265 114.129) (end 93.629 114.129) (width 0.182) (layer "F.Cu") (net 127))
  (via (at 105.625 141) (size 0.45) (drill 0.1) (layers "F.Cu" "B.Cu") (net 127))
  (via (at 94.49 115.714991) (size 0.45) (drill 0.1) (layers "F.Cu" "B.Cu") (net 127))
  (segment (start 94.714999 115.93999) (end 94.49 115.714991) (width 0.109) (layer "In2.Cu") (net 127))
  (segment (start 94.714999 119.314999) (end 94.714999 115.93999) (width 0.109) (layer "In2.Cu") (net 127))
  (segment (start 107.05 138.2) (end 106.750989 138.499011) (width 0.109) (layer "In2.Cu") (net 127))
  (segment (start 106.750989 138.499011) (end 106.750989 140.249011) (width 0.109) (layer "In2.Cu") (net 127))
  (segment (start 106.750989 140.249011) (end 106 141) (width 0.109) (layer "In2.Cu") (net 127))
  (segment (start 99.8 129.4) (end 104.63 129.4) (width 0.109) (layer "In2.Cu") (net 127))
  (segment (start 95.451978 120.051978) (end 94.714999 119.314999) (width 0.109) (layer "In2.Cu") (net 127))
  (segment (start 95.451978 123.551978) (end 95.451978 120.051978) (width 0.109) (layer "In2.Cu") (net 127))
  (segment (start 104.63 129.4) (end 107.8 132.57) (width 0.109) (layer "In2.Cu") (net 127))
  (segment (start 107.05 137.8) (end 107.05 138.2) (width 0.109) (layer "In2.Cu") (net 127))
  (segment (start 98.325 127.925) (end 98.325 126.425) (width 0.109) (layer "In2.Cu") (net 127))
  (segment (start 106.932161 135.142839) (end 106.932161 137.682161) (width 0.109) (layer "In2.Cu") (net 127))
  (segment (start 99.8 129.4) (end 98.325 127.925) (width 0.109) (layer "In2.Cu") (net 127))
  (segment (start 106 141) (end 105.625 141) (width 0.109) (layer "In2.Cu") (net 127))
  (segment (start 98.325 126.425) (end 95.451978 123.551978) (width 0.109) (layer "In2.Cu") (net 127))
  (segment (start 107.8 134.275) (end 106.932161 135.142839) (width 0.109) (layer "In2.Cu") (net 127))
  (segment (start 107.8 132.57) (end 107.8 134.275) (width 0.109) (layer "In2.Cu") (net 127))
  (segment (start 106.932161 137.682161) (end 107.05 137.8) (width 0.109) (layer "In2.Cu") (net 127))
  (segment (start 91.9815 116.979) (end 92.3665 116.669) (width 0.182) (layer "F.Cu") (net 128))
  (segment (start 107.15 139.23) (end 106.890348 138.970348) (width 0.109) (layer "F.Cu") (net 128))
  (segment (start 107.15 139.755) (end 107.15 139.23) (width 0.109) (layer "F.Cu") (net 128))
  (segment (start 106.890348 138.970348) (end 106.371479 138.970348) (width 0.109) (layer "F.Cu") (net 128))
  (via (at 106.371479 138.970348) (size 0.45) (drill 0.1) (layers "F.Cu" "B.Cu") (net 128))
  (via (at 91.9815 116.979) (size 0.45) (drill 0.1) (layers "F.Cu" "B.Cu") (net 128))
  (segment (start 107.36 133.71) (end 106.039621 135.030379) (width 0.109) (layer "In2.Cu") (net 128))
  (segment (start 95.22297 121.37703) (end 95.22297 124.22297) (width 0.109) (layer "In2.Cu") (net 128))
  (segment (start 106.039621 135.030379) (end 106.039621 138.63849) (width 0.109) (layer "In2.Cu") (net 128))
  (segment (start 97.6 128.6) (end 99.4 130.4) (width 0.109) (layer "In2.Cu") (net 128))
  (segment (start 104.77 130.4) (end 107.36 132.99) (width 0.109) (layer "In2.Cu") (net 128))
  (segment (start 99.4 130.4) (end 104.77 130.4) (width 0.109) (layer "In2.Cu") (net 128))
  (segment (start 93.98099 118.13099) (end 94.475 118.625) (width 0.109) (layer "In2.Cu") (net 128))
  (segment (start 107.36 132.99) (end 107.36 133.71) (width 0.109) (layer "In2.Cu") (net 128))
  (segment (start 106.039621 138.63849) (end 106.371479 138.970348) (width 0.109) (layer "In2.Cu") (net 128))
  (segment (start 92.4 117.94) (end 92.59099 118.13099) (width 0.109) (layer "In2.Cu") (net 128))
  (segment (start 94.475 118.625) (end 94.475 119.475) (width 0.109) (layer "In2.Cu") (net 128))
  (segment (start 95 120) (end 95 121.15406) (width 0.109) (layer "In2.Cu") (net 128))
  (segment (start 97.6 126.6) (end 97.6 128.6) (width 0.109) (layer "In2.Cu") (net 128))
  (segment (start 95 121.15406) (end 95.22297 121.37703) (width 0.109) (layer "In2.Cu") (net 128))
  (segment (start 92.59099 118.13099) (end 93.98099 118.13099) (width 0.109) (layer "In2.Cu") (net 128))
  (segment (start 92.4 117.3975) (end 92.4 117.94) (width 0.109) (layer "In2.Cu") (net 128))
  (segment (start 95.22297 124.22297) (end 97.6 126.6) (width 0.109) (layer "In2.Cu") (net 128))
  (segment (start 94.475 119.475) (end 95 120) (width 0.109) (layer "In2.Cu") (net 128))
  (segment (start 91.9815 116.979) (end 92.4 117.3975) (width 0.109) (layer "In2.Cu") (net 128))
  (segment (start 95.515 143.615) (end 95.475001 143.575) (width 0.182) (layer "F.Cu") (net 129))
  (segment (start 95.514999 144.525) (end 95.515 143.615) (width 0.182) (layer "F.Cu") (net 129))
  (segment (start 94.915 145.845) (end 94.575 145.845) (width 0.182) (layer "F.Cu") (net 129))
  (segment (start 89.8265 125.559) (end 90.3 125.245) (width 0.182) (layer "F.Cu") (net 129))
  (segment (start 95.514999 145.245001) (end 94.915 145.845) (width 0.182) (layer "F.Cu") (net 129))
  (segment (start 95.514999 144.525) (end 95.514999 145.245001) (width 0.182) (layer "F.Cu") (net 129))
  (via (at 95.475001 143.575) (size 0.45) (drill 0.1) (layers "F.Cu" "B.Cu") (net 129))
  (via (at 94.575 145.845) (size 0.45) (drill 0.1) (layers "F.Cu" "B.Cu") (net 129))
  (via (at 90.3 125.245) (size 0.45) (drill 0.1) (layers "F.Cu" "B.Cu") (net 129))
  (segment (start 94.2 141.3) (end 94.2 133.7) (width 0.109) (layer "In2.Cu") (net 129))
  (segment (start 94.2 126.2) (end 93.9 125.9) (width 0.109) (layer "In2.Cu") (net 129))
  (segment (start 93.7 129.4) (end 94.2 128.9) (width 0.109) (layer "In2.Cu") (net 129))
  (segment (start 93.9 125.9) (end 90.955 125.9) (width 0.109) (layer "In2.Cu") (net 129))
  (segment (start 95.475001 143.575) (end 95.475001 142.575001) (width 0.109) (layer "In2.Cu") (net 129))
  (segment (start 94.2 133.7) (end 93.7 133.2) (width 0.109) (layer "In2.Cu") (net 129))
  (segment (start 95.475001 142.575001) (end 94.2 141.3) (width 0.109) (layer "In2.Cu") (net 129))
  (segment (start 90.955 125.9) (end 90.3 125.245) (width 0.109) (layer "In2.Cu") (net 129))
  (segment (start 93.7 133.2) (end 93.7 129.4) (width 0.109) (layer "In2.Cu") (net 129))
  (segment (start 94.2 128.9) (end 94.2 126.2) (width 0.109) (layer "In2.Cu") (net 129))
  (segment (start 94.575 145.845) (end 94.575 146.475) (width 0.182) (layer "B.Cu") (net 129))
  (segment (start 106.505 140.4) (end 105.625 140.4) (width 0.182) (layer "F.Cu") (net 130))
  (segment (start 105.8 140) (end 105.625 139.825) (width 0.182) (layer "F.Cu") (net 130))
  (segment (start 106.505 140) (end 105.8 140) (width 0.182) (layer "F.Cu") (net 130))
  (segment (start 89.4415 116.979) (end 89.8265 116.669) (width 0.182) (layer "F.Cu") (net 130))
  (via (at 105.625 139.825) (size 0.45) (drill 0.1) (layers "F.Cu" "B.Cu") (net 130))
  (via (at 105.625 140.4) (size 0.45) (drill 0.1) (layers "F.Cu" "B.Cu") (net 130))
  (via (at 89.4415 116.979) (size 0.45) (drill 0.1) (layers "F.Cu" "B.Cu") (net 130))
  (segment (start 94.175 119.775) (end 94.175 118.775) (width 0.109) (layer "In2.Cu") (net 130))
  (segment (start 94.175 118.775) (end 93.75 118.35) (width 0.109) (layer "In2.Cu") (net 130))
  (segment (start 94.7 120.3) (end 94.175 119.775) (width 0.109) (layer "In2.Cu") (net 130))
  (segment (start 95 121.5) (end 94.7 121.2) (width 0.109) (layer "In2.Cu") (net 130))
  (segment (start 89.25 118.35) (end 88.9 118) (width 0.109) (layer "In2.Cu") (net 130))
  (segment (start 99 131.6) (end 96.8 129.4) (width 0.109) (layer "In2.Cu") (net 130))
  (segment (start 95 124.8) (end 95 121.5) (width 0.109) (layer "In2.Cu") (net 130))
  (segment (start 93.75 118.35) (end 89.25 118.35) (width 0.109) (layer "In2.Cu") (net 130))
  (segment (start 105.625 140.4) (end 105.625 139.825) (width 0.109) (layer "In2.Cu") (net 130))
  (segment (start 94.7 121.2) (end 94.7 120.3) (width 0.109) (layer "In2.Cu") (net 130))
  (segment (start 96.8 129.4) (end 96.8 126.6) (width 0.109) (layer "In2.Cu") (net 130))
  (segment (start 105.27 131.6) (end 99 131.6) (width 0.109) (layer "In2.Cu") (net 130))
  (segment (start 105.954501 132.284501) (end 105.27 131.6) (width 0.109) (layer "In2.Cu") (net 130))
  (segment (start 105.954501 132.682161) (end 105.954501 132.284501) (width 0.109) (layer "In2.Cu") (net 130))
  (segment (start 105.625 139.825) (end 105.625 133.011662) (width 0.109) (layer "In2.Cu") (net 130))
  (segment (start 88.9 117.5205) (end 89.4415 116.979) (width 0.109) (layer "In2.Cu") (net 130))
  (segment (start 96.8 126.6) (end 95 124.8) (width 0.109) (layer "In2.Cu") (net 130))
  (segment (start 105.625 133.011662) (end 105.954501 132.682161) (width 0.109) (layer "In2.Cu") (net 130))
  (segment (start 88.9 118) (end 88.9 117.5205) (width 0.109) (layer "In2.Cu") (net 130))
  (segment (start 123.165 147.02) (end 123.15 147.035) (width 0.182) (layer "B.Cu") (net 131))
  (segment (start 125.05 147.035) (end 124.115 147.035) (width 0.182) (layer "B.Cu") (net 131))
  (segment (start 123.15 147.035) (end 122.25 147.035) (width 0.182) (layer "B.Cu") (net 131))
  (segment (start 124.115 147.035) (end 124.1 147.02) (width 0.182) (layer "B.Cu") (net 131))
  (segment (start 125.05 147.035) (end 126.365 147.035) (width 0.4) (layer "B.Cu") (net 131))
  (segment (start 124.1 147.02) (end 123.165 147.02) (width 0.182) (layer "B.Cu") (net 131))
  (segment (start 150.551832 122.861783) (end 150.551832 122.765723) (width 0.182) (layer "F.Cu") (net 132))
  (segment (start 143.581796 117.898) (end 143.567786 117.88399) (width 0.182) (layer "F.Cu") (net 132))
  (segment (start 152.85 118.2492) (end 153.2 118.5992) (width 0.2) (layer "F.Cu") (net 132))
  (segment (start 144.361 117.898) (end 143.581796 117.898) (width 0.182) (layer "F.Cu") (net 132))
  (segment (start 150.253 122.466891) (end 150.253 122.156) (width 0.182) (layer "F.Cu") (net 132))
  (segment (start 145.86 114.425) (end 145.86 113.865) (width 0.182) (layer "F.Cu") (net 132))
  (segment (start 147.600495 122.851317) (end 147.853 122.598812) (width 0.182) (layer "F.Cu") (net 132))
  (segment (start 152.85 117.9) (end 152.85 118.2492) (width 0.2) (layer "F.Cu") (net 132))
  (segment (start 152.135 117.9) (end 152.85 117.9) (width 0.182) (layer "F.Cu") (net 132))
  (segment (start 147.853 122.598812) (end 147.853 122.156) (width 0.182) (layer "F.Cu") (net 132))
  (segment (start 150.551832 122.765723) (end 150.253 122.466891) (width 0.182) (layer "F.Cu") (net 132))
  (segment (start 145.86 113.865) (end 145.715 113.72) (width 0.182) (layer "F.Cu") (net 132))
  (via (at 147.600495 122.851317) (size 0.45) (drill 0.1) (layers "F.Cu" "B.Cu") (net 132))
  (via (at 145.964901 122.862089) (size 0.45) (drill 0.1) (layers "F.Cu" "B.Cu") (net 132))
  (via (at 150.551832 122.861783) (size 0.45) (drill 0.1) (layers "F.Cu" "B.Cu") (net 132))
  (via (at 145.715 113.72) (size 0.45) (drill 0.1) (layers "F.Cu" "B.Cu") (net 132))
  (via (at 152.85 117.9) (size 0.45) (drill 0.1) (layers "F.Cu" "B.Cu") (net 132))
  (via (at 143.567786 117.88399) (size 0.45) (drill 0.1) (layers "F.Cu" "B.Cu") (net 132))
  (segment (start 144.375 117.88) (end 144.395 117.86) (width 0.182) (layer "B.Cu") (net 132))
  (segment (start 147.580001 122.830823) (end 147.580001 122.145) (width 0.4) (layer "B.Cu") (net 132))
  (segment (start 145.95 122.135) (end 145.95 122.847188) (width 0.4) (layer "B.Cu") (net 132))
  (segment (start 150.551832 122.166832) (end 150.505 122.12) (width 0.4) (layer "B.Cu") (net 132))
  (segment (start 152.065 117.86) (end 152.81 117.86) (width 0.4) (layer "B.Cu") (net 132))
  (segment (start 147.600495 122.851317) (end 147.580001 122.830823) (width 0.4) (layer "B.Cu") (net 132))
  (segment (start 145.83 113.835) (end 145.715 113.72) (width 0.182) (layer "B.Cu") (net 132))
  (segment (start 144.375 117.88) (end 143.571776 117.88) (width 0.4) (layer "B.Cu") (net 132))
  (segment (start 145.83 114.45) (end 145.83 113.835) (width 0.182) (layer "B.Cu") (net 132))
  (segment (start 150.551832 122.861783) (end 150.551832 122.166832) (width 0.4) (layer "B.Cu") (net 132))
  (segment (start 145.95 122.847188) (end 145.964901 122.862089) (width 0.4) (layer "B.Cu") (net 132))
  (segment (start 152.81 117.86) (end 152.85 117.9) (width 0.4) (layer "B.Cu") (net 132))
  (segment (start 143.571776 117.88) (end 143.567786 117.88399) (width 0.4) (layer "B.Cu") (net 132))
  (segment (start 147.625 113.45001) (end 147.780295 113.294715) (width 0.182) (layer "F.Cu") (net 133))
  (segment (start 145.2504 111.5996) (end 144.3 110.6492) (width 0.2) (layer "F.Cu") (net 133))
  (segment (start 145.685 111.785) (end 145.685 112.3) (width 0.2) (layer "F.Cu") (net 133))
  (segment (start 146.653 113.685421) (end 146.601979 113.6344) (width 0.182) (layer "F.Cu") (net 133))
  (segment (start 147.86 114.425) (end 147.86 114.06) (width 0.182) (layer "F.Cu") (net 133))
  (segment (start 146.653 114.406) (end 146.653 113.685421) (width 0.182) (layer "F.Cu") (net 133))
  (segment (start 147.86 114.06) (end 147.625 113.825) (width 0.182) (layer "F.Cu") (net 133))
  (segment (start 146.601979 113.216979) (end 146.601979 113.6344) (width 0.182) (layer "F.Cu") (net 133))
  (segment (start 145.2504 111.5996) (end 145.4996 111.5996) (width 0.2) (layer "F.Cu") (net 133))
  (segment (start 145.685 112.3) (end 146.601979 113.216979) (width 0.182) (layer "F.Cu") (net 133))
  (segment (start 145.4996 111.5996) (end 145.685 111.785) (width 0.2) (layer "F.Cu") (net 133))
  (segment (start 147.625 113.825) (end 147.625 113.45001) (width 0.182) (layer "F.Cu") (net 133))
  (via (at 146.601979 113.6344) (size 0.45) (drill 0.1) (layers "F.Cu" "B.Cu") (net 133))
  (via (at 147.780295 113.294715) (size 0.45) (drill 0.1) (layers "F.Cu" "B.Cu") (net 133))
  (segment (start 147.467505 114.157505) (end 147.17501 114.45) (width 0.4) (layer "B.Cu") (net 133))
  (segment (start 146.73 113.762421) (end 146.601979 113.6344) (width 0.4) (layer "B.Cu") (net 133))
  (segment (start 147.467505 113.607505) (end 147.467505 114.157505) (width 0.4) (layer "B.Cu") (net 133))
  (segment (start 147.17501 114.45) (end 146.73 114.45) (width 0.4) (layer "B.Cu") (net 133))
  (segment (start 146.73 114.45) (end 146.73 113.762421) (width 0.4) (layer "B.Cu") (net 133))
  (segment (start 147.467505 113.607505) (end 147.780295 113.294715) (width 0.4) (layer "B.Cu") (net 133))
  (segment (start 153.35 122.7) (end 153.35 123.3992) (width 0.2) (layer "F.Cu") (net 134))
  (segment (start 153.35 123.3992) (end 153.3 123.4492) (width 0.2) (layer "F.Cu") (net 134))
  (segment (start 149.975 122.745) (end 149.853 122.623) (width 0.182) (layer "F.Cu") (net 134))
  (segment (start 149.985004 123.4) (end 149.975 123.389996) (width 0.182) (layer "F.Cu") (net 134))
  (segment (start 149.975 123.389996) (end 149.975 122.745) (width 0.182) (layer "F.Cu") (net 134))
  (segment (start 150.665 123.4) (end 149.985004 123.4) (width 0.182) (layer "F.Cu") (net 134))
  (segment (start 149.853 122.623) (end 149.853 122.156) (width 0.182) (layer "F.Cu") (net 134))
  (segment (start 153.35 122.7) (end 153.35 123.45) (width 0.2) (layer "F.Cu") (net 134))
  (via (at 153.35 122.7) (size 0.45) (drill 0.1) (layers "F.Cu" "B.Cu") (net 134))
  (via (at 149.975 123.389996) (size 0.45) (drill 0.1) (layers "F.Cu" "B.Cu") (net 134))
  (segment (start 149.605 122.267537) (end 150.02 122.682537) (width 0.4) (layer "B.Cu") (net 134))
  (segment (start 150.02 122.682537) (end 150.02 123.344996) (width 0.4) (layer "B.Cu") (net 134))
  (segment (start 151.560004 123.389996) (end 152.25 122.7) (width 0.2) (layer "B.Cu") (net 134))
  (segment (start 149.605 122.12) (end 149.605 122.267537) (width 0.4) (layer "B.Cu") (net 134))
  (segment (start 150.02 123.344996) (end 149.975 123.389996) (width 0.4) (layer "B.Cu") (net 134))
  (segment (start 149.975 123.389996) (end 151.560004 123.389996) (width 0.2) (layer "B.Cu") (net 134))
  (segment (start 152.25 122.7) (end 153.35 122.7) (width 0.2) (layer "B.Cu") (net 134))
  (segment (start 149.609433 113.344433) (end 149.465 113.2) (width 0.182) (layer "F.Cu") (net 135))
  (segment (start 149.45 113.185) (end 149.515 113.185) (width 0.2) (layer "F.Cu") (net 135))
  (segment (start 149.465 113.2) (end 149.45 113.2) (width 0.182) (layer "F.Cu") (net 135))
  (segment (start 149.609433 113.801815) (end 149.453 113.958248) (width 0.182) (layer "F.Cu") (net 135))
  (segment (start 150.8508 112.75) (end 151.5 113.3992) (width 0.2) (layer "F.Cu") (net 135))
  (segment (start 149.609433 113.801815) (end 149.609433 113.344433) (width 0.182) (layer "F.Cu") (net 135))
  (segment (start 149.515 113.185) (end 149.95 112.75) (width 0.2) (layer "F.Cu") (net 135))
  (segment (start 149.453 113.958248) (end 149.453 114.406) (width 0.182) (layer "F.Cu") (net 135))
  (segment (start 149.95 112.75) (end 150.8508 112.75) (width 0.2) (layer "F.Cu") (net 135))
  (via (at 149.609433 113.801815) (size 0.45) (drill 0.1) (layers "F.Cu" "B.Cu") (net 135))
  (segment (start 149.479999 113.931249) (end 149.479999 114.46) (width 0.4) (layer "B.Cu") (net 135))
  (segment (start 149.609433 113.801815) (end 149.479999 113.931249) (width 0.4) (layer "B.Cu") (net 135))
  (segment (start 143.7 108.575) (end 143.7 108.625) (width 0.2) (layer "F.Cu") (net 136))
  (segment (start 144.1 109.575) (end 145.015 109.575) (width 0.2) (layer "F.Cu") (net 136))
  (segment (start 145.92 110.5292) (end 145.55 110.8992) (width 0.182) (layer "F.Cu") (net 136))
  (segment (start 145.92 110.48) (end 145.92 110.5292) (width 0.182) (layer "F.Cu") (net 136))
  (segment (start 146.4 110.96) (end 146.4 112.505) (width 0.182) (layer "F.Cu") (net 136))
  (segment (start 145.015 109.575) (end 145.92 110.48) (width 0.182) (layer "F.Cu") (net 136))
  (segment (start 143.7 108.625) (end 144.1 109.025) (width 0.2) (layer "F.Cu") (net 136))
  (segment (start 147.06 114.085) (end 147.017989 114.042989) (width 0.182) (layer "F.Cu") (net 136))
  (segment (start 147.017989 113.122989) (end 147.017989 114.042989) (width 0.182) (layer "F.Cu") (net 136))
  (segment (start 144.1 109.025) (end 144.1 109.575) (width 0.2) (layer "F.Cu") (net 136))
  (segment (start 147.06 114.425) (end 147.06 114.085) (width 0.182) (layer "F.Cu") (net 136))
  (segment (start 145.92 110.48) (end 146.4 110.96) (width 0.182) (layer "F.Cu") (net 136))
  (segment (start 146.4 112.505) (end 147.017989 113.122989) (width 0.182) (layer "F.Cu") (net 136))
  (segment (start 147.87 124.39) (end 147.87 125.375) (width 0.182) (layer "F.Cu") (net 137))
  (segment (start 148.653 123.607) (end 147.87 124.39) (width 0.182) (layer "F.Cu") (net 137))
  (segment (start 147.87 125.387767) (end 149.11906 126.636827) (width 0.182) (layer "F.Cu") (net 137))
  (segment (start 147.87 125.375) (end 147.87 125.387767) (width 0.182) (layer "F.Cu") (net 137))
  (segment (start 148.653 122.156) (end 148.653 123.607) (width 0.182) (layer "F.Cu") (net 137))
  (segment (start 143.0827 114.090097) (end 143.089771 114.097168) (width 0.182) (layer "F.Cu") (net 138))
  (segment (start 143.089771 114.097168) (end 143.089771 114.715254) (width 0.182) (layer "F.Cu") (net 138))
  (segment (start 139.05176 113.329792) (end 139.045155 113.336396) (width 0.182) (layer "F.Cu") (net 138))
  (segment (start 139.045155 113.336396) (end 138.246089 113.336396) (width 0.182) (layer "F.Cu") (net 138))
  (segment (start 142.06341 128.118647) (end 142.077552 128.104505) (width 0.182) (layer "F.Cu") (net 138))
  (segment (start 142.077552 128.104505) (end 142.653212 128.104505) (width 0.182) (layer "F.Cu") (net 138))
  (segment (start 140.47 117.525) (end 141.025 117.525) (width 0.2) (layer "F.Cu") (net 138))
  (segment (start 141.025 117.525) (end 141.4 117.9) (width 0.2) (layer "F.Cu") (net 138))
  (segment (start 139.825 117.77) (end 139.825 118.425) (width 0.2) (layer "F.Cu") (net 138))
  (segment (start 152.135 115.1) (end 152.7 115.1) (width 0.182) (layer "F.Cu") (net 138))
  (segment (start 139.425 118.675001) (end 139.675 118.925) (width 0.182) (layer "F.Cu") (net 138))
  (segment (start 139.425 117.77) (end 139.425 118.675001) (width 0.182) (layer "F.Cu") (net 138))
  (segment (start 139.825 118.425) (end 140.3 118.9) (width 0.2) (layer "F.Cu") (net 138))
  (segment (start 139.726787 125.824767) (end 139.049767 125.824767) (width 0.182) (layer "F.Cu") (net 138))
  (segment (start 151.25 111.975) (end 150.744499 111.975) (width 0.3) (layer "F.Cu") (net 138))
  (segment (start 139.625 122.913327) (end 139.913137 123.201464) (width 0.182) (layer "F.Cu") (net 138))
  (segment (start 142.904916 125.812314) (end 142.487314 125.812314) (width 0.182) (layer "F.Cu") (net 138))
  (segment (start 152.400016 123.45) (end 152.450016 123.5) (width 0.4) (layer "F.Cu") (net 138))
  (segment (start 149.45 112.215) (end 149.46 112.215) (width 0.182) (layer "F.Cu") (net 138))
  (segment (start 139.971787 124.571787) (end 139.971787 124.546787) (width 0.182) (layer "F.Cu") (net 138))
  (segment (start 139.049767 125.824767) (end 138.75 125.525) (width 0.182) (layer "F.Cu") (net 138))
  (segment (start 150.744499 111.975) (end 150.719499 112) (width 0.182) (layer "F.Cu") (net 138))
  (segment (start 141.426087 126.539478) (end 141.744285 126.539478) (width 0.182) (layer "F.Cu") (net 138))
  (segment (start 142.34 120.93499) (end 142.32499 120.95) (width 0.182) (layer "F.Cu") (net 138))
  (segment (start 138.624974 128.875026) (end 138.6 128.9) (width 0.182) (layer "F.Cu") (net 138))
  (segment (start 152.147 119.9) (end 152.7 119.9) (width 0.182) (layer "F.Cu") (net 138))
  (segment (start 141.331499 126.539478) (end 141.426087 126.539478) (width 0.182) (layer "F.Cu") (net 138))
  (segment (start 137.085 126.475) (end 137.525 126.475) (width 0.182) (layer "F.Cu") (net 138))
  (segment (start 140.401076 131.826076) (end 140.425 131.85) (width 0.182) (layer "F.Cu") (net 138))
  (segment (start 144.385 118.7) (end 143.603022 118.7) (width 0.182) (layer "F.Cu") (net 138))
  (segment (start 148.253 122.156) (end 148.253 122.75899) (width 0.182) (layer "F.Cu") (net 138))
  (segment (start 140.615 114.71) (end 140.975 115.07) (width 0.182) (layer "F.Cu") (net 138))
  (segment (start 142.34 120.26) (end 142.34 120.93499) (width 0.182) (layer "F.Cu") (net 138))
  (segment (start 142.325 125.65) (end 142.325 125.52461) (width 0.182) (layer "F.Cu") (net 138))
  (segment (start 144.732986 125.817014) (end 145.05 125.5) (width 0.182) (layer "F.Cu") (net 138))
  (segment (start 151.635 123.45) (end 152.400016 123.45) (width 0.4) (layer "F.Cu") (net 138))
  (segment (start 144.194916 125.812314) (end 144.199616 125.817014) (width 0.182) (layer "F.Cu") (net 138))
  (segment (start 149.45 110.6492) (end 149.45 111.075) (width 0.182) (layer "F.Cu") (net 138))
  (segment (start 139.625 122.045) (end 139.625 122.913327) (width 0.182) (layer "F.Cu") (net 138))
  (segment (start 141.016787 125.824767) (end 141.603787 125.824767) (width 0.182) (layer "F.Cu") (net 138))
  (segment (start 137.525 126.475) (end 137.7 126.3) (width 0.182) (layer "F.Cu") (net 138))
  (segment (start 138.624974 128.122183) (end 138.624974 128.875026) (width 0.182) (layer "F.Cu") (net 138))
  (segment (start 137.475 123.275) (end 137.8 123.6) (width 0.182) (layer "F.Cu") (net 138))
  (segment (start 152.7 119.9) (end 152.725 119.875) (width 0.182) (layer "F.Cu") (net 138))
  (segment (start 139.971787 124.546787) (end 139.775 124.35) (width 0.182) (layer "F.Cu") (net 138))
  (segment (start 148.253 122.75899) (end 148.23699 122.775) (width 0.182) (layer "F.Cu") (net 138))
  (segment (start 139.971787 125.179767) (end 139.971787 124.571787) (width 0.182) (layer "F.Cu") (net 138))
  (segment (start 141.016787 126.224766) (end 141.331499 126.539478) (width 0.182) (layer "F.Cu") (net 138))
  (segment (start 142.325 125.52461) (end 142.545277 125.304333) (width 0.182) (layer "F.Cu") (net 138))
  (segment (start 149.45 111.075) (end 149.825 111.45) (width 0.182) (layer "F.Cu") (net 138))
  (segment (start 140.401076 130.931873) (end 140.401076 131.826076) (width 0.182) (layer "F.Cu") (net 138))
  (segment (start 144.199616 125.817014) (end 144.732986 125.817014) (width 0.182) (layer "F.Cu") (net 138))
  (segment (start 149.825 111.85) (end 149.825 111.45) (width 0.182) (layer "F.Cu") (net 138))
  (segment (start 142.315 116.2) (end 142.315 116.615) (width 0.182) (layer "F.Cu") (net 138))
  (segment (start 140.491154 110.483846) (end 140.665 110.31) (width 0.2) (layer "F.Cu") (net 138))
  (segment (start 140.1 114.71) (end 140.615 114.71) (width 0.182) (layer "F.Cu") (net 138))
  (segment (start 137.7 126.3) (end 137.7 126.1) (width 0.182) (layer "F.Cu") (net 138))
  (segment (start 143.603022 118.7) (end 143.555 118.748022) (width 0.182) (layer "F.Cu") (net 138))
  (segment (start 141.603787 125.824767) (end 141.76289 125.665664) (width 0.182) (layer "F.Cu") (net 138))
  (segment (start 149.46 112.215) (end 149.825 111.85) (width 0.182) (layer "F.Cu") (net 138))
  (segment (start 137.085 123.275) (end 137.475 123.275) (width 0.182) (layer "F.Cu") (net 138))
  (segment (start 142.315 116.615) (end 142.525 116.825) (width 0.182) (layer "F.Cu") (net 138))
  (segment (start 141.76289 125.665664) (end 141.76289 125.562125) (width 0.182) (layer "F.Cu") (net 138))
  (segment (start 140.491154 110.843845) (end 140.491154 110.483846) (width 0.2) (layer "F.Cu") (net 138))
  (segment (start 142.487314 125.812314) (end 142.325 125.65) (width 0.182) (layer "F.Cu") (net 138))
  (via (at 140.491154 110.843845) (size 0.45) (drill 0.1) (layers "F.Cu" "B.Cu") (net 138))
  (via (at 143.089771 114.715254) (size 0.45) (drill 0.1) (layers "F.Cu" "B.Cu") (net 138))
  (via (at 138.246089 113.336396) (size 0.45) (drill 0.1) (layers "F.Cu" "B.Cu") (net 138))
  (via (at 142.545277 125.304333) (size 0.45) (drill 0.1) (layers "F.Cu" "B.Cu") (net 138))
  (via (at 142.653212 128.104505) (size 0.45) (drill 0.1) (layers "F.Cu" "B.Cu") (net 138))
  (via (at 152.7 115.1) (size 0.45) (drill 0.1) (layers "F.Cu" "B.Cu") (net 138))
  (via (at 140.3 118.9) (size 0.45) (drill 0.1) (layers "F.Cu" "B.Cu") (net 138))
  (via (at 142.525 116.825) (size 0.45) (drill 0.1) (layers "F.Cu" "B.Cu") (net 138))
  (via (at 152.725 119.875) (size 0.45) (drill 0.1) (layers "F.Cu" "B.Cu") (net 138))
  (via (at 139.675 118.925) (size 0.45) (drill 0.1) (layers "F.Cu" "B.Cu") (net 138))
  (via (at 141.4 117.9) (size 0.45) (drill 0.1) (layers "F.Cu" "B.Cu") (net 138))
  (via (at 145.05 125.5) (size 0.45) (drill 0.1) (layers "F.Cu" "B.Cu") (net 138))
  (via (at 142.32499 120.95) (size 0.45) (drill 0.1) (layers "F.Cu" "B.Cu") (net 138))
  (via (at 141.744285 126.539478) (size 0.45) (drill 0.1) (layers "F.Cu" "B.Cu") (net 138))
  (via (at 150.385 113.21) (size 0.45) (drill 0.1) (layers "F.Cu" "B.Cu") (net 138))
  (via (at 152.450016 123.5) (size 0.6) (drill 0.25) (layers "F.Cu" "B.Cu") (net 138))
  (via (at 149.825 111.45) (size 0.45) (drill 0.1) (layers "F.Cu" "B.Cu") (net 138))
  (via (at 150.719499 112) (size 0.45) (drill 0.1) (layers "F.Cu" "B.Cu") (net 138))
  (via (at 139.913137 123.201464) (size 0.45) (drill 0.1) (layers "F.Cu" "B.Cu") (net 138))
  (via (at 139.775 124.35) (size 0.45) (drill 0.1) (layers "F.Cu" "B.Cu") (net 138))
  (via (at 140.1 114.71) (size 0.45) (drill 0.1) (layers "F.Cu" "B.Cu") (net 138))
  (via (at 143.555 118.748022) (size 0.45) (drill 0.1) (layers "F.Cu" "B.Cu") (net 138))
  (via (at 137.8 123.6) (size 0.45) (drill 0.1) (layers "F.Cu" "B.Cu") (net 138))
  (via (at 138.75 125.525) (size 0.45) (drill 0.1) (layers "F.Cu" "B.Cu") (net 138))
  (via (at 140.425 131.85) (size 0.45) (drill 0.1) (layers "F.Cu" "B.Cu") (net 138))
  (via (at 150.719499 111.519499) (size 0.45) (drill 0.1) (layers "F.Cu" "B.Cu") (net 138))
  (via (at 148.23699 122.775) (size 0.45) (drill 0.1) (layers "F.Cu" "B.Cu") (net 138))
  (via (at 137.7 126.1) (size 0.45) (drill 0.1) (layers "F.Cu" "B.Cu") (net 138))
  (via (at 141.76289 125.562125) (size 0.45) (drill 0.1) (layers "F.Cu" "B.Cu") (net 138))
  (via (at 138.6 128.9) (size 0.45) (drill 0.1) (layers "F.Cu" "B.Cu") (net 138))
  (segment (start 138.246089 113.336396) (end 138.267303 113.357609) (width 0.4) (layer "B.Cu") (net 138))
  (segment (start 138.267303 113.357609) (end 138.885389 113.357609) (width 0.4) (layer "B.Cu") (net 138))
  (segment (start 140.471787 130.891138) (end 140.401076 130.961848) (width 0.182) (layer "B.Cu") (net 138))
  (segment (start 152.095 115.06) (end 152.135 115.1) (width 0.4) (layer "B.Cu") (net 138))
  (segment (start 152.71 119.86) (end 152.725 119.875) (width 0.4) (layer "B.Cu") (net 138))
  (segment (start 144.325 118.69) (end 144.395 118.76) (width 0.182) (layer "B.Cu") (net 138))
  (segment (start 139.675 118.925) (end 139.675 118.26) (width 0.4) (layer "B.Cu") (net 138))
  (segment (start 152.065 119.86) (end 152.71 119.86) (width 0.4) (layer "B.Cu") (net 138))
  (segment (start 152.065 115.06) (end 152.095 115.06) (width 0.4) (layer "B.Cu") (net 138))
  (segment (start 144.329687 125.484674) (end 145.032626 125.484674) (width 0.4) (layer "B.Cu") (net 138))
  (segment (start 152.135 115.1) (end 152.7 115.1) (width 0.4) (layer "B.Cu") (net 138))
  (segment (start 151.365 111.75) (end 150.75 111.75) (width 0.4) (layer "B.Cu") (net 138))
  (segment (start 140.401076 131.826076) (end 140.425 131.85) (width 0.4) (layer "B.Cu") (net 138))
  (segment (start 150.719499 111.519499) (end 150.719499 112) (width 0.4) (layer "B.Cu") (net 138))
  (segment (start 139.925 122.585) (end 139.925 123.189601) (width 0.4) (layer "B.Cu") (net 138))
  (segment (start 144.325 118.69) (end 143.613022 118.69) (width 0.4) (layer "B.Cu") (net 138))
  (segment (start 141.729574 126.524767) (end 141.744285 126.539478) (width 0.4) (layer "B.Cu") (net 138))
  (segment (start 150.395 113.2) (end 150.385 113.21) (width 0.4) (layer "B.Cu") (net 138))
  (segment (start 140.401076 130.961848) (end 140.401076 131.826076) (width 0.4) (layer "B.Cu") (net 138))
  (segment (start 143.613022 118.69) (end 143.555 118.748022) (width 0.4) (layer "B.Cu") (net 138))
  (segment (start 139.925 123.189601) (end 139.913137 123.201464) (width 0.4) (layer "B.Cu") (net 138))
  (segment (start 141.156788 126.524767) (end 141.729574 126.524767) (width 0.4) (layer "B.Cu") (net 138))
  (segment (start 141.15061 125.576598) (end 141.748417 125.576598) (width 0.4) (layer "B.Cu") (net 138))
  (segment (start 141.748417 125.576598) (end 141.76289 125.562125) (width 0.4) (layer "B.Cu") (net 138))
  (segment (start 148.48 122.53199) (end 148.23699 122.775) (width 0.4) (layer "B.Cu") (net 138))
  (segment (start 150.75 111.75) (end 150.719499 111.719499) (width 0.4) (layer "B.Cu") (net 138))
  (segment (start 148.48 122.145) (end 148.48 122.53199) (width 0.4) (layer "B.Cu") (net 138))
  (segment (start 151.2 113.2) (end 150.395 113.2) (width 0.4) (layer "B.Cu") (net 138))
  (segment (start 150.719499 111.719499) (end 150.719499 111.519499) (width 0.4) (layer "B.Cu") (net 138))
  (segment (start 149.06 123.355) (end 149.775 124.07) (width 0.182) (layer "F.Cu") (net 139))
  (segment (start 151.843148 124.506852) (end 152.734493 124.506852) (width 0.182) (layer "F.Cu") (net 139))
  (segment (start 151.513173 124.836827) (end 151.843148 124.506852) (width 0.182) (layer "F.Cu") (net 139))
  (segment (start 149.775 124.07) (end 150.561117 124.07) (width 0.182) (layer "F.Cu") (net 139))
  (segment (start 149.06 122.175) (end 149.06 123.355) (width 0.182) (layer "F.Cu") (net 139))
  (segment (start 151.41906 124.836827) (end 151.513173 124.836827) (width 0.182) (layer "F.Cu") (net 139))
  (segment (start 150.561117 124.07) (end 151.327944 124.836827) (width 0.182) (layer "F.Cu") (net 139))
  (segment (start 151.327944 124.836827) (end 151.41906 124.836827) (width 0.182) (layer "F.Cu") (net 139))
  (segment (start 141.151077 132.248923) (end 141.151077 130.931873) (width 0.182) (layer "F.Cu") (net 140))
  (segment (start 80.475 143.725) (end 80.475 139.575) (width 0.182) (layer "F.Cu") (net 140))
  (segment (start 84.65 137.55) (end 86 136.2) (width 0.182) (layer "F.Cu") (net 140))
  (segment (start 76.8 142.975) (end 78.125 144.3) (width 0.182) (layer "F.Cu") (net 140))
  (segment (start 82.5 137.55) (end 84.65 137.55) (width 0.182) (layer "F.Cu") (net 140))
  (segment (start 78.125 144.3) (end 79.9 144.3) (width 0.182) (layer "F.Cu") (net 140))
  (segment (start 86 128.69999) (end 87 127.69999) (width 0.182) (layer "F.Cu") (net 140))
  (segment (start 141.151077 132.248923) (end 140.9 132.5) (width 0.182) (layer "F.Cu") (net 140))
  (segment (start 140.9 132.5) (end 135.8 132.5) (width 0.182) (layer "F.Cu") (net 140))
  (segment (start 80.475 139.575) (end 82.5 137.55) (width 0.182) (layer "F.Cu") (net 140))
  (segment (start 90.7865 126.829) (end 91.1715 126.518999) (width 0.182) (layer "F.Cu") (net 140))
  (segment (start 79.9 144.3) (end 80.475 143.725) (width 0.182) (layer "F.Cu") (net 140))
  (segment (start 86 136.2) (end 86 128.69999) (width 0.182) (layer "F.Cu") (net 140))
  (via (at 135.8 132.5) (size 0.45) (drill 0.1) (layers "F.Cu" "B.Cu") (net 140))
  (via (at 91.1715 126.518999) (size 0.45) (drill 0.1) (layers "F.Cu" "B.Cu") (net 140))
  (via (at 87 127.69999) (size 0.45) (drill 0.1) (layers "F.Cu" "B.Cu") (net 140))
  (segment (start 126.725 135.2) (end 115.8 135.2) (width 0.109) (layer "In4.Cu") (net 140))
  (segment (start 134.025 135.05) (end 128.625 135.05) (width 0.109) (layer "In4.Cu") (net 140))
  (segment (start 96.725 130.505) (end 93.91999 127.69999) (width 0.109) (layer "In4.Cu") (net 140))
  (segment (start 93.91999 127.69999) (end 90.81499 127.69999) (width 0.109) (layer "In4.Cu") (net 140))
  (segment (start 115.8 135.2) (end 111.105 130.505) (width 0.109) (layer "In4.Cu") (net 140))
  (segment (start 90.81499 127.69999) (end 87 127.69999) (width 0.109) (layer "In4.Cu") (net 140))
  (segment (start 128.495499 134.920499) (end 127.004501 134.920499) (width 0.109) (layer "In4.Cu") (net 140))
  (segment (start 135.8 132.5) (end 135.825 132.525) (width 0.109) (layer "In4.Cu") (net 140))
  (segment (start 135.825 133.25) (end 134.025 135.05) (width 0.109) (layer "In4.Cu") (net 140))
  (segment (start 128.625 135.05) (end 128.495499 134.920499) (width 0.109) (layer "In4.Cu") (net 140))
  (segment (start 135.825 132.525) (end 135.825 133.25) (width 0.109) (layer "In4.Cu") (net 140))
  (segment (start 127.004501 134.920499) (end 126.725 135.2) (width 0.109) (layer "In4.Cu") (net 140))
  (segment (start 91.1715 126.518999) (end 91.1715 126.5235) (width 0.109) (layer "In4.Cu") (net 140))
  (segment (start 91.1715 126.5235) (end 90.81499 126.88001) (width 0.109) (layer "In4.Cu") (net 140))
  (segment (start 90.81499 126.88001) (end 90.81499 127.69999) (width 0.109) (layer "In4.Cu") (net 140))
  (segment (start 111.105 130.505) (end 96.725 130.505) (width 0.109) (layer "In4.Cu") (net 140))
  (segment (start 82.345 136.998) (end 81.573 136.998) (width 0.182) (layer "F.Cu") (net 141))
  (segment (start 137.3 115.925) (end 136.725 115.925) (width 0.182) (layer "F.Cu") (net 141))
  (segment (start 80.4 137.3) (end 80.7 137) (width 0.182) (layer "F.Cu") (net 141))
  (segment (start 137.98 116.325) (end 137.7 116.325) (width 0.182) (layer "F.Cu") (net 141))
  (segment (start 78.8 138.975) (end 79.825 138.975) (width 0.182) (layer "F.Cu") (net 141))
  (segment (start 137.7 116.325) (end 137.3 115.925) (width 0.182) (layer "F.Cu") (net 141))
  (segment (start 82.3475 137) (end 84.1 137) (width 0.182) (layer "F.Cu") (net 141))
  (segment (start 93.3265 121.749) (end 93.648213 121.427287) (width 0.182) (layer "F.Cu") (net 141))
  (segment (start 85.3 128.35) (end 86.55 127.1) (width 0.182) (layer "F.Cu") (net 141))
  (segment (start 93.648213 121.427287) (end 93.720038 121.427287) (width 0.182) (layer "F.Cu") (net 141))
  (segment (start 79.825 138.975) (end 80.4 138.4) (width 0.182) (layer "F.Cu") (net 141))
  (segment (start 80.7 137) (end 81.5125 137) (width 0.182) (layer "F.Cu") (net 141))
  (segment (start 80.4 138.4) (end 80.4 137.3) (width 0.182) (layer "F.Cu") (net 141))
  (segment (start 84.1 137) (end 85.3 135.8) (width 0.182) (layer "F.Cu") (net 141))
  (segment (start 85.3 135.8) (end 85.3 128.35) (width 0.182) (layer "F.Cu") (net 141))
  (via (at 136.725 115.925) (size 0.45) (drill 0.1) (layers "F.Cu" "B.Cu") (net 141))
  (via (at 86.55 127.1) (size 0.45) (drill 0.1) (layers "F.Cu" "B.Cu") (net 141))
  (via (at 93.720038 121.427287) (size 0.45) (drill 0.1) (layers "F.Cu" "B.Cu") (net 141))
  (segment (start 94.09 121.797249) (end 93.720038 121.427287) (width 0.109) (layer "In2.Cu") (net 141))
  (segment (start 88.49 124.28) (end 88.77 124) (width 0.109) (layer "In2.Cu") (net 141))
  (segment (start 93.74 124) (end 94.09 123.65) (width 0.109) (layer "In2.Cu") (net 141))
  (segment (start 86.55 127.1) (end 88.15 127.1) (width 0.109) (layer "In2.Cu") (net 141))
  (segment (start 88.49 126.76) (end 88.49 124.28) (width 0.109) (layer "In2.Cu") (net 141))
  (segment (start 94.09 123.65) (end 94.09 121.797249) (width 0.109) (layer "In2.Cu") (net 141))
  (segment (start 88.15 127.1) (end 88.49 126.76) (width 0.109) (layer "In2.Cu") (net 141))
  (segment (start 88.77 124) (end 93.74 124) (width 0.109) (layer "In2.Cu") (net 141))
  (segment (start 93.7065 121.439) (end 94.434 121.439) (width 0.109) (layer "In4.Cu") (net 141))
  (segment (start 98.3 127.455) (end 111.85 127.455) (width 0.109) (layer "In4.Cu") (net 141))
  (segment (start 133.1 132.18) (end 133.1 126.355) (width 0.109) (layer "In4.Cu") (net 141))
  (segment (start 94.434 121.439) (end 95.3 122.305) (width 0.109) (layer "In4.Cu") (net 141))
  (segment (start 95.3 122.305) (end 95.3 124.455) (width 0.109) (layer "In4.Cu") (net 141))
  (segment (start 133.1 126.355) (end 136.458512 122.996488) (width 0.109) (layer "In4.Cu") (net 141))
  (segment (start 137.4 117.35) (end 137.4 116.6) (width 0.109) (layer "In4.Cu") (net 141))
  (segment (start 136.458512 122.996488) (end 136.458512 118.291488) (width 0.109) (layer "In4.Cu") (net 141))
  (segment (start 137.4 116.6) (end 136.725 115.925) (width 0.109) (layer "In4.Cu") (net 141))
  (segment (start 131.825 133.455) (end 133.1 132.18) (width 0.109) (layer "In4.Cu") (net 141))
  (segment (start 111.85 127.455) (end 117.85 133.455) (width 0.109) (layer "In4.Cu") (net 141))
  (segment (start 95.3 124.455) (end 98.3 127.455) (width 0.109) (layer "In4.Cu") (net 141))
  (segment (start 117.85 133.455) (end 131.825 133.455) (width 0.109) (layer "In4.Cu") (net 141))
  (segment (start 136.458512 118.291488) (end 137.4 117.35) (width 0.109) (layer "In4.Cu") (net 141))
  (segment (start 80.55 136.5) (end 80.075 136.975) (width 0.182) (layer "F.Cu") (net 142))
  (segment (start 137.375 121.4) (end 138.18 121.4) (width 0.182) (layer "F.Cu") (net 142))
  (segment (start 83.5 136.5) (end 84.4 135.6) (width 0.182) (layer "F.Cu") (net 142))
  (segment (start 81.5125 136.5) (end 80.55 136.5) (width 0.182) (layer "F.Cu") (net 142))
  (segment (start 80.075 136.975) (end 78.8 136.975) (width 0.182) (layer "F.Cu") (net 142))
  (segment (start 84.4 127.85) (end 85.8 126.45) (width 0.182) (layer "F.Cu") (net 142))
  (segment (start 82.3475 136.5) (end 83.5 136.5) (width 0.182) (layer "F.Cu") (net 142))
  (segment (start 84.4 135.6) (end 84.4 127.85) (width 0.182) (layer "F.Cu") (net 142))
  (segment (start 81.573 136.498) (end 82.345 136.498) (width 0.182) (layer "F.Cu") (net 142))
  (segment (start 92.84 122.7) (end 93.3265 122.384) (width 0.182) (layer "F.Cu") (net 142))
  (via (at 137.375 121.4) (size 0.45) (drill 0.1) (layers "F.Cu" "B.Cu") (net 142))
  (via (at 92.84 122.7) (size 0.45) (drill 0.1) (layers "F.Cu" "B.Cu") (net 142))
  (via (at 85.8 126.45) (size 0.45) (drill 0.1) (layers "F.Cu" "B.Cu") (net 142))
  (segment (start 88.02 125.93) (end 88.02 124.28) (width 0.109) (layer "In2.Cu") (net 142))
  (segment (start 88.59137 123.70863) (end 92.155105 123.70863) (width 0.109) (layer "In2.Cu") (net 142))
  (segment (start 92.155105 123.70863) (end 92.361001 123.502734) (width 0.109) (layer "In2.Cu") (net 142))
  (segment (start 92.361001 123.502734) (end 92.361001 123.178999) (width 0.109) (layer "In2.Cu") (net 142))
  (segment (start 87.5 126.45) (end 88.02 125.93) (width 0.109) (layer "In2.Cu") (net 142))
  (segment (start 88.02 124.28) (end 88.59137 123.70863) (width 0.109) (layer "In2.Cu") (net 142))
  (segment (start 92.361001 123.178999) (end 92.84 122.7) (width 0.109) (layer "In2.Cu") (net 142))
  (segment (start 85.8 126.45) (end 87.5 126.45) (width 0.109) (layer "In2.Cu") (net 142))
  (segment (start 94.145 122.05) (end 94.825 122.73) (width 0.109) (layer "In4.Cu") (net 142))
  (segment (start 97.9 128.33) (end 111.53 128.33) (width 0.109) (layer "In4.Cu") (net 142))
  (segment (start 134.7 125.58) (end 136.7 123.58) (width 0.109) (layer "In4.Cu") (net 142))
  (segment (start 136.7 121.6) (end 136.9 121.4) (width 0.109) (layer "In4.Cu") (net 142))
  (segment (start 94.825 122.73) (end 94.825 125.255) (width 0.109) (layer "In4.Cu") (net 142))
  (segment (start 134.7 131.93) (end 134.7 125.58) (width 0.109) (layer "In4.Cu") (net 142))
  (segment (start 111.53 128.33) (end 117.2 134) (width 0.109) (layer "In4.Cu") (net 142))
  (segment (start 136.9 121.4) (end 137.375 121.4) (width 0.109) (layer "In4.Cu") (net 142))
  (segment (start 132.63 134) (end 134.7 131.93) (width 0.109) (layer "In4.Cu") (net 142))
  (segment (start 117.2 134) (end 132.63 134) (width 0.109) (layer "In4.Cu") (net 142))
  (segment (start 136.7 123.58) (end 136.7 121.6) (width 0.109) (layer "In4.Cu") (net 142))
  (segment (start 94.825 125.255) (end 97.9 128.33) (width 0.109) (layer "In4.Cu") (net 142))
  (segment (start 93.49 122.05) (end 94.145 122.05) (width 0.109) (layer "In4.Cu") (net 142))
  (segment (start 92.84 122.7) (end 93.49 122.05) (width 0.109) (layer "In4.Cu") (net 142))
  (segment (start 81.573 135.5) (end 82.345 135.5) (width 0.182) (layer "F.Cu") (net 143))
  (segment (start 80.125 134.975) (end 80.65 135.5) (width 0.182) (layer "F.Cu") (net 143))
  (segment (start 136.808192 116.649946) (end 137.174946 116.649946) (width 0.182) (layer "F.Cu") (net 143))
  (segment (start 82.3475 135.5) (end 83.1 135.5) (width 0.182) (layer "F.Cu") (net 143))
  (segment (start 83.8 134.8) (end 83.8 127.1) (width 0.182) (layer "F.Cu") (net 143))
  (segment (start 93.3265 121.114) (end 93.7115 120.803999) (width 0.182) (layer "F.Cu") (net 143))
  (segment (start 83.8 127.1) (end 85.1 125.8) (width 0.182) (layer "F.Cu") (net 143))
  (segment (start 83.1 135.5) (end 83.8 134.8) (width 0.182) (layer "F.Cu") (net 143))
  (segment (start 137.98 116.725) (end 137.25 116.725) (width 0.182) (layer "F.Cu") (net 143))
  (segment (start 78.8 134.975) (end 80.125 134.975) (width 0.182) (layer "F.Cu") (net 143))
  (segment (start 137.174946 116.649946) (end 137.25 116.725) (width 0.182) (layer "F.Cu") (net 143))
  (segment (start 80.65 135.5) (end 81.5125 135.5) (width 0.182) (layer "F.Cu") (net 143))
  (via (at 93.7115 120.803999) (size 0.45) (drill 0.1) (layers "F.Cu" "B.Cu") (net 143))
  (via (at 136.808192 116.649946) (size 0.45) (drill 0.1) (layers "F.Cu" "B.Cu") (net 143))
  (via (at 85.1 125.8) (size 0.45) (drill 0.1) (layers "F.Cu" "B.Cu") (net 143))
  (segment (start 86.675 124.765) (end 87.05 124.39) (width 0.109) (layer "In2.Cu") (net 143))
  (segment (start 85.1 125.8) (end 84.885 126.015) (width 0.109) (layer "In2.Cu") (net 143))
  (segment (start 93.3 121.18275) (end 93.678751 120.803999) (width 0.109) (layer "In2.Cu") (net 143))
  (segment (start 84.885 126.015) (end 84.215 126.015) (width 0.109) (layer "In2.Cu") (net 143))
  (segment (start 83.835 125.065) (end 84.135 124.765) (width 0.109) (layer "In2.Cu") (net 143))
  (segment (start 84.135 124.765) (end 86.675 124.765) (width 0.109) (layer "In2.Cu") (net 143))
  (segment (start 87.05 123.05) (end 88.05 122.05) (width 0.109) (layer "In2.Cu") (net 143))
  (segment (start 83.835 125.635) (end 83.835 125.065) (width 0.109) (layer "In2.Cu") (net 143))
  (segment (start 84.215 126.015) (end 83.835 125.635) (width 0.109) (layer "In2.Cu") (net 143))
  (segment (start 92.9 122.05) (end 93.3 121.65) (width 0.109) (layer "In2.Cu") (net 143))
  (segment (start 93.3 121.65) (end 93.3 121.18275) (width 0.109) (layer "In2.Cu") (net 143))
  (segment (start 87.05 124.39) (end 87.05 123.05) (width 0.109) (layer "In2.Cu") (net 143))
  (segment (start 93.678751 120.803999) (end 93.7115 120.803999) (width 0.109) (layer "In2.Cu") (net 143))
  (segment (start 88.05 122.05) (end 92.9 122.05) (width 0.109) (layer "In2.Cu") (net 143))
  (segment (start 131.105 132.975) (end 132.6 131.48) (width 0.109) (layer "In4.Cu") (net 143))
  (segment (start 132.6 131.48) (end 132.6 126.155) (width 0.109) (layer "In4.Cu") (net 143))
  (segment (start 136.249501 117.830499) (end 136.808192 117.271808) (width 0.109) (layer "In4.Cu") (net 143))
  (segment (start 95.775 123.555) (end 98.77 126.55) (width 0.109) (layer "In4.Cu") (net 143))
  (segment (start 136.808192 117.271808) (end 136.808192 116.649946) (width 0.109) (layer "In4.Cu") (net 143))
  (segment (start 98.77 126.55) (end 112.295 126.55) (width 0.109) (layer "In4.Cu") (net 143))
  (segment (start 93.7065 120.803999) (end 94.598999 120.803999) (width 0.109) (layer "In4.Cu") (net 143))
  (segment (start 136.249501 122.505499) (end 136.249501 117.830499) (width 0.109) (layer "In4.Cu") (net 143))
  (segment (start 94.598999 120.803999) (end 95.775 121.98) (width 0.109) (layer "In4.Cu") (net 143))
  (segment (start 95.775 121.98) (end 95.775 123.555) (width 0.109) (layer "In4.Cu") (net 143))
  (segment (start 112.295 126.55) (end 118.72 132.975) (width 0.109) (layer "In4.Cu") (net 143))
  (segment (start 118.72 132.975) (end 131.105 132.975) (width 0.109) (layer "In4.Cu") (net 143))
  (segment (start 132.6 126.155) (end 136.249501 122.505499) (width 0.109) (layer "In4.Cu") (net 143))
  (segment (start 92.84 126.51) (end 93.3265 126.194) (width 0.182) (layer "F.Cu") (net 144))
  (via (at 92.84 126.51) (size 0.45) (drill 0.1) (layers "F.Cu" "B.Cu") (net 144))
  (via (at 176.071137 140.76584) (size 0.45) (drill 0.1) (layers "F.Cu" "B.Cu") (net 144))
  (segment (start 109.75 131.625) (end 120.225 142.1) (width 0.109) (layer "In6.Cu") (net 144))
  (segment (start 145.15 139.9) (end 147.02 141.77) (width 0.109) (layer "In6.Cu") (net 144))
  (segment (start 143.25 139.9) (end 145.15 139.9) (width 0.109) (layer "In6.Cu") (net 144))
  (segment (start 94.091001 127.566001) (end 98.15 131.625) (width 0.109) (layer "In6.Cu") (net 144))
  (segment (start 161.565526 140.6) (end 162.795526 141.83) (width 0.109) (layer "In6.Cu") (net 144))
  (segment (start 141.05 142.1) (end 143.25 139.9) (width 0.109) (layer "In6.Cu") (net 144))
  (segment (start 169.8 141.25) (end 170.9 142.35) (width 0.109) (layer "In6.Cu") (net 144))
  (segment (start 158.882946 140.6) (end 161.565526 140.6) (width 0.109) (layer "In6.Cu") (net 144))
  (segment (start 167.688338 141.25) (end 169.8 141.25) (width 0.109) (layer "In6.Cu") (net 144))
  (segment (start 93.893661 126.130499) (end 94.091001 126.327839) (width 0.109) (layer "In6.Cu") (net 144))
  (segment (start 174.486977 142.35) (end 176.071137 140.76584) (width 0.109) (layer "In6.Cu") (net 144))
  (segment (start 147.02 141.77) (end 157.712946 141.77) (width 0.109) (layer "In6.Cu") (net 144))
  (segment (start 170.9 142.35) (end 174.486977 142.35) (width 0.109) (layer "In6.Cu") (net 144))
  (segment (start 93.219501 126.130499) (end 93.893661 126.130499) (width 0.109) (layer "In6.Cu") (net 144))
  (segment (start 98.15 131.625) (end 109.75 131.625) (width 0.109) (layer "In6.Cu") (net 144))
  (segment (start 94.091001 126.327839) (end 94.091001 127.566001) (width 0.109) (layer "In6.Cu") (net 144))
  (segment (start 157.712946 141.77) (end 158.882946 140.6) (width 0.109) (layer "In6.Cu") (net 144))
  (segment (start 162.795526 141.83) (end 167.108338 141.83) (width 0.109) (layer "In6.Cu") (net 144))
  (segment (start 120.225 142.1) (end 141.05 142.1) (width 0.109) (layer "In6.Cu") (net 144))
  (segment (start 167.108338 141.83) (end 167.688338 141.25) (width 0.109) (layer "In6.Cu") (net 144))
  (segment (start 92.84 126.51) (end 93.219501 126.130499) (width 0.109) (layer "In6.Cu") (net 144))
  (segment (start 175.3 141.4825) (end 175.3 141.15) (width 0.182) (layer "B.Cu") (net 144))
  (segment (start 175.3 142.3175) (end 175.3 142.8) (width 0.182) (layer "B.Cu") (net 144))
  (segment (start 175.3 142.287) (end 175.3 141.515) (width 0.182) (layer "B.Cu") (net 144))
  (segment (start 175.68416 140.76584) (end 176.071137 140.76584) (width 0.182) (layer "B.Cu") (net 144))
  (segment (start 176.8 145.5) (end 178.1 146.8) (width 0.182) (layer "B.Cu") (net 144))
  (segment (start 175.3 141.15) (end 175.68416 140.76584) (width 0.182) (layer "B.Cu") (net 144))
  (segment (start 176.8 143.7) (end 176.8 145.5) (width 0.182) (layer "B.Cu") (net 144))
  (segment (start 176.1 143) (end 176.8 143.7) (width 0.182) (layer "B.Cu") (net 144))
  (segment (start 175.5 143) (end 176.1 143) (width 0.182) (layer "B.Cu") (net 144))
  (segment (start 175.3 142.8) (end 175.5 143) (width 0.182) (layer "B.Cu") (net 144))
  (segment (start 81.573 135) (end 82.345 135) (width 0.182) (layer "F.Cu") (net 145))
  (segment (start 93.3265 123.019) (end 93.636501 122.708999) (width 0.182) (layer "F.Cu") (net 145))
  (segment (start 81.5125 135) (end 80.7 135) (width 0.182) (layer "F.Cu") (net 145))
  (segment (start 80.7 135) (end 80.3 134.6) (width 0.182) (layer "F.Cu") (net 145))
  (segment (start 80.3 134.6) (end 80.3 133.4) (width 0.182) (layer "F.Cu") (net 145))
  (segment (start 137.175 117.125) (end 136.875 117.425) (width 0.182) (layer "F.Cu") (net 145))
  (segment (start 80.3 133.4) (end 79.875 132.975) (width 0.182) (layer "F.Cu") (net 145))
  (segment (start 82.7 135) (end 83.05 134.65) (width 0.182) (layer "F.Cu") (net 145))
  (segment (start 83.05 126.8) (end 84.5 125.35) (width 0.182) (layer "F.Cu") (net 145))
  (segment (start 83.05 134.65) (end 83.05 126.8) (width 0.182) (layer "F.Cu") (net 145))
  (segment (start 82.3475 135) (end 82.7 135) (width 0.182) (layer "F.Cu") (net 145))
  (segment (start 137.98 117.125) (end 137.175 117.125) (width 0.182) (layer "F.Cu") (net 145))
  (segment (start 93.636501 122.708999) (end 93.71049 122.708999) (width 0.182) (layer "F.Cu") (net 145))
  (segment (start 136.875 117.425) (end 136.875 118.625) (width 0.182) (layer "F.Cu") (net 145))
  (segment (start 79.875 132.975) (end 78.8 132.975) (width 0.182) (layer "F.Cu") (net 145))
  (via (at 136.875 118.625) (size 0.45) (drill 0.1) (layers "F.Cu" "B.Cu") (net 145))
  (via (at 84.5 125.35) (size 0.45) (drill 0.1) (layers "F.Cu" "B.Cu") (net 145))
  (via (at 93.71049 122.708999) (size 0.45) (drill 0.1) (layers "F.Cu" "B.Cu") (net 145))
  (segment (start 88.3 122.3) (end 93.301491 122.3) (width 0.109) (layer "In2.Cu") (net 145))
  (segment (start 87.505 123.095) (end 88.3 122.3) (width 0.109) (layer "In2.Cu") (net 145))
  (segment (start 93.301491 122.3) (end 93.71049 122.708999) (width 0.109) (layer "In2.Cu") (net 145))
  (segment (start 84.5 125.35) (end 87.12 125.35) (width 0.109) (layer "In2.Cu") (net 145))
  (segment (start 87.12 125.35) (end 87.505 124.965) (width 0.109) (layer "In2.Cu") (net 145))
  (segment (start 87.505 124.965) (end 87.505 123.095) (width 0.109) (layer "In2.Cu") (net 145))
  (segment (start 137.755 119.186802) (end 137.193198 118.625) (width 0.109) (layer "In4.Cu") (net 145))
  (segment (start 133.3 134.555) (end 135.3 132.555) (width 0.109) (layer "In4.Cu") (net 145))
  (segment (start 137.755 119.931662) (end 137.755 119.186802) (width 0.109) (layer "In4.Cu") (net 145))
  (segment (start 111.055 129.305) (end 116.305 134.555) (width 0.109) (layer "In4.Cu") (net 145))
  (segment (start 93.7065 122.708999) (end 94.325 123.327499) (width 0.109) (layer "In4.Cu") (net 145))
  (segment (start 137.1 123) (end 137.9 122.2) (width 0.109) (layer "In4.Cu") (net 145))
  (segment (start 116.305 134.555) (end 133.3 134.555) (width 0.109) (layer "In4.Cu") (net 145))
  (segment (start 135.3 125.7) (end 137.1 123.9) (width 0.109) (layer "In4.Cu") (net 145))
  (segment (start 97.625 129.305) (end 111.055 129.305) (width 0.109) (layer "In4.Cu") (net 145))
  (segment (start 137.1 123.9) (end 137.1 123) (width 0.109) (layer "In4.Cu") (net 145))
  (segment (start 135.3 132.555) (end 135.3 125.7) (width 0.109) (layer "In4.Cu") (net 145))
  (segment (start 94.325 123.327499) (end 94.325 126.005) (width 0.109) (layer "In4.Cu") (net 145))
  (segment (start 137.193198 118.625) (end 136.875 118.625) (width 0.109) (layer "In4.Cu") (net 145))
  (segment (start 137.9 122.2) (end 137.9 120.076662) (width 0.109) (layer "In4.Cu") (net 145))
  (segment (start 137.9 120.076662) (end 137.755 119.931662) (width 0.109) (layer "In4.Cu") (net 145))
  (segment (start 94.325 126.005) (end 97.625 129.305) (width 0.109) (layer "In4.Cu") (net 145))
  (segment (start 175.3 141.4825) (end 175.3 141.25) (width 0.182) (layer "F.Cu") (net 146))
  (segment (start 175.3 142.8) (end 175.5 143) (width 0.182) (layer "F.Cu") (net 146))
  (segment (start 175.3 141.25) (end 175.631001 140.918999) (width 0.182) (layer "F.Cu") (net 146))
  (segment (start 91.9815 124.599) (end 92.3665 124.289) (width 0.182) (layer "F.Cu") (net 146))
  (segment (start 175.631001 140.918999) (end 175.631001 140.268185) (width 0.182) (layer "F.Cu") (net 146))
  (segment (start 175.3 142.285) (end 175.3 141.513) (width 0.182) (layer "F.Cu") (net 146))
  (segment (start 176.84 143) (end 178.1 144.26) (width 0.182) (layer "F.Cu") (net 146))
  (segment (start 175.5 143) (end 176.84 143) (width 0.182) (layer "F.Cu") (net 146))
  (segment (start 175.3 142.3175) (end 175.3 142.8) (width 0.182) (layer "F.Cu") (net 146))
  (via (at 175.631001 140.268185) (size 0.45) (drill 0.1) (layers "F.Cu" "B.Cu") (net 146))
  (via (at 91.9815 124.599) (size 0.45) (drill 0.1) (layers "F.Cu" "B.Cu") (net 146))
  (segment (start 175.631001 140.268185) (end 175.631001 140.744199) (width 0.109) (layer "In6.Cu") (net 146))
  (segment (start 94.4875 127.1625) (end 94.4875 126.2875) (width 0.109) (layer "In6.Cu") (net 146))
  (segment (start 98.05 130.725) (end 94.4875 127.1625) (width 0.109) (layer "In6.Cu") (net 146))
  (segment (start 148.18 141.01) (end 146.37 139.2) (width 0.109) (layer "In6.Cu") (net 146))
  (segment (start 109.9 130.725) (end 98.05 130.725) (width 0.109) (layer "In6.Cu") (net 146))
  (segment (start 142.875 139.2) (end 140.495 141.58) (width 0.109) (layer "In6.Cu") (net 146))
  (segment (start 146.37 139.2) (end 142.875 139.2) (width 0.109) (layer "In6.Cu") (net 146))
  (segment (start 175.631001 140.744199) (end 174.5002 141.875) (width 0.109) (layer "In6.Cu") (net 146))
  (segment (start 157.53 141.01) (end 148.18 141.01) (width 0.109) (layer "In6.Cu") (net 146))
  (segment (start 158.44 140.1) (end 157.53 141.01) (width 0.109) (layer "In6.Cu") (net 146))
  (segment (start 140.495 141.58) (end 120.755 141.58) (width 0.109) (layer "In6.Cu") (net 146))
  (segment (start 167.41 140.93) (end 167.01 141.33) (width 0.109) (layer "In6.Cu") (net 146))
  (segment (start 161.62 140.1) (end 158.44 140.1) (width 0.109) (layer "In6.Cu") (net 146))
  (segment (start 170.13 140.93) (end 167.41 140.93) (width 0.109) (layer "In6.Cu") (net 146))
  (segment (start 93.975 125.775) (end 92.75 125.775) (width 0.109) (layer "In6.Cu") (net 146))
  (segment (start 167.01 141.33) (end 162.85 141.33) (width 0.109) (layer "In6.Cu") (net 146))
  (segment (start 94.4875 126.2875) (end 93.975 125.775) (width 0.109) (layer "In6.Cu") (net 146))
  (segment (start 120.755 141.58) (end 109.9 130.725) (width 0.109) (layer "In6.Cu") (net 146))
  (segment (start 92.75 125.775) (end 92.4 125.425) (width 0.109) (layer "In6.Cu") (net 146))
  (segment (start 171.075 141.875) (end 170.13 140.93) (width 0.109) (layer "In6.Cu") (net 146))
  (segment (start 92.4 125.0125) (end 91.9865 124.599) (width 0.109) (layer "In6.Cu") (net 146))
  (segment (start 174.5002 141.875) (end 171.075 141.875) (width 0.109) (layer "In6.Cu") (net 146))
  (segment (start 162.85 141.33) (end 161.62 140.1) (width 0.109) (layer "In6.Cu") (net 146))
  (segment (start 92.4 125.425) (end 92.4 125.0125) (width 0.109) (layer "In6.Cu") (net 146))
  (segment (start 174.8 141.4825) (end 174.8 140.996707) (width 0.182) (layer "F.Cu") (net 147))
  (segment (start 92.3665 123.654) (end 92.84 123.34) (width 0.182) (layer "F.Cu") (net 147))
  (segment (start 174.8 143.5) (end 175.56 144.26) (width 0.182) (layer "F.Cu") (net 147))
  (segment (start 174.8 142.285) (end 174.8 141.513) (width 0.182) (layer "F.Cu") (net 147))
  (segment (start 174.8 142.3175) (end 174.8 143.5) (width 0.182) (layer "F.Cu") (net 147))
  (segment (start 174.8 140.996707) (end 175.131173 140.665534) (width 0.182) (layer "F.Cu") (net 147))
  (via (at 175.131173 140.665534) (size 0.45) (drill 0.1) (layers "F.Cu" "B.Cu") (net 147))
  (via (at 92.852386 123.338751) (size 0.45) (drill 0.1) (layers "F.Cu" "B.Cu") (net 147))
  (segment (start 96.75 126.025) (end 98.05 127.325) (width 0.109) (layer "In6.Cu") (net 147))
  (segment (start 123.205 139.48) (end 138.795 139.48) (width 0.109) (layer "In6.Cu") (net 147))
  (segment (start 174.793198 139.9) (end 175.131173 140.237975) (width 0.109) (layer "In6.Cu") (net 147))
  (segment (start 158.64 138.56) (end 159.2 138) (width 0.109) (layer "In6.Cu") (net 147))
  (segment (start 151.285 136.175) (end 153.09 137.98) (width 0.109) (layer "In6.Cu") (net 147))
  (segment (start 142.1 136.175) (end 151.285 136.175) (width 0.109) (layer "In6.Cu") (net 147))
  (segment (start 157.27 138.56) (end 158.64 138.56) (width 0.109) (layer "In6.Cu") (net 147))
  (segment (start 95.1625 124.0125) (end 96.75 125.6) (width 0.109) (layer "In6.Cu") (net 147))
  (segment (start 92.852386 123.338751) (end 93.526135 124.0125) (width 0.109) (layer "In6.Cu") (net 147))
  (segment (start 171.64 139.7) (end 172.103512 140.163512) (width 0.109) (layer "In6.Cu") (net 147))
  (segment (start 162.27 138) (end 163.72 139.45) (width 0.109) (layer "In6.Cu") (net 147))
  (segment (start 111.05 127.325) (end 123.205 139.48) (width 0.109) (layer "In6.Cu") (net 147))
  (segment (start 163.72 139.45) (end 169.08 139.45) (width 0.109) (layer "In6.Cu") (net 147))
  (segment (start 172.103512 140.163512) (end 174.186488 140.163512) (width 0.109) (layer "In6.Cu") (net 147))
  (segment (start 159.2 138) (end 162.27 138) (width 0.109) (layer "In6.Cu") (net 147))
  (segment (start 138.795 139.48) (end 142.1 136.175) (width 0.109) (layer "In6.Cu") (net 147))
  (segment (start 169.33 139.7) (end 171.64 139.7) (width 0.109) (layer "In6.Cu") (net 147))
  (segment (start 93.526135 124.0125) (end 95.1625 124.0125) (width 0.109) (layer "In6.Cu") (net 147))
  (segment (start 156.69 137.98) (end 157.27 138.56) (width 0.109) (layer "In6.Cu") (net 147))
  (segment (start 98.05 127.325) (end 111.05 127.325) (width 0.109) (layer "In6.Cu") (net 147))
  (segment (start 174.45 139.9) (end 174.793198 139.9) (width 0.109) (layer "In6.Cu") (net 147))
  (segment (start 174.186488 140.163512) (end 174.45 139.9) (width 0.109) (layer "In6.Cu") (net 147))
  (segment (start 169.08 139.45) (end 169.33 139.7) (width 0.109) (layer "In6.Cu") (net 147))
  (segment (start 96.75 125.6) (end 96.75 126.025) (width 0.109) (layer "In6.Cu") (net 147))
  (segment (start 153.09 137.98) (end 156.69 137.98) (width 0.109) (layer "In6.Cu") (net 147))
  (segment (start 175.131173 140.237975) (end 175.131173 140.665534) (width 0.109) (layer "In6.Cu") (net 147))
  (segment (start 91.9815 123.329) (end 92.3665 123.019) (width 0.182) (layer "F.Cu") (net 148))
  (segment (start 173.8 142.3175) (end 173.8 143.48) (width 0.182) (layer "F.Cu") (net 148))
  (segment (start 173.802 142.285) (end 173.802 141.513) (width 0.182) (layer "F.Cu") (net 148))
  (segment (start 173.8 141.4825) (end 173.8 140.920559) (width 0.182) (layer "F.Cu") (net 148))
  (segment (start 173.8 140.920559) (end 173.9 140.820559) (width 0.182) (layer "F.Cu") (net 148))
  (segment (start 173.8 143.48) (end 173.02 144.26) (width 0.182) (layer "F.Cu") (net 148))
  (segment (start 173.9 140.820559) (end 173.9 139.6) (width 0.182) (layer "F.Cu") (net 148))
  (via (at 173.9 139.6) (size 0.45) (drill 0.1) (layers "F.Cu" "B.Cu") (net 148))
  (via (at 91.9815 123.320573) (size 0.45) (drill 0.1) (layers "F.Cu" "B.Cu") (net 148))
  (segment (start 164.17 139.05) (end 169.4 139.05) (width 0.109) (layer "In6.Cu") (net 148))
  (segment (start 157.05 137.25) (end 157.45 136.85) (width 0.109) (layer "In6.Cu") (net 148))
  (segment (start 111.5325 126.625) (end 123.7875 138.88) (width 0.109) (layer "In6.Cu") (net 148))
  (segment (start 152.275 135.275) (end 154.25 137.25) (width 0.109) (layer "In6.Cu") (net 148))
  (segment (start 159.286601 137.5) (end 162.62 137.5) (width 0.109) (layer "In6.Cu") (net 148))
  (segment (start 158.636601 136.85) (end 159.286601 137.5) (width 0.109) (layer "In6.Cu") (net 148))
  (segment (start 157.45 136.85) (end 158.636601 136.85) (width 0.109) (layer "In6.Cu") (net 148))
  (segment (start 98.425 126.625) (end 111.5325 126.625) (width 0.109) (layer "In6.Cu") (net 148))
  (segment (start 123.7875 138.88) (end 138.395 138.88) (width 0.109) (layer "In6.Cu") (net 148))
  (segment (start 142 135.275) (end 152.275 135.275) (width 0.109) (layer "In6.Cu") (net 148))
  (segment (start 94.1 122.3) (end 98.425 126.625) (width 0.109) (layer "In6.Cu") (net 148))
  (segment (start 169.4 139.05) (end 169.76 139.41) (width 0.109) (layer "In6.Cu") (net 148))
  (segment (start 172.674501 139.954501) (end 173.545499 139.954501) (width 0.109) (layer "In6.Cu") (net 148))
  (segment (start 173.545499 139.954501) (end 173.9 139.6) (width 0.109) (layer "In6.Cu") (net 148))
  (segment (start 92.4 122.898646) (end 92.4 122.5) (width 0.109) (layer "In6.Cu") (net 148))
  (segment (start 138.395 138.88) (end 142 135.275) (width 0.109) (layer "In6.Cu") (net 148))
  (segment (start 92.6 122.3) (end 94.1 122.3) (width 0.109) (layer "In6.Cu") (net 148))
  (segment (start 162.62 137.5) (end 164.17 139.05) (width 0.109) (layer "In6.Cu") (net 148))
  (segment (start 92.4 122.5) (end 92.6 122.3) (width 0.109) (layer "In6.Cu") (net 148))
  (segment (start 91.978073 123.320573) (end 92.4 122.898646) (width 0.109) (layer "In6.Cu") (net 148))
  (segment (start 172.13 139.41) (end 172.674501 139.954501) (width 0.109) (layer "In6.Cu") (net 148))
  (segment (start 169.76 139.41) (end 172.13 139.41) (width 0.109) (layer "In6.Cu") (net 148))
  (segment (start 154.25 137.25) (end 157.05 137.25) (width 0.109) (layer "In6.Cu") (net 148))
  (segment (start 137.575 130.45) (end 137.325 130.2) (width 0.182) (layer "F.Cu") (net 149))
  (segment (start 91.9815 118.884) (end 92.3665 118.574) (width 0.182) (layer "F.Cu") (net 149))
  (segment (start 95.45451 124.20451) (end 95.45451 119) (width 0.182) (layer "F.Cu") (net 149))
  (segment (start 117.425 126.8) (end 98.05 126.8) (width 0.182) (layer "F.Cu") (net 149))
  (segment (start 143.949916 128.975084) (end 142.475 130.45) (width 0.182) (layer "F.Cu") (net 149))
  (segment (start 142.475 130.45) (end 137.575 130.45) (width 0.182) (layer "F.Cu") (net 149))
  (segment (start 98.05 126.8) (end 95.45451 124.20451) (width 0.182) (layer "F.Cu") (net 149))
  (segment (start 143.949916 126.857314) (end 143.949916 128.975084) (width 0.182) (layer "F.Cu") (net 149))
  (segment (start 137.325 130.2) (end 136.9 130.2) (width 0.182) (layer "F.Cu") (net 149))
  (via (at 136.9 130.2) (size 0.45) (drill 0.1) (layers "F.Cu" "B.Cu") (net 149))
  (via (at 91.9815 118.884) (size 0.45) (drill 0.1) (layers "F.Cu" "B.Cu") (net 149))
  (via (at 117.425 126.8) (size 0.45) (drill 0.1) (layers "F.Cu" "B.Cu") (net 149))
  (via (at 95.45451 119) (size 0.45) (drill 0.1) (layers "F.Cu" "B.Cu") (net 149))
  (segment (start 125.525 126.8) (end 129.175 130.45) (width 0.109) (layer "In2.Cu") (net 149))
  (segment (start 136.15 129.45) (end 136.9 130.2) (width 0.109) (layer "In2.Cu") (net 149))
  (segment (start 132.4 129.45) (end 136.15 129.45) (width 0.109) (layer "In2.Cu") (net 149))
  (segment (start 117.425 126.8) (end 125.525 126.8) (width 0.109) (layer "In2.Cu") (net 149))
  (segment (start 131.4 130.45) (end 132.4 129.45) (width 0.109) (layer "In2.Cu") (net 149))
  (segment (start 129.175 130.45) (end 131.4 130.45) (width 0.109) (layer "In2.Cu") (net 149))
  (segment (start 92.4205 118.45) (end 94.90451 118.45) (width 0.109) (layer "In4.Cu") (net 149))
  (segment (start 94.90451 118.45) (end 95.45451 119) (width 0.109) (layer "In4.Cu") (net 149))
  (segment (start 91.9865 118.884) (end 92.4205 118.45) (width 0.109) (layer "In4.Cu") (net 149))
  (segment (start 92.3665 117.939) (end 92.84 117.625) (width 0.182) (layer "F.Cu") (net 150))
  (segment (start 95.869204 123.569204) (end 95.869204 120.988316) (width 0.182) (layer "F.Cu") (net 150))
  (segment (start 143.549916 126.857314) (end 143.549916 128.800084) (width 0.182) (layer "F.Cu") (net 150))
  (segment (start 137.89 130.09) (end 137.375 129.575) (width 0.182) (layer "F.Cu") (net 150))
  (segment (start 117.5 126.225) (end 98.525 126.225) (width 0.182) (layer "F.Cu") (net 150))
  (segment (start 98.525 126.225) (end 95.869204 123.569204) (width 0.182) (layer "F.Cu") (net 150))
  (segment (start 137.375 129.575) (end 137.1 129.575) (width 0.182) (layer "F.Cu") (net 150))
  (segment (start 95.869204 120.988316) (end 96.094203 120.763317) (width 0.182) (layer "F.Cu") (net 150))
  (segment (start 143.549916 128.800084) (end 142.26 130.09) (width 0.182) (layer "F.Cu") (net 150))
  (segment (start 142.26 130.09) (end 137.89 130.09) (width 0.182) (layer "F.Cu") (net 150))
  (via (at 137.1 129.575) (size 0.45) (drill 0.1) (layers "F.Cu" "B.Cu") (net 150))
  (via (at 96.094203 120.763317) (size 0.45) (drill 0.1) (layers "F.Cu" "B.Cu") (net 150))
  (via (at 117.5 126.225) (size 0.45) (drill 0.1) (layers "F.Cu" "B.Cu") (net 150))
  (via (at 92.84 117.625) (size 0.45) (drill 0.1) (layers "F.Cu" "B.Cu") (net 150))
  (segment (start 125.625 126.225) (end 117.5 126.225) (width 0.109) (layer "In2.Cu") (net 150))
  (segment (start 137.1 129.575) (end 136.575 129.05) (width 0.109) (layer "In2.Cu") (net 150))
  (segment (start 128.45 129.05) (end 125.625 126.225) (width 0.109) (layer "In2.Cu") (net 150))
  (segment (start 136.575 129.05) (end 128.45 129.05) (width 0.109) (layer "In2.Cu") (net 150))
  (segment (start 93.415 117.05) (end 94.1 117.05) (width 0.109) (layer "In6.Cu") (net 150))
  (segment (start 94.625 117.575) (end 94.625 119.294114) (width 0.109) (layer "In6.Cu") (net 150))
  (segment (start 94.1 117.05) (end 94.625 117.575) (width 0.109) (layer "In6.Cu") (net 150))
  (segment (start 94.625 119.294114) (end 96.094203 120.763317) (width 0.109) (layer "In6.Cu") (net 150))
  (segment (start 92.84 117.625) (end 93.415 117.05) (width 0.109) (layer "In6.Cu") (net 150))
  (segment (start 139.651076 130.931873) (end 135.968127 130.931873) (width 0.182) (layer "F.Cu") (net 151))
  (segment (start 116.293458 129.1) (end 115.5 129.1) (width 0.182) (layer "F.Cu") (net 151))
  (segment (start 117.753064 127.450889) (end 117.753064 127.640394) (width 0.182) (layer "F.Cu") (net 151))
  (segment (start 110.481729 134.118271) (end 110.481729 134.911729) (width 0.182) (layer "F.Cu") (net 151))
  (segment (start 109.325 135.55) (end 109.35 135.525) (width 0.182) (layer "F.Cu") (net 151))
  (segment (start 125.1 133.1) (end 123.6 131.6) (width 0.182) (layer "F.Cu") (net 151))
  (segment (start 107.461161 135.6) (end 107.75 135.6) (width 0.182) (layer "F.Cu") (net 151))
  (segment (start 106.11 147.0592) (end 106.5592 147.0592) (width 0.182) (layer "F.Cu") (net 151))
  (segment (start 108.3 148.4) (end 108.3 147.2) (width 0.182) (layer "F.Cu") (net 151))
  (segment (start 135.968127 130.931873) (end 133.8 133.1) (width 0.182) (layer "F.Cu") (net 151))
  (segment (start 109.868458 135.525) (end 109.35 135.525) (width 0.182) (layer "F.Cu") (net 151))
  (segment (start 110.481729 134.911729) (end 109.868458 135.525) (width 0.182) (layer "F.Cu") (net 151))
  (segment (start 107.75 135.6) (end 107.7 135.55) (width 0.109) (layer "F.Cu") (net 151))
  (segment (start 133.8 133.1) (end 125.1 133.1) (width 0.182) (layer "F.Cu") (net 151))
  (segment (start 90.7865 127.464) (end 91.138209 127.464) (width 0.182) (layer "F.Cu") (net 151))
  (segment (start 107.7 135.55) (end 109.325 135.55) (width 0.182) (layer "F.Cu") (net 151))
  (segment (start 91.138209 127.464) (end 91.454968 127.147241) (width 0.182) (layer "F.Cu") (net 151))
  (segment (start 106.5592 147.0592) (end 106.7 147.2) (width 0.182) (layer "F.Cu") (net 151))
  (segment (start 115.5 129.1) (end 110.481729 134.118271) (width 0.182) (layer "F.Cu") (net 151))
  (segment (start 107.311161 135.45) (end 107.461161 135.6) (width 0.182) (layer "F.Cu") (net 151))
  (segment (start 106.7 147.2) (end 108.3 147.2) (width 0.182) (layer "F.Cu") (net 151))
  (segment (start 117.753064 127.640394) (end 116.293458 129.1) (width 0.182) (layer "F.Cu") (net 151))
  (via (at 91.454968 127.147241) (size 0.45) (drill 0.1) (layers "F.Cu" "B.Cu") (net 151))
  (via (at 123.6 131.6) (size 0.45) (drill 0.1) (layers "F.Cu" "B.Cu") (net 151))
  (via (at 107.311161 135.45) (size 0.45) (drill 0.1) (layers "F.Cu" "B.Cu") (net 151))
  (via (at 117.753064 127.450889) (size 0.45) (drill 0.1) (layers "F.Cu" "B.Cu") (net 151))
  (via (at 108.3 147.2) (size 0.45) (drill 0.1) (layers "F.Cu" "B.Cu") (net 151))
  (segment (start 121.902175 131.6) (end 117.753064 127.450889) (width 0.109) (layer "In4.Cu") (net 151))
  (segment (start 123.6 131.6) (end 121.902175 131.6) (width 0.109) (layer "In4.Cu") (net 151))
  (segment (start 107.311161 135.723034) (end 104.5 138.534195) (width 0.109) (layer "In6.Cu") (net 151))
  (segment (start 94.45 129.425) (end 97.9 132.875) (width 0.109) (layer "In6.Cu") (net 151))
  (segment (start 93.575 127.75) (end 94.45 128.625) (width 0.109) (layer "In6.Cu") (net 151))
  (segment (start 91.7625 127.75) (end 93.575 127.75) (width 0.109) (layer "In6.Cu") (net 151))
  (segment (start 107.311161 135.45) (end 107.311161 135.723034) (width 0.109) (layer "In6.Cu") (net 151))
  (segment (start 104.5 144) (end 104.5 138.534195) (width 0.109) (layer "In6.Cu") (net 151))
  (segment (start 108.3 147.2) (end 107.7 147.2) (width 0.109) (layer "In6.Cu") (net 151))
  (segment (start 91.64375 127.336023) (end 91.454968 127.147241) (width 0.109) (layer "In6.Cu") (net 151))
  (segment (start 97.9 135.75) (end 100.684195 138.534195) (width 0.109) (layer "In6.Cu") (net 151))
  (segment (start 91.64375 127.63125) (end 91.64375 127.336023) (width 0.109) (layer "In6.Cu") (net 151))
  (segment (start 91.64375 127.63125) (end 91.7625 127.75) (width 0.109) (layer "In6.Cu") (net 151))
  (segment (start 100.684195 138.534195) (end 104.5 138.534195) (width 0.109) (layer "In6.Cu") (net 151))
  (segment (start 97.9 132.875) (end 97.9 135.75) (width 0.109) (layer "In6.Cu") (net 151))
  (segment (start 107.7 147.2) (end 104.5 144) (width 0.109) (layer "In6.Cu") (net 151))
  (segment (start 94.45 128.625) (end 94.45 129.425) (width 0.109) (layer "In6.Cu") (net 151))
  (segment (start 90.7865 123.019) (end 91.1715 122.708999) (width 0.182) (layer "F.Cu") (net 152))
  (segment (start 173.3 142.75) (end 173.3 142.3175) (width 0.182) (layer "F.Cu") (net 152))
  (segment (start 171.79 142.95) (end 173.1 142.95) (width 0.182) (layer "F.Cu") (net 152))
  (segment (start 173.302 142.285) (end 173.302 141.513) (width 0.182) (layer "F.Cu") (net 152))
  (segment (start 172.955 140.855) (end 172.955 139.45) (width 0.182) (layer "F.Cu") (net 152))
  (segment (start 173.3 141.4825) (end 173.3 141.2) (width 0.182) (layer "F.Cu") (net 152))
  (segment (start 173.1 142.95) (end 173.3 142.75) (width 0.182) (layer "F.Cu") (net 152))
  (segment (start 173.3 141.2) (end 172.955 140.855) (width 0.182) (layer "F.Cu") (net 152))
  (segment (start 170.48 144.26) (end 171.79 142.95) (width 0.182) (layer "F.Cu") (net 152))
  (via (at 91.1715 122.708999) (size 0.45) (drill 0.1) (layers "F.Cu" "B.Cu") (net 152))
  (via (at 172.955 139.45) (size 0.45) (drill 0.1) (layers "F.Cu" "B.Cu") (net 152))
  (segment (start 111.908413 125.883413) (end 124.4 138.375) (width 0.109) (layer "In6.Cu") (net 152))
  (segment (start 94.55 122.05) (end 98.383413 125.883413) (width 0.109) (layer "In6.Cu") (net 152))
  (segment (start 91.1665 122.708999) (end 91.575499 122.3) (width 0.109) (layer "In6.Cu") (net 152))
  (segment (start 152.96 134.25) (end 155.17 136.46) (width 0.109) (layer "In6.Cu") (net 152))
  (segment (start 92.15 122.3) (end 92.4 122.05) (width 0.109) (layer "In6.Cu") (net 152))
  (segment (start 162.8 136.95) (end 164.51 138.66) (width 0.109) (layer "In6.Cu") (net 152))
  (segment (start 98.383413 125.883413) (end 111.908413 125.883413) (width 0.109) (layer "In6.Cu") (net 152))
  (segment (start 164.51 138.66) (end 169.829998 138.66) (width 0.109) (layer "In6.Cu") (net 152))
  (segment (start 170.289998 139.12) (end 172.625 139.12) (width 0.109) (layer "In6.Cu") (net 152))
  (segment (start 124.4 138.375) (end 138 138.375) (width 0.109) (layer "In6.Cu") (net 152))
  (segment (start 159.51 136.46) (end 160 136.95) (width 0.109) (layer "In6.Cu") (net 152))
  (segment (start 92.4 122.05) (end 94.55 122.05) (width 0.109) (layer "In6.Cu") (net 152))
  (segment (start 172.625 139.12) (end 172.955 139.45) (width 0.109) (layer "In6.Cu") (net 152))
  (segment (start 160 136.95) (end 162.8 136.95) (width 0.109) (layer "In6.Cu") (net 152))
  (segment (start 155.17 136.46) (end 159.51 136.46) (width 0.109) (layer "In6.Cu") (net 152))
  (segment (start 169.829998 138.66) (end 170.289998 139.12) (width 0.109) (layer "In6.Cu") (net 152))
  (segment (start 91.575499 122.3) (end 92.15 122.3) (width 0.109) (layer "In6.Cu") (net 152))
  (segment (start 138 138.375) (end 142.125 134.25) (width 0.109) (layer "In6.Cu") (net 152))
  (segment (start 142.125 134.25) (end 152.96 134.25) (width 0.109) (layer "In6.Cu") (net 152))
  (segment (start 95.565 134.585) (end 95.55 134.6) (width 0.182) (layer "F.Cu") (net 153))
  (segment (start 96.95 134.585) (end 95.565 134.585) (width 0.182) (layer "F.Cu") (net 153))
  (segment (start 102.65 147.15) (end 102.65 148.7492) (width 0.109) (layer "F.Cu") (net 153))
  (segment (start 103.85 145.95) (end 102.65 147.15) (width 0.109) (layer "F.Cu") (net 153))
  (segment (start 90.3 120.795) (end 90.7865 120.479) (width 0.182) (layer "F.Cu") (net 153))
  (segment (start 103.85 145.35) (end 103.85 145.95) (width 0.109) (layer "F.Cu") (net 153))
  (via (at 95.55 134.6) (size 0.45) (drill 0.1) (layers "F.Cu" "B.Cu") (net 153))
  (via (at 90.3 120.795) (size 0.45) (drill 0.1) (layers "F.Cu" "B.Cu") (net 153))
  (via (at 103.85 145.35) (size 0.45) (drill 0.1) (layers "F.Cu" "B.Cu") (net 153))
  (segment (start 95.55 134.6) (end 95.05 135.1) (width 0.109) (layer "In2.Cu") (net 153))
  (segment (start 95.05 135.1) (end 95.05 136.5) (width 0.109) (layer "In2.Cu") (net 153))
  (segment (start 93.78 120.3) (end 90.795 120.3) (width 0.109) (layer "In2.Cu") (net 153))
  (segment (start 102.42 143.92) (end 103.85 145.35) (width 0.109) (layer "In2.Cu") (net 153))
  (segment (start 95.05 136.5) (end 95.85 137.3) (width 0.109) (layer "In2.Cu") (net 153))
  (segment (start 95.55 134.6) (end 95.55 132.45) (width 0.109) (layer "In2.Cu") (net 153))
  (segment (start 102.42 141.87) (end 102.42 143.92) (width 0.109) (layer "In2.Cu") (net 153))
  (segment (start 94.41 121.821663) (end 94.12 121.531663) (width 0.109) (layer "In2.Cu") (net 153))
  (segment (start 90.795 120.3) (end 90.3 120.795) (width 0.109) (layer "In2.Cu") (net 153))
  (segment (start 94.12 121.531663) (end 94.12 120.64) (width 0.109) (layer "In2.Cu") (net 153))
  (segment (start 95.55 132.45) (end 95.15 132.05) (width 0.109) (layer "In2.Cu") (net 153))
  (segment (start 97.85 137.3) (end 102.42 141.87) (width 0.109) (layer "In2.Cu") (net 153))
  (segment (start 94.12 120.64) (end 93.78 120.3) (width 0.109) (layer "In2.Cu") (net 153))
  (segment (start 94.41 125.71) (end 94.41 121.821663) (width 0.109) (layer "In2.Cu") (net 153))
  (segment (start 95.85 137.3) (end 97.85 137.3) (width 0.109) (layer "In2.Cu") (net 153))
  (segment (start 95.15 126.45) (end 94.41 125.71) (width 0.109) (layer "In2.Cu") (net 153))
  (segment (start 95.15 132.05) (end 95.15 126.45) (width 0.109) (layer "In2.Cu") (net 153))
  (segment (start 120.895 96.7629) (end 120.895 96.045) (width 0.182) (layer "F.Cu") (net 154))
  (segment (start 120.895 96.045) (end 120.815 95.965) (width 0.182) (layer "F.Cu") (net 154))
  (via (at 120.815 95.965) (size 0.45) (drill 0.1) (layers "F.Cu" "B.Cu") (net 154))
  (segment (start 120.699 96.101) (end 120.699 96.659) (width 0.4) (layer "B.Cu") (net 154))
  (segment (start 120.815 95.965) (end 120.815 95.985) (width 0.4) (layer "B.Cu") (net 154))
  (segment (start 120.815 95.985) (end 120.699 96.101) (width 0.4) (layer "B.Cu") (net 154))
  (segment (start 89.4415 124.599) (end 89.8265 124.289) (width 0.182) (layer "F.Cu") (net 155))
  (via (at 174.674998 140.32) (size 0.45) (drill 0.1) (layers "F.Cu" "B.Cu") (net 155))
  (via (at 89.4415 124.599) (size 0.45) (drill 0.1) (layers "F.Cu" "B.Cu") (net 155))
  (segment (start 174.437152 140.32) (end 174.674998 140.32) (width 0.109) (layer "In6.Cu") (net 155))
  (segment (start 157.15 140.31) (end 157.76 139.7) (width 0.109) (layer "In6.Cu") (net 155))
  (segment (start 94.95 125.85) (end 94.95 126.775) (width 0.109) (layer "In6.Cu") (net 155))
  (segment (start 142.475 138.6) (end 147.73 138.6) (width 0.109) (layer "In6.Cu") (net 155))
  (segment (start 93.1125 124.8625) (end 93.9625 124.8625) (width 0.109) (layer "In6.Cu") (net 155))
  (segment (start 89.8455 124.2) (end 92.45 124.2) (width 0.109) (layer "In6.Cu") (net 155))
  (segment (start 89.4465 124.599) (end 89.8455 124.2) (width 0.109) (layer "In6.Cu") (net 155))
  (segment (start 149.44 140.31) (end 157.15 140.31) (width 0.109) (layer "In6.Cu") (net 155))
  (segment (start 121.405 141.08) (end 139.995 141.08) (width 0.109) (layer "In6.Cu") (net 155))
  (segment (start 166.73 140.87) (end 166.98 140.62) (width 0.109) (layer "In6.Cu") (net 155))
  (segment (start 110.05 129.725) (end 121.405 141.08) (width 0.109) (layer "In6.Cu") (net 155))
  (segment (start 94.95 126.775) (end 97.9 129.725) (width 0.109) (layer "In6.Cu") (net 155))
  (segment (start 166.98 140.62) (end 170.4 140.62) (width 0.109) (layer "In6.Cu") (net 155))
  (segment (start 162.98 140.87) (end 166.73 140.87) (width 0.109) (layer "In6.Cu") (net 155))
  (segment (start 157.76 139.7) (end 161.81 139.7) (width 0.109) (layer "In6.Cu") (net 155))
  (segment (start 97.9 129.725) (end 110.05 129.725) (width 0.109) (layer "In6.Cu") (net 155))
  (segment (start 92.45 124.2) (end 93.1125 124.8625) (width 0.109) (layer "In6.Cu") (net 155))
  (segment (start 170.4 140.62) (end 171.24599 141.46599) (width 0.109) (layer "In6.Cu") (net 155))
  (segment (start 93.9625 124.8625) (end 94.95 125.85) (width 0.109) (layer "In6.Cu") (net 155))
  (segment (start 171.24599 141.46599) (end 173.291162 141.46599) (width 0.109) (layer "In6.Cu") (net 155))
  (segment (start 147.73 138.6) (end 149.44 140.31) (width 0.109) (layer "In6.Cu") (net 155))
  (segment (start 173.291162 141.46599) (end 174.437152 140.32) (width 0.109) (layer "In6.Cu") (net 155))
  (segment (start 161.81 139.7) (end 162.98 140.87) (width 0.109) (layer "In6.Cu") (net 155))
  (segment (start 139.995 141.08) (end 142.475 138.6) (width 0.109) (layer "In6.Cu") (net 155))
  (segment (start 174.413012 143.609907) (end 174.413012 145.653012) (width 0.182) (layer "B.Cu") (net 155))
  (segment (start 174.686428 140.33143) (end 174.674998 140.32) (width 0.182) (layer "B.Cu") (net 155))
  (segment (start 174.686428 140.957279) (end 174.686428 140.33143) (width 0.182) (layer "B.Cu") (net 155))
  (segment (start 174.8 142.3175) (end 174.8 143.222919) (width 0.182) (layer "B.Cu") (net 155))
  (segment (start 174.8 143.222919) (end 174.413012 143.609907) (width 0.182) (layer "B.Cu") (net 155))
  (segment (start 174.8 141.4825) (end 174.8 141.070851) (width 0.182) (layer "B.Cu") (net 155))
  (segment (start 174.8 142.287) (end 174.8 141.515) (width 0.182) (layer "B.Cu") (net 155))
  (segment (start 174.8 141.070851) (end 174.686428 140.957279) (width 0.182) (layer "B.Cu") (net 155))
  (segment (start 174.413012 145.653012) (end 175.56 146.8) (width 0.182) (layer "B.Cu") (net 155))
  (segment (start 89.8265 123.654) (end 90.16001 123.32049) (width 0.182) (layer "F.Cu") (net 156))
  (segment (start 90.16001 123.32049) (end 90.3 123.32049) (width 0.182) (layer "F.Cu") (net 156))
  (via (at 90.3 123.32049) (size 0.45) (drill 0.1) (layers "F.Cu" "B.Cu") (net 156))
  (via (at 173.458109 140.683545) (size 0.45) (drill 0.1) (layers "F.Cu" "B.Cu") (net 156))
  (segment (start 152 138.9) (end 150.2 137.1) (width 0.109) (layer "In6.Cu") (net 156))
  (segment (start 122.705 139.98) (end 110.95 128.225) (width 0.109) (layer "In6.Cu") (net 156))
  (segment (start 159.414892 138.5) (end 159.014892 138.9) (width 0.109) (layer "In6.Cu") (net 156))
  (segment (start 173.458109 140.683545) (end 173.147087 140.372523) (width 0.109) (layer "In6.Cu") (net 156))
  (segment (start 96.15 126.225) (end 96.15 125.65) (width 0.109) (layer "In6.Cu") (net 156))
  (segment (start 162.04 138.5) (end 159.414892 138.5) (width 0.109) (layer "In6.Cu") (net 156))
  (segment (start 93.375 124.275) (end 92.825 123.725) (width 0.109) (layer "In6.Cu") (net 156))
  (segment (start 142.075 137.1) (end 139.195 139.98) (width 0.109) (layer "In6.Cu") (net 156))
  (segment (start 139.195 139.98) (end 122.705 139.98) (width 0.109) (layer "In6.Cu") (net 156))
  (segment (start 90.70451 123.725) (end 90.3 123.32049) (width 0.109) (layer "In6.Cu") (net 156))
  (segment (start 171.592523 140.372523) (end 171.22 140) (width 0.109) (layer "In6.Cu") (net 156))
  (segment (start 150.2 137.1) (end 142.075 137.1) (width 0.109) (layer "In6.Cu") (net 156))
  (segment (start 96.15 125.65) (end 94.775 124.275) (width 0.109) (layer "In6.Cu") (net 156))
  (segment (start 98.15 128.225) (end 96.15 126.225) (width 0.109) (layer "In6.Cu") (net 156))
  (segment (start 159.014892 138.9) (end 152 138.9) (width 0.109) (layer "In6.Cu") (net 156))
  (segment (start 92.825 123.725) (end 90.70451 123.725) (width 0.109) (layer "In6.Cu") (net 156))
  (segment (start 163.36 139.82) (end 162.04 138.5) (width 0.109) (layer "In6.Cu") (net 156))
  (segment (start 173.147087 140.372523) (end 171.592523 140.372523) (width 0.109) (layer "In6.Cu") (net 156))
  (segment (start 94.775 124.275) (end 93.375 124.275) (width 0.109) (layer "In6.Cu") (net 156))
  (segment (start 171.22 140) (end 168.77 140) (width 0.109) (layer "In6.Cu") (net 156))
  (segment (start 168.77 140) (end 168.59 139.82) (width 0.109) (layer "In6.Cu") (net 156))
  (segment (start 110.95 128.225) (end 98.15 128.225) (width 0.109) (layer "In6.Cu") (net 156))
  (segment (start 168.59 139.82) (end 163.36 139.82) (width 0.109) (layer "In6.Cu") (net 156))
  (segment (start 173.802 142.287) (end 173.802 141.515) (width 0.182) (layer "B.Cu") (net 156))
  (segment (start 173.8 143.247859) (end 174.131001 143.57886) (width 0.182) (layer "B.Cu") (net 156))
  (segment (start 173.8 142.3175) (end 173.8 143.247859) (width 0.182) (layer "B.Cu") (net 156))
  (segment (start 173.8 141.4825) (end 173.8 141.025436) (width 0.182) (layer "B.Cu") (net 156))
  (segment (start 173.8 141.025436) (end 173.458109 140.683545) (width 0.182) (layer "B.Cu") (net 156))
  (segment (start 174.131001 145.688999) (end 173.02 146.8) (width 0.182) (layer "B.Cu") (net 156))
  (segment (start 174.131001 143.57886) (end 174.131001 145.688999) (width 0.182) (layer "B.Cu") (net 156))
  (segment (start 89.52501 123.32049) (end 89.4415 123.32049) (width 0.182) (layer "F.Cu") (net 157))
  (segment (start 89.8265 123.019) (end 89.52501 123.32049) (width 0.182) (layer "F.Cu") (net 157))
  (via (at 172.53899 140.752033) (size 0.45) (drill 0.1) (layers "F.Cu" "B.Cu") (net 157))
  (via (at 89.4415 123.32049) (size 0.45) (drill 0.1) (layers "F.Cu" "B.Cu") (net 157))
  (segment (start 161.9 139.1) (end 163.1 140.3) (width 0.109) (layer "In6.Cu") (net 157))
  (segment (start 139.695 140.48) (end 142.275 137.9) (width 0.109) (layer "In6.Cu") (net 157))
  (segment (start 157 139.6) (end 157.35 139.25) (width 0.109) (layer "In6.Cu") (net 157))
  (segment (start 159.604891 139.1) (end 161.9 139.1) (width 0.109) (layer "In6.Cu") (net 157))
  (segment (start 94.325 124.575) (end 95.55 125.8) (width 0.109) (layer "In6.Cu") (net 157))
  (segment (start 122.055 140.48) (end 139.695 140.48) (width 0.109) (layer "In6.Cu") (net 157))
  (segment (start 93.225 124.575) (end 94.325 124.575) (width 0.109) (layer "In6.Cu") (net 157))
  (segment (start 92.584011 123.934011) (end 93.225 124.575) (width 0.109) (layer "In6.Cu") (net 157))
  (segment (start 157.35 139.25) (end 159.454891 139.25) (width 0.109) (layer "In6.Cu") (net 157))
  (segment (start 97.95 128.925) (end 110.5 128.925) (width 0.109) (layer "In6.Cu") (net 157))
  (segment (start 170.72 140.3) (end 171.172033 140.752033) (width 0.109) (layer "In6.Cu") (net 157))
  (segment (start 95.55 125.8) (end 95.55 126.525) (width 0.109) (layer "In6.Cu") (net 157))
  (segment (start 163.1 140.3) (end 170.72 140.3) (width 0.109) (layer "In6.Cu") (net 157))
  (segment (start 159.454891 139.25) (end 159.604891 139.1) (width 0.109) (layer "In6.Cu") (net 157))
  (segment (start 142.275 137.9) (end 148.8 137.9) (width 0.109) (layer "In6.Cu") (net 157))
  (segment (start 90.051511 123.934011) (end 92.584011 123.934011) (width 0.109) (layer "In6.Cu") (net 157))
  (segment (start 148.8 137.9) (end 150.5 139.6) (width 0.109) (layer "In6.Cu") (net 157))
  (segment (start 95.55 126.525) (end 97.95 128.925) (width 0.109) (layer "In6.Cu") (net 157))
  (segment (start 150.5 139.6) (end 157 139.6) (width 0.109) (layer "In6.Cu") (net 157))
  (segment (start 89.4465 123.329) (end 90.051511 123.934011) (width 0.109) (layer "In6.Cu") (net 157))
  (segment (start 110.5 128.925) (end 122.055 140.48) (width 0.109) (layer "In6.Cu") (net 157))
  (segment (start 171.172033 140.752033) (end 172.53899 140.752033) (width 0.109) (layer "In6.Cu") (net 157))
  (segment (start 172.852033 140.752033) (end 172.53899 140.752033) (width 0.182) (layer "B.Cu") (net 157))
  (segment (start 173.3 142.75) (end 173.3 142.3175) (width 0.182) (layer "B.Cu") (net 157))
  (segment (start 171.75 143.65) (end 172.45 142.95) (width 0.182) (layer "B.Cu") (net 157))
  (segment (start 173.1 142.95) (end 173.3 142.75) (width 0.182) (layer "B.Cu") (net 157))
  (segment (start 173.302 142.287) (end 173.302 141.515) (width 0.182) (layer "B.Cu") (net 157))
  (segment (start 170.48 146.8) (end 171.75 145.53) (width 0.182) (layer "B.Cu") (net 157))
  (segment (start 172.45 142.95) (end 173.1 142.95) (width 0.182) (layer "B.Cu") (net 157))
  (segment (start 171.75 145.53) (end 171.75 143.65) (width 0.182) (layer "B.Cu") (net 157))
  (segment (start 173.3 141.4825) (end 173.3 141.2) (width 0.182) (layer "B.Cu") (net 157))
  (segment (start 173.3 141.2) (end 172.852033 140.752033) (width 0.182) (layer "B.Cu") (net 157))
  (segment (start 153.1 117.1) (end 152.135 117.1) (width 0.182) (layer "F.Cu") (net 158))
  (segment (start 154.125 118.125) (end 153.1 117.1) (width 0.182) (layer "F.Cu") (net 158))
  (segment (start 154.125 125.775) (end 154.125 118.125) (width 0.182) (layer "F.Cu") (net 158))
  (segment (start 149.882843 128.533096) (end 151.366904 128.533096) (width 0.182) (layer "F.Cu") (net 158))
  (segment (start 151.366904 128.533096) (end 154.125 125.775) (width 0.182) (layer "F.Cu") (net 158))
  (segment (start 143.39 120.165) (end 143.525 120.3) (width 0.182) (layer "F.Cu") (net 159))
  (segment (start 141.600659 123.079341) (end 142.025 122.655) (width 0.182) (layer "F.Cu") (net 159))
  (segment (start 137.625 128.575) (end 137.8 128.4) (width 0.182) (layer "F.Cu") (net 159))
  (segment (start 142.025 122.655) (end 142.025 122.155) (width 0.182) (layer "F.Cu") (net 159))
  (segment (start 138.873159 123.926841) (end 140.351841 123.926841) (width 0.182) (layer "F.Cu") (net 159))
  (segment (start 138.3 127.5) (end 138.3 124.5) (width 0.182) (layer "F.Cu") (net 159))
  (segment (start 143.525 120.3) (end 144.359 120.3) (width 0.182) (layer "F.Cu") (net 159))
  (segment (start 141.199341 123.079341) (end 141.600659 123.079341) (width 0.182) (layer "F.Cu") (net 159))
  (segment (start 135.7508 130.0492) (end 136.6 129.2) (width 0.182) (layer "F.Cu") (net 159))
  (segment (start 138.3 124.5) (end 138.873159 123.926841) (width 0.182) (layer "F.Cu") (net 159))
  (segment (start 136.6 129.2) (end 136.6 129.025) (width 0.182) (layer "F.Cu") (net 159))
  (segment (start 137.8 128.4) (end 137.8 128) (width 0.182) (layer "F.Cu") (net 159))
  (segment (start 140.351841 123.926841) (end 141.199341 123.079341) (width 0.182) (layer "F.Cu") (net 159))
  (segment (start 137.05 128.575) (end 137.625 128.575) (width 0.182) (layer "F.Cu") (net 159))
  (segment (start 136.6 129.025) (end 137.05 128.575) (width 0.182) (layer "F.Cu") (net 159))
  (segment (start 137.8 128) (end 138.3 127.5) (width 0.182) (layer "F.Cu") (net 159))
  (segment (start 135.75 130.0492) (end 135.7508 130.0492) (width 0.182) (layer "F.Cu") (net 159))
  (segment (start 143.39 120.79) (end 143.39 120.165) (width 0.182) (layer "F.Cu") (net 159))
  (segment (start 142.025 122.155) (end 143.39 120.79) (width 0.182) (layer "F.Cu") (net 159))
  (segment (start 135.75 123.675) (end 135.75 124.025) (width 0.182) (layer "F.Cu") (net 160))
  (segment (start 135.75 124.1) (end 135.75 124.875) (width 0.182) (layer "F.Cu") (net 160))
  (segment (start 135.75 124.025) (end 135.75 124.1) (width 0.182) (layer "F.Cu") (net 160))
  (segment (start 136.115 123.275) (end 136.115 123.31) (width 0.182) (layer "F.Cu") (net 160))
  (segment (start 136.115 123.31) (end 135.75 123.675) (width 0.182) (layer "F.Cu") (net 160))
  (segment (start 138.425 118.575) (end 138.625 118.375) (width 0.182) (layer "F.Cu") (net 160))
  (segment (start 134.75 124.9) (end 135.724999 124.9) (width 0.182) (layer "F.Cu") (net 160))
  (segment (start 138.825 121.995) (end 138.825 122.575) (width 0.182) (layer "F.Cu") (net 160))
  (segment (start 136.3 122.5) (end 136.115 122.685) (width 0.182) (layer "F.Cu") (net 160))
  (segment (start 138.325 122.975) (end 137.85 122.5) (width 0.182) (layer "F.Cu") (net 160))
  (segment (start 135.724999 124.9) (end 135.75 124.874999) (width 0.182) (layer "F.Cu") (net 160))
  (segment (start 137.98 117.525) (end 137.35 117.525) (width 0.182) (layer "F.Cu") (net 160))
  (segment (start 137.775 118.575) (end 138.425 118.575) (width 0.182) (layer "F.Cu") (net 160))
  (segment (start 137.325 117.55) (end 137.325 118.125) (width 0.182) (layer "F.Cu") (net 160))
  (segment (start 136.115 122.685) (end 136.115 123.275) (width 0.182) (layer "F.Cu") (net 160))
  (segment (start 138.625 118.375) (end 138.625 117.72) (width 0.182) (layer "F.Cu") (net 160))
  (segment (start 138.425 122.975) (end 138.325 122.975) (width 0.182) (layer "F.Cu") (net 160))
  (segment (start 137.325 118.125) (end 137.775 118.575) (width 0.182) (layer "F.Cu") (net 160))
  (segment (start 137.35 117.525) (end 137.325 117.55) (width 0.182) (layer "F.Cu") (net 160))
  (segment (start 137.85 122.5) (end 136.3 122.5) (width 0.182) (layer "F.Cu") (net 160))
  (segment (start 138.825 122.575) (end 138.425 122.975) (width 0.182) (layer "F.Cu") (net 160))
  (via (at 137.775 118.575) (size 0.45) (drill 0.1) (layers "F.Cu" "B.Cu") (net 160))
  (via (at 138.325 122.975) (size 0.45) (drill 0.1) (layers "F.Cu" "B.Cu") (net 160))
  (segment (start 138.325 120.525) (end 137.775 119.975) (width 0.109) (layer "In6.Cu") (net 160))
  (segment (start 137.775 119.975) (end 137.775 118.575) (width 0.109) (layer "In6.Cu") (net 160))
  (segment (start 138.325 122.975) (end 138.325 120.525) (width 0.109) (layer "In6.Cu") (net 160))
  (segment (start 107.775 143.53) (end 107.775 143) (width 0.182) (layer "F.Cu") (net 161))
  (segment (start 106.75 142.7) (end 106.95 142.5) (width 0.182) (layer "F.Cu") (net 161))
  (segment (start 105.575 141.675) (end 105.575 141.875) (width 0.182) (layer "F.Cu") (net 161))
  (segment (start 105.85 142.7) (end 106.75 142.7) (width 0.182) (layer "F.Cu") (net 161))
  (segment (start 106.505 141.2) (end 106.05 141.2) (width 0.182) (layer "F.Cu") (net 161))
  (segment (start 107.15 142.7) (end 106.95 142.5) (width 0.182) (layer "F.Cu") (net 161))
  (segment (start 106.05 141.2) (end 105.575 141.675) (width 0.182) (layer "F.Cu") (net 161))
  (segment (start 107.775 143) (end 107.475 142.7) (width 0.182) (layer "F.Cu") (net 161))
  (segment (start 105.575 141.875) (end 105.575 142.425) (width 0.182) (layer "F.Cu") (net 161))
  (segment (start 107.475 142.7) (end 107.15 142.7) (width 0.182) (layer "F.Cu") (net 161))
  (segment (start 105.575 142.425) (end 105.725 142.575) (width 0.182) (layer "F.Cu") (net 161))
  (segment (start 104.491198 138.54) (end 106.96 138.54) (width 0.182) (layer "F.Cu") (net 161))
  (segment (start 106.95 141.96) (end 107.15 141.76) (width 0.182) (layer "F.Cu") (net 161))
  (segment (start 103.3 141.682) (end 103.3 139.731198) (width 0.182) (layer "F.Cu") (net 161))
  (segment (start 107.796978 137.446978) (end 107.796978 137.653022) (width 0.182) (layer "F.Cu") (net 161))
  (segment (start 109.575 138.05) (end 108.193956 138.05) (width 0.182) (layer "F.Cu") (net 161))
  (segment (start 107.7 137.8) (end 107.796978 137.703022) (width 0.182) (layer "F.Cu") (net 161))
  (segment (start 110.125 137.225001) (end 110.125 137.5) (width 0.182) (layer "F.Cu") (net 161))
  (segment (start 107.9 137.8) (end 107.921978 137.778022) (width 0.182) (layer "F.Cu") (net 161))
  (segment (start 106.96 138.54) (end 107.7 137.8) (width 0.182) (layer "F.Cu") (net 161))
  (segment (start 105.1 147.0492) (end 105.1 143.2) (width 0.182) (layer "F.Cu") (net 161))
  (segment (start 110.500001 136.85) (end 110.125 137.225001) (width 0.182) (layer "F.Cu") (net 161))
  (segment (start 108.193956 138.05) (end 107.921978 137.778022) (width 0.182) (layer "F.Cu") (net 161))
  (segment (start 105.1 143.2) (end 105.725 142.575) (width 0.182) (layer "F.Cu") (net 161))
  (segment (start 107.921978 137.778022) (end 107.796978 137.653022) (width 0.182) (layer "F.Cu") (net 161))
  (segment (start 103.493 141.875) (end 103.3 141.682) (width 0.182) (layer "F.Cu") (net 161))
  (segment (start 106.95 142.5) (end 106.95 141.96) (width 0.182) (layer "F.Cu") (net 161))
  (segment (start 107.796978 137.703022) (end 107.796978 137.653022) (width 0.182) (layer "F.Cu") (net 161))
  (segment (start 107.7 137.8) (end 107.9 137.8) (width 0.182) (layer "F.Cu") (net 161))
  (segment (start 107.15 141.76) (end 107.15 141.395) (width 0.182) (layer "F.Cu") (net 161))
  (segment (start 110.125 137.5) (end 109.575 138.05) (width 0.182) (layer "F.Cu") (net 161))
  (segment (start 105.575 141.875) (end 103.493 141.875) (width 0.182) (layer "F.Cu") (net 161))
  (segment (start 103.3 139.731198) (end 104.491198 138.54) (width 0.182) (layer "F.Cu") (net 161))
  (segment (start 105.725 142.575) (end 105.85 142.7) (width 0.182) (layer "F.Cu") (net 161))
  (segment (start 105.08 147.0692) (end 105.1 147.0492) (width 0.182) (layer "F.Cu") (net 161))
  (segment (start 107.2 136.85) (end 107.796978 137.446978) (width 0.182) (layer "F.Cu") (net 161))
  (segment (start 104.4 136.8) (end 104.399997 136.800003) (width 0.182) (layer "F.Cu") (net 162))
  (segment (start 104.4 136.0954) (end 104.4 136.8) (width 0.182) (layer "F.Cu") (net 162))
  (segment (start 101.85 134.585) (end 103.135 134.585) (width 0.182) (layer "F.Cu") (net 162))
  (segment (start 103.135 134.585) (end 103.15 134.6) (width 0.182) (layer "F.Cu") (net 162))
  (segment (start 98.9 137.2492) (end 98.9 135.8) (width 0.182) (layer "F.Cu") (net 162))
  (segment (start 99.925 134.775) (end 101.66 134.775) (width 0.182) (layer "F.Cu") (net 162))
  (segment (start 101.66 134.775) (end 101.85 134.585) (width 0.182) (layer "F.Cu") (net 162))
  (segment (start 98.9 135.8) (end 99.925 134.775) (width 0.182) (layer "F.Cu") (net 162))
  (via (at 104.399997 136.800003) (size 0.45) (drill 0.1) (layers "F.Cu" "B.Cu") (net 162))
  (via (at 103.15 134.6) (size 0.45) (drill 0.1) (layers "F.Cu" "B.Cu") (net 162))
  (segment (start 103.15 134.6) (end 103.15 134.95) (width 0.109) (layer "In6.Cu") (net 162))
  (segment (start 104.399997 136.199997) (end 104.399997 136.800003) (width 0.109) (layer "In6.Cu") (net 162))
  (segment (start 103.15 134.95) (end 104.399997 136.199997) (width 0.109) (layer "In6.Cu") (net 162))
  (segment (start 103.15 134.6) (end 103.15 134.7) (width 0.182) (layer "B.Cu") (net 162))
  (segment (start 102.9 135.2) (end 103.15 134.95) (width 0.4) (layer "B.Cu") (net 162))
  (segment (start 102.335 135.2) (end 102.9 135.2) (width 0.4) (layer "B.Cu") (net 162))
  (segment (start 103.15 134.95) (end 103.15 134.6) (width 0.4) (layer "B.Cu") (net 162))
  (segment (start 101.905 135.8) (end 101.85 135.855) (width 0.182) (layer "F.Cu") (net 163))
  (segment (start 103.15 135.8) (end 101.905 135.8) (width 0.182) (layer "F.Cu") (net 163))
  (segment (start 103.35 136.7) (end 103.5 136.85) (width 0.182) (layer "F.Cu") (net 163))
  (segment (start 103.15 135.8) (end 103.15 136.2) (width 0.182) (layer "F.Cu") (net 163))
  (segment (start 103.75 136.85) (end 103.899999 136.700001) (width 0.182) (layer "F.Cu") (net 163))
  (segment (start 103.5 136.85) (end 103.75 136.85) (width 0.182) (layer "F.Cu") (net 163))
  (segment (start 100.8 136.2) (end 100.8 136.4492) (width 0.182) (layer "F.Cu") (net 163))
  (segment (start 103.35 136.4) (end 103.35 136.7) (width 0.182) (layer "F.Cu") (net 163))
  (segment (start 100.8 136.4492) (end 100 137.2492) (width 0.182) (layer "F.Cu") (net 163))
  (segment (start 101.85 135.855) (end 101.145 135.855) (width 0.182) (layer "F.Cu") (net 163))
  (segment (start 101.145 135.855) (end 100.8 136.2) (width 0.182) (layer "F.Cu") (net 163))
  (segment (start 103.15 136.2) (end 103.35 136.4) (width 0.182) (layer "F.Cu") (net 163))
  (segment (start 103.899999 136.700001) (end 103.899999 136.0954) (width 0.182) (layer "F.Cu") (net 163))
  (via (at 103.15 135.8) (size 0.45) (drill 0.1) (layers "F.Cu" "B.Cu") (net 163))
  (segment (start 102.335 136.05) (end 102.9 136.05) (width 0.4) (layer "B.Cu") (net 163))
  (segment (start 102.9 136.05) (end 103.15 135.8) (width 0.4) (layer "B.Cu") (net 163))
  (segment (start 139.726787 126.224767) (end 139.000233 126.224767) (width 0.182) (layer "F.Cu") (net 164))
  (segment (start 145.46 114.13) (end 145.46 114.425) (width 0.182) (layer "F.Cu") (net 164))
  (segment (start 144.525 113.225) (end 144.843198 113.225) (width 0.182) (layer "F.Cu") (net 164))
  (segment (start 144.843198 113.225) (end 145.299 113.680802) (width 0.182) (layer "F.Cu") (net 164))
  (segment (start 139.000233 126.224767) (end 138.775 126.45) (width 0.182) (layer "F.Cu") (net 164))
  (segment (start 145.299 113.969) (end 145.46 114.13) (width 0.182) (layer "F.Cu") (net 164))
  (segment (start 145.299 113.680802) (end 145.299 113.969) (width 0.182) (layer "F.Cu") (net 164))
  (via (at 144.525 113.225) (size 0.45) (drill 0.1) (layers "F.Cu" "B.Cu") (net 164))
  (via (at 138.775 126.45) (size 0.45) (drill 0.1) (layers "F.Cu" "B.Cu") (net 164))
  (segment (start 141.354501 114.670499) (end 142.8 113.225) (width 0.109) (layer "In6.Cu") (net 164))
  (segment (start 138.775 126.45) (end 141.095499 124.129501) (width 0.109) (layer "In6.Cu") (net 164))
  (segment (start 141.095499 122.195161) (end 140.775 121.874662) (width 0.109) (layer "In6.Cu") (net 164))
  (segment (start 140.775 115.786662) (end 141.354501 115.207161) (width 0.109) (layer "In6.Cu") (net 164))
  (segment (start 142.8 113.225) (end 144.525 113.225) (width 0.109) (layer "In6.Cu") (net 164))
  (segment (start 140.775 121.874662) (end 140.775 115.786662) (width 0.109) (layer "In6.Cu") (net 164))
  (segment (start 141.095499 124.129501) (end 141.095499 122.195161) (width 0.109) (layer "In6.Cu") (net 164))
  (segment (start 141.354501 115.207161) (end 141.354501 114.670499) (width 0.109) (layer "In6.Cu") (net 164))
  (segment (start 145.053 122.953) (end 145.053 122.156) (width 0.182) (layer "F.Cu") (net 165))
  (segment (start 143.949916 125.167314) (end 143.949916 124.056084) (width 0.182) (layer "F.Cu") (net 165))
  (segment (start 143.949916 124.056084) (end 145.053 122.953) (width 0.182) (layer "F.Cu") (net 165))
  (segment (start 144.385 121.5) (end 144.175 121.5) (width 0.182) (layer "F.Cu") (net 166))
  (segment (start 143.549916 122.125084) (end 143.549916 125.167314) (width 0.182) (layer "F.Cu") (net 166))
  (segment (start 144.175 121.5) (end 143.549916 122.125084) (width 0.182) (layer "F.Cu") (net 166))
  (segment (start 144.385 121.1) (end 144.055 121.1) (width 0.182) (layer "F.Cu") (net 167))
  (segment (start 142.175 124.055) (end 141.3 124.055) (width 0.182) (layer "F.Cu") (net 167))
  (segment (start 143.073164 122.081836) (end 144.055 121.1) (width 0.182) (layer "F.Cu") (net 167))
  (segment (start 143.073164 123.156836) (end 142.175 124.055) (width 0.182) (layer "F.Cu") (net 167))
  (segment (start 141.3 124.055) (end 140.771787 124.583213) (width 0.182) (layer "F.Cu") (net 167))
  (segment (start 143.073164 122.081836) (end 143.073164 123.156836) (width 0.182) (layer "F.Cu") (net 167))
  (segment (start 140.771787 124.583213) (end 140.771787 125.179767) (width 0.182) (layer "F.Cu") (net 167))
  (segment (start 140.371787 124.433213) (end 141.251248 123.553752) (width 0.182) (layer "F.Cu") (net 168))
  (segment (start 142.55 122.127504) (end 143.926252 120.751252) (width 0.182) (layer "F.Cu") (net 168))
  (segment (start 141.901248 123.553752) (end 142.55 122.905) (width 0.182) (layer "F.Cu") (net 168))
  (segment (start 141.251248 123.553752) (end 141.901248 123.553752) (width 0.182) (layer "F.Cu") (net 168))
  (segment (start 140.371787 125.179767) (end 140.371787 124.433213) (width 0.182) (layer "F.Cu") (net 168))
  (segment (start 144.385 120.7) (end 143.977504 120.7) (width 0.182) (layer "F.Cu") (net 168))
  (segment (start 142.55 122.905) (end 142.55 122.127504) (width 0.182) (layer "F.Cu") (net 168))
  (segment (start 143.977504 120.7) (end 143.926252 120.751252) (width 0.182) (layer "F.Cu") (net 168))
  (segment (start 143.904728 119.881) (end 143.772718 119.74899) (width 0.182) (layer "F.Cu") (net 169))
  (segment (start 140.985 120.6) (end 140.67 120.6) (width 0.182) (layer "F.Cu") (net 169))
  (segment (start 143.772718 119.74899) (end 141.83601 119.74899) (width 0.182) (layer "F.Cu") (net 169))
  (segment (start 144.378 119.881) (end 143.904728 119.881) (width 0.182) (layer "F.Cu") (net 169))
  (segment (start 141.83601 119.74899) (end 140.985 120.6) (width 0.182) (layer "F.Cu") (net 169))
  (via (at 141.65 119.92) (size 0.45) (drill 0.1) (layers "F.Cu" "B.Cu") (net 169))
  (segment (start 140.96 120.35) (end 141.39 119.92) (width 0.182) (layer "B.Cu") (net 169))
  (segment (start 141.39 119.92) (end 141.65 119.92) (width 0.182) (layer "B.Cu") (net 169))
  (segment (start 141.253762 117.125) (end 142.135 118.006238) (width 0.182) (layer "F.Cu") (net 170))
  (segment (start 142.135 119.06) (end 142.541979 119.466979) (width 0.182) (layer "F.Cu") (net 170))
  (segment (start 140.47 117.125) (end 141.253762 117.125) (width 0.182) (layer "F.Cu") (net 170))
  (segment (start 142.541979 119.466979) (end 144.363979 119.466979) (width 0.182) (layer "F.Cu") (net 170))
  (segment (start 142.135 118.006238) (end 142.135 119.06) (width 0.182) (layer "F.Cu") (net 170))
  (segment (start 140.67 121.4) (end 141.4 121.4) (width 0.182) (layer "F.Cu") (net 171))
  (segment (start 144.385 119.1) (end 144.025 119.1) (width 0.182) (layer "F.Cu") (net 171))
  (segment (start 143.976405 119.148595) (end 144.025 119.1) (width 0.182) (layer "F.Cu") (net 171))
  (segment (start 143.149023 119.164023) (end 143.035 119.05) (width 0.182) (layer "F.Cu") (net 171))
  (segment (start 143.976405 119.148595) (end 143.960977 119.164023) (width 0.182) (layer "F.Cu") (net 171))
  (segment (start 143.960977 119.164023) (end 143.149023 119.164023) (width 0.182) (layer "F.Cu") (net 171))
  (via (at 141.4 121.4) (size 0.45) (drill 0.1) (layers "F.Cu" "B.Cu") (net 171))
  (via (at 143.035 119.05) (size 0.45) (drill 0.1) (layers "F.Cu" "B.Cu") (net 171))
  (segment (start 141.4 121.4) (end 141.4 121.02) (width 0.109) (layer "In6.Cu") (net 171))
  (segment (start 143.035 119.385) (end 143.035 119.05) (width 0.109) (layer "In6.Cu") (net 171))
  (segment (start 141.4 121.02) (end 143.035 119.385) (width 0.109) (layer "In6.Cu") (net 171))
  (segment (start 141.25 116.3) (end 140.495 116.3) (width 0.109) (layer "F.Cu") (net 172))
  (segment (start 143.812988 117.467988) (end 143.282012 117.467988) (width 0.182) (layer "F.Cu") (net 172))
  (segment (start 144.385 117.5) (end 143.845 117.5) (width 0.182) (layer "F.Cu") (net 172))
  (segment (start 143.282012 117.467988) (end 142.9 117.85) (width 0.182) (layer "F.Cu") (net 172))
  (segment (start 140.495 116.3) (end 140.47 116.325) (width 0.109) (layer "F.Cu") (net 172))
  (segment (start 143.845 117.5) (end 143.812988 117.467988) (width 0.182) (layer "F.Cu") (net 172))
  (via (at 142.9 117.85) (size 0.45) (drill 0.1) (layers "F.Cu" "B.Cu") (net 172))
  (via (at 141.25 116.3) (size 0.45) (drill 0.1) (layers "F.Cu" "B.Cu") (net 172))
  (segment (start 142.35 117.85) (end 141.25 116.75) (width 0.109) (layer "In6.Cu") (net 172))
  (segment (start 141.25 116.75) (end 141.25 116.3) (width 0.109) (layer "In6.Cu") (net 172))
  (segment (start 142.9 117.85) (end 142.35 117.85) (width 0.109) (layer "In6.Cu") (net 172))
  (segment (start 143.775 117.1) (end 144.385 117.1) (width 0.182) (layer "F.Cu") (net 173))
  (segment (start 142.875 117.3) (end 143.094 117.081) (width 0.182) (layer "F.Cu") (net 173))
  (segment (start 142.075 117.3) (end 142.875 117.3) (width 0.182) (layer "F.Cu") (net 173))
  (segment (start 141.5 116.725) (end 142.075 117.3) (width 0.182) (layer "F.Cu") (net 173))
  (segment (start 143.094 117.081) (end 143.756 117.081) (width 0.182) (layer "F.Cu") (net 173))
  (segment (start 140.47 116.725) (end 141.5 116.725) (width 0.182) (layer "F.Cu") (net 173))
  (segment (start 143.756 117.081) (end 143.775 117.1) (width 0.182) (layer "F.Cu") (net 173))
  (segment (start 96.495 144.494999) (end 96.495 143.85) (width 0.182) (layer "F.Cu") (net 174))
  (segment (start 99.7 147.16) (end 98.91 147.16) (width 0.182) (layer "F.Cu") (net 174))
  (segment (start 96.464999 145.294999) (end 96.464999 144.525) (width 0.182) (layer "F.Cu") (net 174))
  (segment (start 96.464999 144.525) (end 96.495 144.494999) (width 0.182) (layer "F.Cu") (net 174))
  (segment (start 96.59 145.42) (end 96.464999 145.294999) (width 0.182) (layer "F.Cu") (net 174))
  (segment (start 97.17 145.42) (end 96.59 145.42) (width 0.182) (layer "F.Cu") (net 174))
  (segment (start 96.725 143.62) (end 96.725 143.025001) (width 0.182) (layer "F.Cu") (net 174))
  (segment (start 98.91 147.16) (end 97.17 145.42) (width 0.182) (layer "F.Cu") (net 174))
  (segment (start 96.495 143.85) (end 96.725 143.62) (width 0.182) (layer "F.Cu") (net 174))
  (segment (start 128.344862 89.334862) (end 127.907742 89.334862) (width 0.182) (layer "F.Cu") (net 175))
  (segment (start 111.3 146.4492) (end 111.3 147.2) (width 0.2) (layer "F.Cu") (net 175))
  (segment (start 111.3 148.4) (end 111.3 147.2) (width 0.182) (layer "F.Cu") (net 175))
  (segment (start 129.055 89.615) (end 128.625 89.615) (width 0.182) (layer "F.Cu") (net 175))
  (segment (start 115.375 131.954271) (end 115.375 139.016582) (width 0.182) (layer "F.Cu") (net 175))
  (segment (start 129.7 94.3) (end 131.735 92.265) (width 0.182) (layer "F.Cu") (net 175))
  (segment (start 131.735 90.335) (end 130.734862 89.334862) (width 0.182) (layer "F.Cu") (net 175))
  (segment (start 131.735 92.265) (end 131.735 90.335) (width 0.182) (layer "F.Cu") (net 175))
  (segment (start 128.625 89.615) (end 128.344862 89.334862) (width 0.182) (layer "F.Cu") (net 175))
  (segment (start 113.56 140.1) (end 114.291582 140.1) (width 0.182) (layer "F.Cu") (net 175))
  (segment (start 130.734862 89.334862) (end 129.335138 89.334862) (width 0.182) (layer "F.Cu") (net 175))
  (segment (start 118.252316 129.076955) (end 115.375 131.954271) (width 0.182) (layer "F.Cu") (net 175))
  (segment (start 129.335138 89.334862) (end 129.055 89.615) (width 0.182) (layer "F.Cu") (net 175))
  (segment (start 114.291582 140.1) (end 114.320796 140.070786) (width 0.182) (layer "F.Cu") (net 175))
  (segment (start 115.375 139.016582) (end 114.320796 140.070786) (width 0.182) (layer "F.Cu") (net 175))
  (via (at 111.3 147.2) (size 0.45) (drill 0.1) (layers "F.Cu" "B.Cu") (net 175))
  (via (at 114.320796 140.070786) (size 0.45) (drill 0.1) (layers "F.Cu" "B.Cu") (net 175))
  (via (at 129.7 94.3) (size 0.45) (drill 0.1) (layers "F.Cu" "B.Cu") (net 175))
  (via (at 118.252316 129.076955) (size 0.45) (drill 0.1) (layers "F.Cu" "B.Cu") (net 175))
  (segment (start 122.45 124.879271) (end 118.252316 129.076955) (width 0.109) (layer "In6.Cu") (net 175))
  (segment (start 125.9 114.05) (end 122.45 117.5) (width 0.109) (layer "In6.Cu") (net 175))
  (segment (start 113.5 140.891582) (end 114.320796 140.070786) (width 0.109) (layer "In6.Cu") (net 175))
  (segment (start 113.5 145) (end 113.5 140.891582) (width 0.109) (layer "In6.Cu") (net 175))
  (segment (start 125.9 110.6) (end 125.9 114.05) (width 0.109) (layer "In6.Cu") (net 175))
  (segment (start 129.7 106.8) (end 125.9 110.6) (width 0.109) (layer "In6.Cu") (net 175))
  (segment (start 129.7 94.3) (end 129.7 106.8) (width 0.109) (layer "In6.Cu") (net 175))
  (segment (start 111.3 147.2) (end 113.5 145) (width 0.109) (layer "In6.Cu") (net 175))
  (segment (start 122.45 117.5) (end 122.45 124.879271) (width 0.109) (layer "In6.Cu") (net 175))
  (segment (start 114.7 139.691582) (end 114.320796 140.070786) (width 0.182) (layer "B.Cu") (net 175))
  (segment (start 115.215 139.1) (end 115.2 139.1) (width 0.182) (layer "B.Cu") (net 175))
  (segment (start 114.7 139.6) (end 114.7 139.691582) (width 0.182) (layer "B.Cu") (net 175))
  (segment (start 115.2 139.1) (end 114.7 139.6) (width 0.182) (layer "B.Cu") (net 175))
  (segment (start 153.44939 88.44939) (end 152.33661 88.44939) (width 0.182) (layer "F.Cu") (net 176))
  (segment (start 113.56 141.1) (end 114.217387 141.1) (width 0.182) (layer "F.Cu") (net 176))
  (segment (start 114.217387 141.1) (end 114.345528 141.228141) (width 0.182) (layer "F.Cu") (net 176))
  (segment (start 112.3 146.5) (end 112.3 147.2) (width 0.2) (layer "F.Cu") (net 176))
  (segment (start 152.33661 88.44939) (end 152.321965 88.464035) (width 0.182) (layer "F.Cu") (net 176))
  (segment (start 112.3 148.4) (end 112.3 147.2) (width 0.182) (layer "F.Cu") (net 176))
  (segment (start 118.7 129.5) (end 115.882011 132.317989) (width 0.182) (layer "F.Cu") (net 176))
  (segment (start 115.882011 132.317989) (end 115.882011 139.691658) (width 0.182) (layer "F.Cu") (net 176))
  (segment (start 115.882011 139.691658) (end 114.345528 141.228141) (width 0.182) (layer "F.Cu") (net 176))
  (via (at 153.44939 88.44939) (size 0.45) (drill 0.1) (layers "F.Cu" "B.Cu") (net 176))
  (via (at 128.25 110.3) (size 0.45) (drill 0.1) (layers "F.Cu" "B.Cu") (net 176))
  (via (at 114.345528 141.228141) (size 0.45) (drill 0.1) (layers "F.Cu" "B.Cu") (net 176))
  (via (at 112.3 147.2) (size 0.45) (drill 0.1) (layers "F.Cu" "B.Cu") (net 176))
  (via (at 118.7 129.5) (size 0.45) (drill 0.1) (layers "F.Cu" "B.Cu") (net 176))
  (segment (start 139.575 110.3) (end 128.25 110.3) (width 0.109) (layer "In4.Cu") (net 176))
  (segment (start 153.44939 92.17561) (end 152.675 92.95) (width 0.109) (layer "In4.Cu") (net 176))
  (segment (start 153.44939 88.44939) (end 153.44939 92.17561) (width 0.109) (layer "In4.Cu") (net 176))
  (segment (start 152.675 92.95) (end 152.675 97.2) (width 0.109) (layer "In4.Cu") (net 176))
  (segment (start 152.675 97.2) (end 139.575 110.3) (width 0.109) (layer "In4.Cu") (net 176))
  (segment (start 113.8 141.773669) (end 114.345528 141.228141) (width 0.109) (layer "In6.Cu") (net 176))
  (segment (start 113.8 145.7) (end 113.8 141.773669) (width 0.109) (layer "In6.Cu") (net 176))
  (segment (start 118.7 129.5) (end 122.8 125.4) (width 0.109) (layer "In6.Cu") (net 176))
  (segment (start 112.3 147.2) (end 113.8 145.7) (width 0.109) (layer "In6.Cu") (net 176))
  (segment (start 128.25 113.1) (end 128.25 110.3) (width 0.109) (layer "In6.Cu") (net 176))
  (segment (start 122.8 118.55) (end 128.25 113.1) (width 0.109) (layer "In6.Cu") (net 176))
  (segment (start 122.8 125.4) (end 122.8 118.55) (width 0.109) (layer "In6.Cu") (net 176))
  (segment (start 115.215 141.1) (end 114.8 141.1) (width 0.182) (layer "B.Cu") (net 176))
  (segment (start 114.671859 141.228141) (end 114.345528 141.228141) (width 0.182) (layer "B.Cu") (net 176))
  (segment (start 114.8 141.1) (end 114.671859 141.228141) (width 0.182) (layer "B.Cu") (net 176))
  (segment (start 109.3 146.5) (end 109.3 147.2) (width 0.2) (layer "F.Cu") (net 177))
  (segment (start 110.474996 140.6) (end 110.383652 140.691344) (width 0.182) (layer "F.Cu") (net 177))
  (segment (start 111.14 140.6) (end 110.474996 140.6) (width 0.182) (layer "F.Cu") (net 177))
  (segment (start 109.3 148.4) (end 109.3 147.2) (width 0.182) (layer "F.Cu") (net 177))
  (via (at 109.3 147.2) (size 0.45) (drill 0.1) (layers "F.Cu" "B.Cu") (net 177))
  (via (at 110.383652 140.691344) (size 0.45) (drill 0.1) (layers "F.Cu" "B.Cu") (net 177))
  (via (at 117.8 147) (size 0.45) (drill 0.1) (layers "F.Cu" "B.Cu") (net 177))
  (segment (start 110.05 146.45) (end 116.2 146.45) (width 0.109) (layer "In2.Cu") (net 177))
  (segment (start 110.05 146.45) (end 109.3 147.2) (width 0.109) (layer "In2.Cu") (net 177))
  (segment (start 116.75 147) (end 116.2 146.45) (width 0.109) (layer "In2.Cu") (net 177))
  (segment (start 117.8 147) (end 116.75 147) (width 0.109) (layer "In2.Cu") (net 177))
  (segment (start 109.3 147.2) (end 108.775 146.675) (width 0.109) (layer "In6.Cu") (net 177))
  (segment (start 108.775 143) (end 109.3 142.475) (width 0.109) (layer "In6.Cu") (net 177))
  (segment (start 108.775 146.675) (end 108.775 143) (width 0.109) (layer "In6.Cu") (net 177))
  (segment (start 110.8 142.075) (end 110.8 141.107692) (width 0.109) (layer "In6.Cu") (net 177))
  (segment (start 110.4 142.475) (end 110.8 142.075) (width 0.109) (layer "In6.Cu") (net 177))
  (segment (start 110.8 141.107692) (end 110.383652 140.691344) (width 0.109) (layer "In6.Cu") (net 177))
  (segment (start 109.3 142.475) (end 110.4 142.475) (width 0.109) (layer "In6.Cu") (net 177))
  (segment (start 110.658656 140.691344) (end 110.383652 140.691344) (width 0.182) (layer "B.Cu") (net 177))
  (segment (start 111.2 140.15) (end 110.658656 140.691344) (width 0.182) (layer "B.Cu") (net 177))
  (segment (start 117.8 147) (end 118.8 147) (width 0.182) (layer "B.Cu") (net 177))
  (segment (start 112.1 138.671668) (end 112.971668 137.8) (width 0.182) (layer "F.Cu") (net 178))
  (segment (start 112.971668 137.8) (end 114.6 137.8) (width 0.182) (layer "F.Cu") (net 178))
  (segment (start 123.1151 98.475) (end 124.363834 98.475) (width 0.182) (layer "F.Cu") (net 178))
  (segment (start 114.6 137.8) (end 114.825 137.575) (width 0.182) (layer "F.Cu") (net 178))
  (segment (start 125.888834 100) (end 127.1 100) (width 0.182) (layer "F.Cu") (net 178))
  (segment (start 110.3 146.5) (end 110.3 147.2) (width 0.2) (layer "F.Cu") (net 178))
  (segment (start 110.3 148.4) (end 110.3 147.2) (width 0.182) (layer "F.Cu") (net 178))
  (segment (start 124.363834 98.475) (end 125.888834 100) (width 0.182) (layer "F.Cu") (net 178))
  (segment (start 112.1 139.64) (end 112.1 138.95451) (width 0.182) (layer "F.Cu") (net 178))
  (segment (start 112.1 138.95451) (end 112.1 138.671668) (width 0.182) (layer "F.Cu") (net 178))
  (segment (start 114.825 131.755607) (end 117.983494 128.597113) (width 0.182) (layer "F.Cu") (net 178))
  (segment (start 114.825 137.575) (end 114.825 131.755607) (width 0.182) (layer "F.Cu") (net 178))
  (via (at 117.983494 128.597113) (size 0.45) (drill 0.1) (layers "F.Cu" "B.Cu") (net 178))
  (via (at 112.1 138.95451) (size 0.45) (drill 0.1) (layers "F.Cu" "B.Cu") (net 178))
  (via (at 110.3 147.2) (size 0.45) (drill 0.1) (layers "F.Cu" "B.Cu") (net 178))
  (via (at 127.1 100) (size 0.45) (drill 0.1) (layers "F.Cu" "B.Cu") (net 178))
  (segment (start 112.1 141.35) (end 112.1 138.95451) (width 0.109) (layer "In6.Cu") (net 178))
  (segment (start 122.05 124.530607) (end 117.983494 128.597113) (width 0.109) (layer "In6.Cu") (net 178))
  (segment (start 127.9 100.8) (end 127.9 107.7) (width 0.109) (layer "In6.Cu") (net 178))
  (segment (start 127.1 100) (end 127.9 100.8) (width 0.109) (layer "In6.Cu") (net 178))
  (segment (start 125.2 110.4) (end 125.2 113.224662) (width 0.109) (layer "In6.Cu") (net 178))
  (segment (start 110.3 145.6) (end 109.195 144.495) (width 0.109) (layer "In6.Cu") (net 178))
  (segment (start 110.55 142.9) (end 112.1 141.35) (width 0.109) (layer "In6.Cu") (net 178))
  (segment (start 109.195 143.105) (end 109.4 142.9) (width 0.109) (layer "In6.Cu") (net 178))
  (segment (start 110.3 147.2) (end 110.3 145.6) (width 0.109) (layer "In6.Cu") (net 178))
  (segment (start 125.2 113.224662) (end 122.05 116.374662) (width 0.109) (layer "In6.Cu") (net 178))
  (segment (start 109.195 144.495) (end 109.195 143.105) (width 0.109) (layer "In6.Cu") (net 178))
  (segment (start 122.05 116.374662) (end 122.05 124.530607) (width 0.109) (layer "In6.Cu") (net 178))
  (segment (start 109.4 142.9) (end 110.55 142.9) (width 0.109) (layer "In6.Cu") (net 178))
  (segment (start 127.9 107.7) (end 125.2 110.4) (width 0.109) (layer "In6.Cu") (net 178))
  (segment (start 112.135 138.91951) (end 112.1 138.95451) (width 0.182) (layer "B.Cu") (net 178))
  (segment (start 112.135 138.25) (end 112.135 138.91951) (width 0.182) (layer "B.Cu") (net 178))
  (segment (start 92.3665 105.874) (end 92.846 105.563) (width 0.182) (layer "F.Cu") (net 179))
  (segment (start 110.835 104.825) (end 111.188 105.178) (width 0.178) (layer "F.Cu") (net 179))
  (segment (start 110.835 104.125) (end 110.835 104.825) (width 0.178) (layer "F.Cu") (net 179))
  (segment (start 111.188 105.178) (end 111.188 105.623571) (width 0.178) (layer "F.Cu") (net 179))
  (segment (start 111.188 105.623571) (end 111.077 105.734571) (width 0.178) (layer "F.Cu") (net 179))
  (via (at 92.846 105.563) (size 0.45) (drill 0.1) (layers "F.Cu" "B.Cu") (net 179))
  (via (at 111.077 105.734571) (size 0.45) (drill 0.1) (layers "F.Cu" "B.Cu") (net 179))
  (segment (start 109.9465 106.308101) (end 109.9465 106.5135) (width 0.107) (layer "In4.Cu") (net 179))
  (segment (start 99.09825 104.3585) (end 98.12825 105.3285) (width 0.107) (layer "In4.Cu") (net 179))
  (segment (start 106.11175 106.7385) (end 103.73175 104.3585) (width 0.107) (layer "In4.Cu") (net 179))
  (segment (start 110.98825 106.7385) (end 110.6215 106.7385) (width 0.107) (layer "In4.Cu") (net 179))
  (segment (start 95.052562 105.894184) (end 95.052563 105.894184) (width 0.107) (layer "In4.Cu") (net 179))
  (segment (start 95.017208 105.293145) (end 95.017208 105.293144) (width 0.107) (layer "In4.Cu") (net 179))
  (segment (start 95.017208 105.575986) (end 95.052563 105.611341) (width 0.107) (layer "In4.Cu") (net 179))
  (segment (start 92.5945 105.90125) (end 92.5945 105.8145) (width 0.107) (layer "In4.Cu") (net 179))
  (segment (start 95.335406 105.3285) (end 95.335407 105.3285) (width 0.107) (layer "In4.Cu") (net 179))
  (segment (start 110.3965 106.5135) (end 110.3965 106.308101) (width 0.107) (layer "In4.Cu") (net 179))
  (segment (start 92.66175 105.9685) (end 92.5945 105.90125) (width 0.107) (layer "In4.Cu") (net 179))
  (segment (start 109.7215 106.7385) (end 109.6715 106.7385) (width 0.107) (layer "In4.Cu") (net 179))
  (segment (start 109.6715 106.7385) (end 106.11175 106.7385) (width 0.107) (layer "In4.Cu") (net 179))
  (segment (start 111.2485 105.906071) (end 111.2485 106.47825) (width 0.107) (layer "In4.Cu") (net 179))
  (segment (start 111.077 105.734571) (end 111.2485 105.906071) (width 0.107) (layer "In4.Cu") (net 179))
  (segment (start 95.052563 105.894184) (end 94.97825 105.9685) (width 0.107) (layer "In4.Cu") (net 179))
  (segment (start 92.5945 105.8145) (end 92.846 105.563) (width 0.107) (layer "In4.Cu") (net 179))
  (segment (start 111.2485 106.47825) (end 110.98825 106.7385) (width 0.107) (layer "In4.Cu") (net 179))
  (segment (start 103.73175 104.3585) (end 99.09825 104.3585) (width 0.107) (layer "In4.Cu") (net 179))
  (segment (start 95.335407 105.3285) (end 95.300051 105.293144) (width 0.107) (layer "In4.Cu") (net 179))
  (segment (start 94.97825 105.9685) (end 92.66175 105.9685) (width 0.107) (layer "In4.Cu") (net 179))
  (segment (start 98.12825 105.3285) (end 95.61825 105.3285) (width 0.107) (layer "In4.Cu") (net 179))
  (arc (start 110.6215 106.7385) (mid 110.462401 106.672599) (end 110.3965 106.5135) (width 0.107) (layer "In4.Cu") (net 179))
  (arc (start 110.1715 106.083101) (mid 110.012401 106.149002) (end 109.9465 106.308101) (width 0.107) (layer "In4.Cu") (net 179))
  (arc (start 95.052563 105.611341) (mid 95.111141 105.752763) (end 95.052562 105.894184) (width 0.107) (layer "In4.Cu") (net 179))
  (arc (start 109.9465 106.5135) (mid 109.880599 106.672599) (end 109.7215 106.7385) (width 0.107) (layer "In4.Cu") (net 179))
  (arc (start 95.300051 105.293144) (mid 95.158629 105.234566) (end 95.017208 105.293145) (width 0.107) (layer "In4.Cu") (net 179))
  (arc (start 110.3965 106.308101) (mid 110.330599 106.149002) (end 110.1715 106.083101) (width 0.107) (layer "In4.Cu") (net 179))
  (arc (start 95.017208 105.293144) (mid 94.95863 105.434565) (end 95.017208 105.575986) (width 0.107) (layer "In4.Cu") (net 179))
  (arc (start 95.61825 105.3285) (mid 95.476828 105.387079) (end 95.335406 105.3285) (width 0.107) (layer "In4.Cu") (net 179))
  (segment (start 91.89 105.553) (end 92.3665 105.239) (width 0.182) (layer "F.Cu") (net 180))
  (segment (start 111.752 105.178) (end 111.752 105.623571) (width 0.178) (layer "F.Cu") (net 180))
  (segment (start 112.105 104.825) (end 111.752 105.178) (width 0.178) (layer "F.Cu") (net 180))
  (segment (start 111.752 105.623571) (end 111.863 105.734571) (width 0.178) (layer "F.Cu") (net 180))
  (segment (start 112.105 104.125) (end 112.105 104.825) (width 0.178) (layer "F.Cu") (net 180))
  (via (at 91.89 105.553) (size 0.45) (drill 0.1) (layers "F.Cu" "B.Cu") (net 180))
  (via (at 111.863 105.734571) (size 0.45) (drill 0.1) (layers "F.Cu" "B.Cu") (net 180))
  (segment (start 103.54825 104.8015) (end 105.92825 107.1815) (width 0.107) (layer "In4.Cu") (net 180))
  (segment (start 111.17175 107.1815) (end 111.6915 106.66175) (width 0.107) (layer "In4.Cu") (net 180))
  (segment (start 98.31175 105.7715) (end 99.28175 104.8015) (width 0.107) (layer "In4.Cu") (net 180))
  (segment (start 92.1515 105.8145) (end 92.1515 106.08475) (width 0.107) (layer "In4.Cu") (net 180))
  (segment (start 95.16175 106.4115) (end 95.80175 105.7715) (width 0.107) (layer "In4.Cu") (net 180))
  (segment (start 99.28175 104.8015) (end 103.54825 104.8015) (width 0.107) (layer "In4.Cu") (net 180))
  (segment (start 111.863 105.734571) (end 111.6915 105.906071) (width 0.107) (layer "In4.Cu") (net 180))
  (segment (start 92.1515 106.08475) (end 92.47825 106.4115) (width 0.107) (layer "In4.Cu") (net 180))
  (segment (start 111.6915 106.66175) (end 111.6915 105.906071) (width 0.107) (layer "In4.Cu") (net 180))
  (segment (start 92.47825 106.4115) (end 95.16175 106.4115) (width 0.107) (layer "In4.Cu") (net 180))
  (segment (start 91.89 105.553) (end 92.1515 105.8145) (width 0.107) (layer "In4.Cu") (net 180))
  (segment (start 105.92825 107.1815) (end 111.17175 107.1815) (width 0.107) (layer "In4.Cu") (net 180))
  (segment (start 95.80175 105.7715) (end 98.31175 105.7715) (width 0.107) (layer "In4.Cu") (net 180))
  (segment (start 100.598 105.586107) (end 100.487 105.697107) (width 0.178) (layer "F.Cu") (net 181))
  (segment (start 100.598 105.138) (end 100.598 105.586107) (width 0.178) (layer "F.Cu") (net 181))
  (segment (start 99.61 104.05) (end 99.61 104.15) (width 0.178) (layer "F.Cu") (net 181))
  (segment (start 99.61 104.15) (end 100.598 105.138) (width 0.178) (layer "F.Cu") (net 181))
  (segment (start 90.7865 107.144) (end 91.266 106.833) (width 0.182) (layer "F.Cu") (net 181))
  (via (at 100.487 105.697107) (size 0.45) (drill 0.1) (layers "F.Cu" "B.Cu") (net 181))
  (via (at 91.266 106.833) (size 0.45) (drill 0.1) (layers "F.Cu" "B.Cu") (net 181))
  (segment (start 93.64922 107.2115) (end 93.64622 107.2085) (width 0.107) (layer "In4.Cu") (net 181))
  (segment (start 93.96578 107.2085) (end 95.5715 107.2085) (width 0.107) (layer "In4.Cu") (net 181))
  (segment (start 91.05175 107.2085) (end 91.0145 107.17125) (width 0.107) (layer "In4.Cu") (net 181))
  (segment (start 99.65325 107.2085) (end 96.5715 107.2085) (width 0.107) (layer "In4.Cu") (net 181))
  (segment (start 100.6585 105.868607) (end 100.6585 106.20325) (width 0.107) (layer "In4.Cu") (net 181))
  (segment (start 93.96578 107.2085) (end 93.96278 107.2115) (width 0.107) (layer "In4.Cu") (net 181))
  (segment (start 99.854477 107.00727) (end 99.854478 107.007271) (width 0.107) (layer "In4.Cu") (net 181))
  (segment (start 95.8215 106.811384) (end 95.8215 106.9585) (width 0.107) (layer "In4.Cu") (net 181))
  (segment (start 99.819122 106.653717) (end 99.854477 106.689072) (width 0.107) (layer "In4.Cu") (net 181))
  (segment (start 100.172675 106.370875) (end 100.172676 106.370875) (width 0.107) (layer "In4.Cu") (net 181))
  (segment (start 96.3215 106.9585) (end 96.3215 106.811384) (width 0.107) (layer "In4.Cu") (net 181))
  (segment (start 91.0145 107.17125) (end 91.0145 107.0845) (width 0.107) (layer "In4.Cu") (net 181))
  (segment (start 100.6585 106.20325) (end 100.490875 106.370875) (width 0.107) (layer "In4.Cu") (net 181))
  (segment (start 100.487 105.697107) (end 100.6585 105.868607) (width 0.107) (layer "In4.Cu") (net 181))
  (segment (start 100.172676 106.370875) (end 100.13732 106.335519) (width 0.107) (layer "In4.Cu") (net 181))
  (segment (start 91.0145 107.0845) (end 91.266 106.833) (width 0.107) (layer "In4.Cu") (net 181))
  (segment (start 93.64622 107.2085) (end 91.05175 107.2085) (width 0.107) (layer "In4.Cu") (net 181))
  (segment (start 99.854478 107.007271) (end 99.65325 107.2085) (width 0.107) (layer "In4.Cu") (net 181))
  (segment (start 93.96278 107.2115) (end 93.64922 107.2115) (width 0.107) (layer "In4.Cu") (net 181))
  (arc (start 96.5715 107.2085) (mid 96.394723 107.135277) (end 96.3215 106.9585) (width 0.107) (layer "In4.Cu") (net 181))
  (arc (start 99.819122 106.335519) (mid 99.753221 106.494618) (end 99.819122 106.653717) (width 0.107) (layer "In4.Cu") (net 181))
  (arc (start 99.854477 106.689072) (mid 99.920378 106.848171) (end 99.854477 107.00727) (width 0.107) (layer "In4.Cu") (net 181))
  (arc (start 96.3215 106.811384) (mid 96.248277 106.634607) (end 96.0715 106.561384) (width 0.107) (layer "In4.Cu") (net 181))
  (arc (start 96.0715 106.561384) (mid 95.894723 106.634607) (end 95.8215 106.811384) (width 0.107) (layer "In4.Cu") (net 181))
  (arc (start 100.490875 106.370875) (mid 100.331775 106.436776) (end 100.172675 106.370875) (width 0.107) (layer "In4.Cu") (net 181))
  (arc (start 95.8215 106.9585) (mid 95.748277 107.135277) (end 95.5715 107.2085) (width 0.107) (layer "In4.Cu") (net 181))
  (arc (start 100.13732 106.335519) (mid 99.978221 106.269618) (end 99.819122 106.335519) (width 0.107) (layer "In4.Cu") (net 181))
  (segment (start 102.15 104.05) (end 102.15 104.15) (width 0.178) (layer "F.Cu") (net 182))
  (segment (start 102.15 104.15) (end 101.162 105.138) (width 0.178) (layer "F.Cu") (net 182))
  (segment (start 101.162 105.138) (end 101.162 105.586107) (width 0.178) (layer "F.Cu") (net 182))
  (segment (start 101.162 105.586107) (end 101.273 105.697107) (width 0.178) (layer "F.Cu") (net 182))
  (segment (start 90.31 106.823) (end 90.7865 106.509) (width 0.182) (layer "F.Cu") (net 182))
  (via (at 101.273 105.697107) (size 0.45) (drill 0.1) (layers "F.Cu" "B.Cu") (net 182))
  (via (at 90.31 106.823) (size 0.45) (drill 0.1) (layers "F.Cu" "B.Cu") (net 182))
  (segment (start 101.1015 105.868607) (end 101.273 105.697107) (width 0.107) (layer "In4.Cu") (net 182))
  (segment (start 101.1015 106.38675) (end 101.1015 105.868607) (width 0.107) (layer "In4.Cu") (net 182))
  (segment (start 90.5715 107.35475) (end 90.86825 107.6515) (width 0.107) (layer "In4.Cu") (net 182))
  (segment (start 99.83675 107.6515) (end 101.1015 106.38675) (width 0.107) (layer "In4.Cu") (net 182))
  (segment (start 90.31 106.823) (end 90.5715 107.0845) (width 0.107) (layer "In4.Cu") (net 182))
  (segment (start 90.5715 107.0845) (end 90.5715 107.35475) (width 0.107) (layer "In4.Cu") (net 182))
  (segment (start 90.86825 107.6515) (end 99.83675 107.6515) (width 0.107) (layer "In4.Cu") (net 182))
  (segment (start 100.125 96.675) (end 100.5035 97.0535) (width 0.107) (layer "F.Cu") (net 183))
  (segment (start 100.443 96.993) (end 100.443 97.732002) (width 0.178) (layer "F.Cu") (net 183))
  (segment (start 100.443 97.732002) (end 100.332 97.843002) (width 0.178) (layer "F.Cu") (net 183))
  (segment (start 100.125 96.575) (end 100.125 96.675) (width 0.107) (layer "F.Cu") (net 183))
  (segment (start 89.8265 103.334) (end 90.306 103.023) (width 0.182) (layer "F.Cu") (net 183))
  (segment (start 100.125 96.675) (end 100.443 96.993) (width 0.178) (layer "F.Cu") (net 183))
  (via (at 90.306 103.023) (size 0.45) (drill 0.1) (layers "F.Cu" "B.Cu") (net 183))
  (via (at 100.332 97.843002) (size 0.45) (drill 0.1) (layers "F.Cu" "B.Cu") (net 183))
  (segment (start 89.346266 97.115321) (end 89.324678 97.125717) (width 0.107) (layer "In4.Cu") (net 183))
  (segment (start 89.172703 97.0632) (end 89.151115 97.052804) (width 0.107) (layer "In4.Cu") (net 183))
  (segment (start 89.409078 96.657134) (end 89.387743 96.652264) (width 0.107) (layer "In4.Cu") (net 183))
  (segment (start 89.379936 96.967794) (end 89.390333 96.98938) (width 0.107) (layer "In4.Cu") (net 183))
  (segment (start 89.267093 96.851157) (end 89.364997 96.949061) (width 0.107) (layer "In4.Cu") (net 183))
  (segment (start 88.869332 97.248918) (end 88.021502 98.096748) (width 0.107) (layer "In4.Cu") (net 183))
  (segment (start 88.0215 101.70825) (end 88.44175 102.1285) (width 0.107) (layer "In4.Cu") (net 183))
  (segment (start 89.452298 96.652264) (end 89.430962 96.657134) (width 0.107) (layer "In4.Cu") (net 183))
  (segment (start 89.270869 96.601115) (end 89.249534 96.605985) (width 0.107) (layer "In4.Cu") (net 183))
  (segment (start 99.507403 96.133111) (end 99.500007 96.154247) (width 0.107) (layer "In4.Cu") (net 183))
  (segment (start 99.701596 96.133111) (end 99.689683 96.114151) (width 0.107) (layer "In4.Cu") (net 183))
  (segment (start 89.395663 97.012741) (end 89.395663 97.036701) (width 0.107) (layer "In4.Cu") (net 183))
  (segment (start 99.535151 96.098316) (end 99.519316 96.114151) (width 0.107) (layer "In4.Cu") (net 183))
  (segment (start 89.199594 96.642237) (end 89.185949 96.659347) (width 0.107) (layer "In4.Cu") (net 183))
  (segment (start 89.249534 96.605985) (end 89.229817 96.61548) (width 0.107) (layer "In4.Cu") (net 183))
  (segment (start 89.268698 96.849549) (end 89.267093 96.851157) (width 0.107) (layer "In4.Cu") (net 183))
  (segment (start 99.5975 96.0765) (end 99.575247 96.079007) (width 0.107) (layer "In4.Cu") (net 183))
  (segment (start 99.243213 96.299845) (end 99.222925 96.287097) (width 0.107) (layer "In4.Cu") (net 183))
  (segment (start 99.222925 96.287097) (end 99.200309 96.279183) (width 0.107) (layer "In4.Cu") (net 183))
  (segment (start 99.3905 96.5265) (end 99.36669 96.523818) (width 0.107) (layer "In4.Cu") (net 183))
  (segment (start 99.4975 96.4195) (end 99.494817 96.44331) (width 0.107) (layer "In4.Cu") (net 183))
  (segment (start 99.280817 96.359691) (end 99.272903 96.337075) (width 0.107) (layer "In4.Cu") (net 183))
  (segment (start 89.324678 97.125717) (end 89.301317 97.131049) (width 0.107) (layer "In4.Cu") (net 183))
  (segment (start 89.212707 96.629125) (end 89.199594 96.642237) (width 0.107) (layer "In4.Cu") (net 183))
  (segment (start 99.414309 96.523818) (end 99.3905 96.5265) (width 0.107) (layer "In4.Cu") (net 183))
  (segment (start 99.494817 96.44331) (end 99.486903 96.465926) (width 0.107) (layer "In4.Cu") (net 183))
  (segment (start 88.44175 102.1285) (end 89.4115 102.1285) (width 0.107) (layer "In4.Cu") (net 183))
  (segment (start 89.333806 96.61548) (end 89.314089 96.605985) (width 0.107) (layer "In4.Cu") (net 183))
  (segment (start 99.8115 96.2765) (end 99.789247 96.273992) (width 0.107) (layer "In4.Cu") (net 183))
  (segment (start 89.390333 97.06006) (end 89.379937 97.081648) (width 0.107) (layer "In4.Cu") (net 183))
  (segment (start 99.689683 96.114151) (end 99.673848 96.098316) (width 0.107) (layer "In4.Cu") (net 183))
  (segment (start 89.292753 96.601115) (end 89.270869 96.601115) (width 0.107) (layer "In4.Cu") (net 183))
  (segment (start 99.436925 96.515904) (end 99.414309 96.523818) (width 0.107) (layer "In4.Cu") (net 183))
  (segment (start 89.364997 96.949061) (end 89.379936 96.967794) (width 0.107) (layer "In4.Cu") (net 183))
  (segment (start 99.486903 96.465926) (end 99.474155 96.486214) (width 0.107) (layer "In4.Cu") (net 183))
  (segment (start 89.040114 97.07814) (end 88.869332 97.248918) (width 0.107) (layer "In4.Cu") (net 183))
  (segment (start 99.2835 96.4195) (end 99.2835 96.3835) (width 0.107) (layer "In4.Cu") (net 183))
  (segment (start 99.633752 96.079007) (end 99.6115 96.0765) (width 0.107) (layer "In4.Cu") (net 183))
  (segment (start 89.171585 96.722283) (end 89.176454 96.743619) (width 0.107) (layer "In4.Cu") (net 183))
  (segment (start 89.253998 97.125717) (end 89.23241 97.115322) (width 0.107) (layer "In4.Cu") (net 183))
  (segment (start 88.021502 98.096748) (end 88.021502 98.59175) (width 0.107) (layer "In4.Cu") (net 183))
  (segment (start 99.749151 96.254683) (end 99.733316 96.238848) (width 0.107) (layer "In4.Cu") (net 183))
  (segment (start 99.654888 96.086403) (end 99.633752 96.079007) (width 0.107) (layer "In4.Cu") (net 183))
  (segment (start 89.387743 96.652264) (end 89.368026 96.642769) (width 0.107) (layer "In4.Cu") (net 183))
  (segment (start 99.344074 96.515904) (end 99.323786 96.503156) (width 0.107) (layer "In4.Cu") (net 183))
  (segment (start 99.575247 96.079007) (end 99.554111 96.086403) (width 0.107) (layer "In4.Cu") (net 183))
  (segment (start 89.229817 96.61548) (end 89.212707 96.629125) (width 0.107) (layer "In4.Cu") (net 183))
  (segment (start 99.294096 96.465926) (end 99.286182 96.44331) (width 0.107) (layer "In4.Cu") (net 183))
  (segment (start 99.768111 96.266596) (end 99.749151 96.254683) (width 0.107) (layer "In4.Cu") (net 183))
  (segment (start 89.176454 96.743619) (end 89.185949 96.763336) (width 0.107) (layer "In4.Cu") (net 183))
  (segment (start 99.200309 96.279183) (end 99.1765 96.2765) (width 0.107) (layer "In4.Cu") (net 183))
  (segment (start 99.323786 96.503156) (end 99.306844 96.486214) (width 0.107) (layer "In4.Cu") (net 183))
  (segment (start 100.5035 97.671502) (end 100.5035 96.69675) (width 0.107) (layer "In4.Cu") (net 183))
  (segment (start 89.185949 96.763336) (end 89.199594 96.780445) (width 0.107) (layer "In4.Cu") (net 183))
  (segment (start 99.714007 96.198752) (end 99.708992 96.154247) (width 0.107) (layer "In4.Cu") (net 183))
  (segment (start 89.430962 96.657134) (end 89.409078 96.657134) (width 0.107) (layer "In4.Cu") (net 183))
  (segment (start 89.127755 97.047473) (end 89.103795 97.047472) (width 0.107) (layer "In4.Cu") (net 183))
  (segment (start 100.332 97.843002) (end 100.5035 97.671502) (width 0.107) (layer "In4.Cu") (net 183))
  (segment (start 99.721403 96.219888) (end 99.714007 96.198752) (width 0.107) (layer "In4.Cu") (net 183))
  (segment (start 89.191436 97.078139) (end 89.172703 97.0632) (width 0.107) (layer "In4.Cu") (net 183))
  (segment (start 99.6115 96.0765) (end 99.5975 96.0765) (width 0.107) (layer "In4.Cu") (net 183))
  (segment (start 89.058847 97.063201) (end 89.040114 97.07814) (width 0.107) (layer "In4.Cu") (net 183))
  (segment (start 89.176454 96.679064) (end 89.171585 96.700399) (width 0.107) (layer "In4.Cu") (net 183))
  (segment (start 89.368026 96.642769) (end 89.333806 96.61548) (width 0.107) (layer "In4.Cu") (net 183))
  (segment (start 89.199594 96.780445) (end 89.268698 96.849549) (width 0.107) (layer "In4.Cu") (net 183))
  (segment (start 100.08325 96.2765) (end 99.8115 96.2765) (width 0.107) (layer "In4.Cu") (net 183))
  (segment (start 89.080435 97.052804) (end 89.058847 97.063201) (width 0.107) (layer "In4.Cu") (net 183))
  (segment (start 89.84175 96.2765) (end 89.489125 96.629125) (width 0.107) (layer "In4.Cu") (net 183))
  (segment (start 89.185949 96.659347) (end 89.176454 96.679064) (width 0.107) (layer "In4.Cu") (net 183))
  (segment (start 99.500007 96.154247) (end 99.4975 96.1765) (width 0.107) (layer "In4.Cu") (net 183))
  (segment (start 89.489125 96.629125) (end 89.472015 96.642769) (width 0.107) (layer "In4.Cu") (net 183))
  (segment (start 89.277357 97.131049) (end 89.253998 97.125717) (width 0.107) (layer "In4.Cu") (net 183))
  (segment (start 100.5035 96.69675) (end 100.08325 96.2765) (width 0.107) (layer "In4.Cu") (net 183))
  (segment (start 89.472015 96.642769) (end 89.452298 96.652264) (width 0.107) (layer "In4.Cu") (net 183))
  (segment (start 89.4115 102.1285) (end 90.306 103.023) (width 0.107) (layer "In4.Cu") (net 183))
  (segment (start 99.474155 96.486214) (end 99.457213 96.503156) (width 0.107) (layer "In4.Cu") (net 183))
  (segment (start 99.519316 96.114151) (end 99.507403 96.133111) (width 0.107) (layer "In4.Cu") (net 183))
  (segment (start 99.708992 96.154247) (end 99.701596 96.133111) (width 0.107) (layer "In4.Cu") (net 183))
  (segment (start 99.554111 96.086403) (end 99.535151 96.098316) (width 0.107) (layer "In4.Cu") (net 183))
  (segment (start 89.171585 96.700399) (end 89.171585 96.722283) (width 0.107) (layer "In4.Cu") (net 183))
  (segment (start 99.673848 96.098316) (end 99.654888 96.086403) (width 0.107) (layer "In4.Cu") (net 183))
  (segment (start 99.1765 96.2765) (end 89.84175 96.2765) (width 0.107) (layer "In4.Cu") (net 183))
  (segment (start 99.2835 96.3835) (end 99.280817 96.359691) (width 0.107) (layer "In4.Cu") (net 183))
  (segment (start 89.395663 97.036701) (end 89.390333 97.06006) (width 0.107) (layer "In4.Cu") (net 183))
  (segment (start 99.272903 96.337075) (end 99.260155 96.316787) (width 0.107) (layer "In4.Cu") (net 183))
  (segment (start 89.301317 97.131049) (end 89.277357 97.131049) (width 0.107) (layer "In4.Cu") (net 183))
  (segment (start 89.390333 96.98938) (end 89.395663 97.012741) (width 0.107) (layer "In4.Cu") (net 183))
  (segment (start 99.457213 96.503156) (end 99.436925 96.515904) (width 0.107) (layer "In4.Cu") (net 183))
  (segment (start 99.36669 96.523818) (end 99.344074 96.515904) (width 0.107) (layer "In4.Cu") (net 183))
  (segment (start 99.789247 96.273992) (end 99.768111 96.266596) (width 0.107) (layer "In4.Cu") (net 183))
  (segment (start 88.0215 98.59175) (end 88.0215 101.70825) (width 0.107) (layer "In4.Cu") (net 183))
  (segment (start 99.286182 96.44331) (end 99.2835 96.4195) (width 0.107) (layer "In4.Cu") (net 183))
  (segment (start 89.151115 97.052804) (end 89.127755 97.047473) (width 0.107) (layer "In4.Cu") (net 183))
  (segment (start 99.733316 96.238848) (end 99.721403 96.219888) (width 0.107) (layer "In4.Cu") (net 183))
  (segment (start 99.306844 96.486214) (end 99.294096 96.465926) (width 0.107) (layer "In4.Cu") (net 183))
  (segment (start 99.4975 96.1765) (end 99.4975 96.4195) (width 0.107) (layer "In4.Cu") (net 183))
  (segment (start 99.260155 96.316787) (end 99.243213 96.299845) (width 0.107) (layer "In4.Cu") (net 183))
  (segment (start 89.364998 97.100381) (end 89.346266 97.115321) (width 0.107) (layer "In4.Cu") (net 183))
  (segment (start 89.103795 97.047472) (end 89.080435 97.052804) (width 0.107) (layer "In4.Cu") (net 183))
  (segment (start 88.021502 98.59175) (end 88.0215 98.59175) (width 0.107) (layer "In4.Cu") (net 183))
  (segment (start 89.23241 97.115322) (end 89.213678 97.100381) (width 0.107) (layer "In4.Cu") (net 183))
  (segment (start 89.314089 96.605985) (end 89.292753 96.601115) (width 0.107) (layer "In4.Cu") (net 183))
  (segment (start 89.213678 97.100381) (end 89.191436 97.078139) (width 0.107) (layer "In4.Cu") (net 183))
  (segment (start 89.379937 97.081648) (end 89.364998 97.100381) (width 0.107) (layer "In4.Cu") (net 183))
  (segment (start 101.325 96.575) (end 101.325 96.675) (width 0.107) (layer "F.Cu") (net 184))
  (segment (start 89.35 103.013) (end 89.8265 102.699) (width 0.182) (layer "F.Cu") (net 184))
  (segment (start 101.007 97.732002) (end 101.118 97.843002) (width 0.178) (layer "F.Cu") (net 184))
  (segment (start 101.325 96.675) (end 100.9465 97.0535) (width 0.107) (layer "F.Cu") (net 184))
  (segment (start 101.007 96.993) (end 101.007 97.732002) (width 0.178) (layer "F.Cu") (net 184))
  (segment (start 101.325 96.675) (end 101.007 96.993) (width 0.178) (layer "F.Cu") (net 184))
  (via (at 101.118 97.843002) (size 0.45) (drill 0.1) (layers "F.Cu" "B.Cu") (net 184))
  (via (at 89.35 103.013) (size 0.45) (drill 0.1) (layers "F.Cu" "B.Cu") (net 184))
  (segment (start 89.35 102.693497) (end 89.228003 102.5715) (width 0.107) (layer "In4.Cu") (net 184))
  (segment (start 89.228003 102.5715) (end 88.25825 102.5715) (width 0.107) (layer "In4.Cu") (net 184))
  (segment (start 89.65825 95.8335) (end 100.26675 95.8335) (width 0.107) (layer "In4.Cu") (net 184))
  (segment (start 89.35 103.013) (end 89.35 102.693497) (width 0.107) (layer "In4.Cu") (net 184))
  (segment (start 87.5785 97.91325) (end 89.65825 95.8335) (width 0.107) (layer "In4.Cu") (net 184))
  (segment (start 87.5785 101.89175) (end 87.5785 97.91325) (width 0.107) (layer "In4.Cu") (net 184))
  (segment (start 100.26675 95.8335) (end 100.9465 96.51325) (width 0.107) (layer "In4.Cu") (net 184))
  (segment (start 100.9465 96.51325) (end 100.9465 97.671502) (width 0.107) (layer "In4.Cu") (net 184))
  (segment (start 88.25825 102.5715) (end 87.5785 101.89175) (width 0.107) (layer "In4.Cu") (net 184))
  (segment (start 100.9465 97.671502) (end 101.118 97.843002) (width 0.107) (layer "In4.Cu") (net 184))
  (segment (start 108.3 95.375) (end 108.3 94.65) (width 0.182) (layer "F.Cu") (net 185))
  (segment (start 105.063834 94.975) (end 105.063834 99.476166) (width 0.182) (layer "F.Cu") (net 185))
  (segment (start 104.69 99.951166) (end 106.490557 101.751723) (width 0.182) (layer "F.Cu") (net 185))
  (segment (start 112.565 135.55) (end 112.6 135.515) (width 0.182) (layer "F.Cu") (net 185))
  (segment (start 119.40864 121.05864) (end 119.3 120.95) (width 0.182) (layer "F.Cu") (net 185))
  (segment (start 119.875 120.95) (end 119.9 120.975) (width 0.182) (layer "F.Cu") (net 185))
  (segment (start 108 118.6) (end 108 119.3) (width 0.182) (layer "F.Cu") (net 185))
  (segment (start 105.063834 94.975) (end 106.463834 94.975) (width 0.182) (layer "F.Cu") (net 185))
  (segment (start 119.40864 127.48364) (end 119.40864 121.05864) (width 0.182) (layer "F.Cu") (net 185))
  (segment (start 118.84614 128.04614) (end 119.40864 127.48364) (width 0.182) (layer "F.Cu") (net 185))
  (segment (start 112.6 133.19228) (end 117.74614 128.04614) (width 0.182) (layer "F.Cu") (net 185))
  (segment (start 106.863834 95.375) (end 108.3 95.375) (width 0.182) (layer "F.Cu") (net 185))
  (segment (start 104.69 99.85) (end 104.69 99.951166) (width 0.182) (layer "F.Cu") (net 185))
  (segment (start 108 118.6) (end 108 118.64228) (width 0.109) (layer "F.Cu") (net 185))
  (segment (start 112.6 135.515) (end 112.6 133.19228) (width 0.182) (layer "F.Cu") (net 185))
  (segment (start 108 119.3) (end 108.2 119.5) (width 0.182) (layer "F.Cu") (net 185))
  (segment (start 105.590557 117.251723) (end 106.590557 117.251723) (width 0.182) (layer "F.Cu") (net 185))
  (segment (start 102.525 94.975) (end 105.063834 94.975) (width 0.182) (layer "F.Cu") (net 185))
  (segment (start 108 118.64228) (end 107.990557 118.651723) (width 0.109) (layer "F.Cu") (net 185))
  (segment (start 106.490557 101.751723) (end 106.490557 102.551723) (width 0.182) (layer "F.Cu") (net 185))
  (segment (start 105.063834 99.476166) (end 104.69 99.85) (width 0.182) (layer "F.Cu") (net 185))
  (segment (start 106.590557 117.251723) (end 107.990557 118.651723) (width 0.182) (layer "F.Cu") (net 185))
  (segment (start 105.588034 117.2492) (end 105.590557 117.251723) (width 0.182) (layer "F.Cu") (net 185))
  (segment (start 117.74614 128.04614) (end 118.84614 128.04614) (width 0.182) (layer "F.Cu") (net 185))
  (segment (start 104.85 117.2492) (end 105.588034 117.2492) (width 0.182) (layer "F.Cu") (net 185))
  (segment (start 119.3 120.95) (end 119.875 120.95) (width 0.182) (layer "F.Cu") (net 185))
  (segment (start 111.000001 135.55) (end 112.565 135.55) (width 0.182) (layer "F.Cu") (net 185))
  (segment (start 106.463834 94.975) (end 106.863834 95.375) (width 0.182) (layer "F.Cu") (net 185))
  (via (at 119.9 120.975) (size 0.45) (drill 0.1) (layers "F.Cu" "B.Cu") (net 185))
  (via (at 107.990557 118.651723) (size 0.45) (drill 0.1) (layers "F.Cu" "B.Cu") (net 185))
  (via (at 108.3 94.65) (size 0.45) (drill 0.1) (layers "F.Cu" "B.Cu") (net 185))
  (via (at 86.190557 112.251723) (size 0.45) (drill 0.1) (layers "F.Cu" "B.Cu") (net 185))
  (via (at 88.132494 113.403494) (size 0.45) (drill 0.1) (layers "F.Cu" "B.Cu") (net 185))
  (via (at 140.325 87.6) (size 0.45) (drill 0.1) (layers "F.Cu" "B.Cu") (net 185))
  (via (at 106.490557 102.551723) (size 0.45) (drill 0.1) (layers "F.Cu" "B.Cu") (net 185))
  (via (at 105.590557 117.251723) (size 0.45) (drill 0.1) (layers "F.Cu" "B.Cu") (net 185))
  (segment (start 111.2 119.66) (end 112.32 120.78) (width 0.109) (layer "In2.Cu") (net 185))
  (segment (start 113.13 120.78) (end 113.81 120.1) (width 0.109) (layer "In2.Cu") (net 185))
  (segment (start 113.81 120.1) (end 117.35 120.1) (width 0.109) (layer "In2.Cu") (net 185))
  (segment (start 112.32 120.78) (end 113.13 120.78) (width 0.109) (layer "In2.Cu") (net 185))
  (segment (start 108 118.6) (end 109.06 119.66) (width 0.109) (layer "In2.Cu") (net 185))
  (segment (start 117.35 120.1) (end 118.225 120.975) (width 0.109) (layer "In2.Cu") (net 185))
  (segment (start 109.06 119.66) (end 111.2 119.66) (width 0.109) (layer "In2.Cu") (net 185))
  (segment (start 118.225 120.975) (end 119.9 120.975) (width 0.109) (layer "In2.Cu") (net 185))
  (segment (start 102.990557 117.251723) (end 105.590557 117.251723) (width 0.109) (layer "In4.Cu") (net 185))
  (segment (start 105.93614 103.10614) (end 106.490557 102.551723) (width 0.109) (layer "In4.Cu") (net 185))
  (segment (start 97.453083 115.218083) (end 100.956917 115.218083) (width 0.109) (layer "In4.Cu") (net 185))
  (segment (start 89.062 113.011805) (end 89.284305 112.7895) (width 0.109) (layer "In4.Cu") (net 185))
  (segment (start 95.56 113.325) (end 97.453083 115.218083) (width 0.109) (layer "In4.Cu") (net 185))
  (segment (start 86.028277 103.651723) (end 97.631723 103.651723) (width 0.109) (layer "In4.Cu") (net 185))
  (segment (start 105.93614 103.10614) (end 98.177306 103.10614) (width 0.109) (layer "In4.Cu") (net 185))
  (segment (start 88.524183 113.011805) (end 89.062 113.011805) (width 0.109) (layer "In4.Cu") (net 185))
  (segment (start 131.185 88.25) (end 133.570001 90.635001) (width 0.109) (layer "In4.Cu") (net 185))
  (segment (start 84.825 110.886166) (end 84.825 104.855) (width 0.109) (layer "In4.Cu") (net 185))
  (segment (start 124.85 88.2) (end 125.95 89.3) (width 0.109) (layer "In4.Cu") (net 185))
  (segment (start 125.95 89.3) (end 127.5 89.3) (width 0.109) (layer "In4.Cu") (net 185))
  (segment (start 138.489999 90.635001) (end 139.274999 89.850001) (width 0.109) (layer "In4.Cu") (net 185))
  (segment (start 139.274999 88.650001) (end 140.325 87.6) (width 0.109) (layer "In4.Cu") (net 185))
  (segment (start 89.284305 112.7895) (end 94.114499 112.789499) (width 0.109) (layer "In4.Cu") (net 185))
  (segment (start 128.55 88.25) (end 131.185 88.25) (width 0.109) (layer "In4.Cu") (net 185))
  (segment (start 88.132494 113.403494) (end 88.524183 113.011805) (width 0.109) (layer "In4.Cu") (net 185))
  (segment (start 139.274999 89.850001) (end 139.274999 88.650001) (width 0.109) (layer "In4.Cu") (net 185))
  (segment (start 127.5 89.3) (end 128.55 88.25) (width 0.109) (layer "In4.Cu") (net 185))
  (segment (start 100.956917 115.218083) (end 102.990557 117.251723) (width 0.109) (layer "In4.Cu") (net 185))
  (segment (start 133.570001 90.635001) (end 138.489999 90.635001) (width 0.109) (layer "In4.Cu") (net 185))
  (segment (start 84.825 104.855) (end 86.028277 103.651723) (width 0.109) (layer "In4.Cu") (net 185))
  (segment (start 94.65 113.325) (end 95.56 113.325) (width 0.109) (layer "In4.Cu") (net 185))
  (segment (start 98.177306 103.10614) (end 97.631723 103.651723) (width 0.109) (layer "In4.Cu") (net 185))
  (segment (start 114.75 88.2) (end 124.85 88.2) (width 0.109) (layer "In4.Cu") (net 185))
  (segment (start 86.190557 112.251723) (end 84.825 110.886166) (width 0.109) (layer "In4.Cu") (net 185))
  (segment (start 108.3 94.65) (end 114.75 88.2) (width 0.109) (layer "In4.Cu") (net 185))
  (segment (start 94.114499 112.789499) (end 94.65 113.325) (width 0.109) (layer "In4.Cu") (net 185))
  (segment (start 87.342328 113.403494) (end 86.190557 112.251723) (width 0.109) (layer "In6.Cu") (net 185))
  (segment (start 88.132494 113.403494) (end 87.342328 113.403494) (width 0.109) (layer "In6.Cu") (net 185))
  (segment (start 139.55 87.835) (end 140.09 87.835) (width 0.2) (layer "B.Cu") (net 185))
  (segment (start 140.09 87.835) (end 140.325 87.6) (width 0.2) (layer "B.Cu") (net 185))
  (segment (start 104.9 136.0954) (end 104.9 136.625) (width 0.182) (layer "F.Cu") (net 186))
  (segment (start 105.015 136.74) (end 105.015 137.075) (width 0.182) (layer "F.Cu") (net 186))
  (segment (start 104.9 136.625) (end 105.015 136.74) (width 0.182) (layer "F.Cu") (net 186))
  (segment (start 148.782841 129.833095) (end 149.382843 129.833094) (width 0.109) (layer "F.Cu") (net 186))
  (segment (start 104.715012 137.374988) (end 104.4 137.374988) (width 0.182) (layer "F.Cu") (net 186))
  (segment (start 104.325788 137.4492) (end 104.4 137.374988) (width 0.2) (layer "F.Cu") (net 186))
  (segment (start 105.015 137.075) (end 104.715012 137.374988) (width 0.182) (layer "F.Cu") (net 186))
  (segment (start 103.55 137.4492) (end 104.325788 137.4492) (width 0.2) (layer "F.Cu") (net 186))
  (via (at 148.782841 129.833095) (size 0.45) (drill 0.1) (layers "F.Cu" "B.Cu") (net 186))
  (via (at 104.4 137.374988) (size 0.45) (drill 0.1) (layers "F.Cu" "B.Cu") (net 186))
  (segment (start 138.897495 137.602505) (end 138.025852 137.602505) (width 0.109) (layer "In4.Cu") (net 186))
  (segment (start 114.175 136.375) (end 105.399988 136.375) (width 0.109) (layer "In4.Cu") (net 186))
  (segment (start 146.666905 129.833095) (end 138.897495 137.602505) (width 0.109) (layer "In4.Cu") (net 186))
  (segment (start 130.348719 136.848719) (end 114.648719 136.848719) (width 0.109) (layer "In4.Cu") (net 186))
  (segment (start 131.1 137.6) (end 130.348719 136.848719) (width 0.109) (layer "In4.Cu") (net 186))
  (segment (start 138.025852 137.602505) (end 138.023347 137.6) (width 0.109) (layer "In4.Cu") (net 186))
  (segment (start 148.782841 129.833095) (end 146.666905 129.833095) (width 0.109) (layer "In4.Cu") (net 186))
  (segment (start 105.399988 136.375) (end 104.4 137.374988) (width 0.109) (layer "In4.Cu") (net 186))
  (segment (start 114.648719 136.848719) (end 114.175 136.375) (width 0.109) (layer "In4.Cu") (net 186))
  (segment (start 138.023347 137.6) (end 131.1 137.6) (width 0.109) (layer "In4.Cu") (net 186))
  (segment (start 104.344988 137.43) (end 104.4 137.374988) (width 0.182) (layer "B.Cu") (net 186))
  (segment (start 103.5 137.43) (end 104.344988 137.43) (width 0.182) (layer "B.Cu") (net 186))
  (segment (start 151.25 108.875) (end 150.744499 108.875) (width 0.3) (layer "F.Cu") (net 187))
  (segment (start 144.715 111.665256) (end 144.624872 111.575128) (width 0.4) (layer "F.Cu") (net 187))
  (segment (start 144.715 112.3) (end 144.715 111.665256) (width 0.4) (layer "F.Cu") (net 187))
  (segment (start 150.744499 108.875) (end 150.719499 108.9) (width 0.182) (layer "F.Cu") (net 187))
  (via (at 150.719499 108.9) (size 0.45) (drill 0.1) (layers "F.Cu" "B.Cu") (net 187))
  (via (at 144.624872 111.575128) (size 0.45) (drill 0.1) (layers "F.Cu" "B.Cu") (net 187))
  (segment (start 149.544499 110.075) (end 150.719499 108.9) (width 0.4) (layer "In4.Cu") (net 187))
  (segment (start 146.125 110.075) (end 149.544499 110.075) (width 0.4) (layer "In4.Cu") (net 187))
  (segment (start 146.125 110.075) (end 144.624872 111.575128) (width 0.4) (layer "In4.Cu") (net 187))
  (segment (start 150.8 108.7) (end 150.719499 108.619499) (width 0.4) (layer "B.Cu") (net 187))
  (segment (start 151.365 108.7) (end 150.8 108.7) (width 0.4) (layer "B.Cu") (net 187))
  (segment (start 150.719499 108.419499) (end 150.719499 108.9) (width 0.4) (layer "B.Cu") (net 187))
  (segment (start 150.719499 108.619499) (end 150.719499 108.419499) (width 0.4) (layer "B.Cu") (net 187))
  (segment (start 147.3 107.115) (end 147.536 106.879) (width 0.182) (layer "F.Cu") (net 188))
  (segment (start 147.462 106.13) (end 147.536 106.204) (width 0.182) (layer "F.Cu") (net 188))
  (segment (start 147.2 62.65) (end 147.2 62.925) (width 0.182) (layer "F.Cu") (net 188))
  (segment (start 147.536 106.879) (end 147.536 106.204) (width 0.182) (layer "F.Cu") (net 188))
  (segment (start 147.45 106.13) (end 147.462 106.13) (width 0.182) (layer "F.Cu") (net 188))
  (segment (start 147.2 62.925) (end 146.889 63.236) (width 0.182) (layer "F.Cu") (net 188))
  (segment (start 146.889 63.236) (end 146.889 63.439002) (width 0.182) (layer "F.Cu") (net 188))
  (segment (start 146.889 63.439002) (end 146.998 63.548002) (width 0.182) (layer "F.Cu") (net 188))
  (via (at 147.45 106.13) (size 0.45) (drill 0.1) (layers "F.Cu" "B.Cu") (net 188))
  (via (at 146.998 63.548002) (size 0.45) (drill 0.1) (layers "F.Cu" "B.Cu") (net 188))
  (segment (start 147.462 106.13) (end 147.6075 105.9845) (width 0.109) (layer "In6.Cu") (net 188))
  (segment (start 147.247186 105.1275) (end 137.817186 105.1275) (width 0.109) (layer "In6.Cu") (net 188))
  (segment (start 132.3325 87.122814) (end 132.3325 80.937186) (width 0.109) (layer "In6.Cu") (net 188))
  (segment (start 142.967186 62.4325) (end 146.502814 62.4325) (width 0.109) (layer "In6.Cu") (net 188))
  (segment (start 132.8025 100.112814) (end 132.8025 87.592814) (width 0.109) (layer "In6.Cu") (net 188))
  (segment (start 132.3325 80.937186) (end 140.4925 72.777186) (width 0.109) (layer "In6.Cu") (net 188))
  (segment (start 146.8275 63.377502) (end 146.998 63.548002) (width 0.109) (layer "In6.Cu") (net 188))
  (segment (start 147.6075 105.487814) (end 147.247186 105.1275) (width 0.109) (layer "In6.Cu") (net 188))
  (segment (start 137.817186 105.1275) (end 132.8025 100.112814) (width 0.109) (layer "In6.Cu") (net 188))
  (segment (start 140.4925 64.907186) (end 142.967186 62.4325) (width 0.109) (layer "In6.Cu") (net 188))
  (segment (start 146.502814 62.4325) (end 146.8275 62.757186) (width 0.109) (layer "In6.Cu") (net 188))
  (segment (start 140.4925 72.777186) (end 140.4925 64.907186) (width 0.109) (layer "In6.Cu") (net 188))
  (segment (start 146.8275 62.757186) (end 146.8275 63.377502) (width 0.109) (layer "In6.Cu") (net 188))
  (segment (start 147.45 106.13) (end 147.462 106.13) (width 0.109) (layer "In6.Cu") (net 188))
  (segment (start 132.8025 87.592814) (end 132.3325 87.122814) (width 0.109) (layer "In6.Cu") (net 188))
  (segment (start 147.6075 105.9845) (end 147.6075 105.487814) (width 0.109) (layer "In6.Cu") (net 188))
  (segment (start 148.15 107.115) (end 147.914 106.879) (width 0.182) (layer "F.Cu") (net 189))
  (segment (start 146.511 63.236) (end 146.511 63.439002) (width 0.182) (layer "F.Cu") (net 189))
  (segment (start 147.914 106.221) (end 147.914 106.879) (width 0.182) (layer "F.Cu") (net 189))
  (segment (start 146.2 62.925) (end 146.511 63.236) (width 0.182) (layer "F.Cu") (net 189))
  (segment (start 148.02 106.13) (end 148.005 106.13) (width 0.182) (layer "F.Cu") (net 189))
  (segment (start 146.511 63.439002) (end 146.402 63.548002) (width 0.182) (layer "F.Cu") (net 189))
  (segment (start 146.2 62.65) (end 146.2 62.925) (width 0.182) (layer "F.Cu") (net 189))
  (segment (start 148.005 106.13) (end 147.914 106.221) (width 0.182) (layer "F.Cu") (net 189))
  (via (at 148.02 106.13) (size 0.45) (drill 0.1) (layers "F.Cu" "B.Cu") (net 189))
  (via (at 146.402 63.548002) (size 0.45) (drill 0.1) (layers "F.Cu" "B.Cu") (net 189))
  (segment (start 147.8625 105.382186) (end 147.352814 104.8725) (width 0.109) (layer "In6.Cu") (net 189))
  (segment (start 142.369272 63.810697) (end 142.360551 63.772492) (width 0.109) (layer "In6.Cu") (net 189))
  (segment (start 142.268749 63.631673) (end 142.26003 63.593467) (width 0.109) (layer "In6.Cu") (net 189))
  (segment (start 142.838522 63.242213) (end 142.814088 63.211576) (width 0.109) (layer "In6.Cu") (net 189))
  (segment (start 142.37613 63.408697) (end 142.414335 63.399976) (width 0.109) (layer "In6.Cu") (net 189))
  (segment (start 142.783451 63.483496) (end 142.814089 63.459062) (width 0.109) (layer "In6.Cu") (net 189))
  (segment (start 142.755003 63.059306) (end 142.763722 63.021102) (width 0.109) (layer "In6.Cu") (net 189))
  (segment (start 142.755003 63.098494) (end 142.755003 63.059306) (width 0.109) (layer "In6.Cu") (net 189))
  (segment (start 137.922814 104.8725) (end 133.0575 100.007186) (width 0.109) (layer "In6.Cu") (net 189))
  (segment (start 143.072814 62.6875) (end 146.397186 62.6875) (width 0.109) (layer "In6.Cu") (net 189))
  (segment (start 142.597239 63.483497) (end 142.632547 63.500498) (width 0.109) (layer "In6.Cu") (net 189))
  (segment (start 142.670751 63.509219) (end 142.709939 63.509219) (width 0.109) (layer "In6.Cu") (net 189))
  (segment (start 142.310184 63.697618) (end 142.285752 63.666979) (width 0.109) (layer "In6.Cu") (net 189))
  (segment (start 142.268749 63.516075) (end 142.285751 63.480769) (width 0.109) (layer "In6.Cu") (net 189))
  (segment (start 142.343548 63.923398) (end 142.360551 63.88809) (width 0.109) (layer "In6.Cu") (net 189))
  (segment (start 142.253172 63.995471) (end 142.288478 63.978469) (width 0.109) (layer "In6.Cu") (net 189))
  (segment (start 142.855524 63.393117) (end 142.864245 63.354912) (width 0.109) (layer "In6.Cu") (net 189))
  (segment (start 140.7475 72.882814) (end 140.7475 65.012814) (width 0.109) (layer "In6.Cu") (net 189))
  (segment (start 141.95855 63.894949) (end 141.996755 63.90367) (width 0.109) (layer "In6.Cu") (net 189))
  (segment (start 142.319115 63.706549) (end 142.310184 63.697618) (width 0.109) (layer "In6.Cu") (net 189))
  (segment (start 140.7475 65.012814) (end 141.815211 63.945104) (width 0.109) (layer "In6.Cu") (net 189))
  (segment (start 142.748145 63.500498) (end 142.783451 63.483496) (width 0.109) (layer "In6.Cu") (net 189))
  (segment (start 142.491728 63.408697) (end 142.527034 63.425699) (width 0.109) (layer "In6.Cu") (net 189))
  (segment (start 141.996755 63.90367) (end 142.032061 63.920672) (width 0.109) (layer "In6.Cu") (net 189))
  (segment (start 142.855524 63.277519) (end 142.838522 63.242213) (width 0.109) (layer "In6.Cu") (net 189))
  (segment (start 142.864245 63.354912) (end 142.864245 63.315724) (width 0.109) (layer "In6.Cu") (net 189))
  (segment (start 142.763722 63.1367) (end 142.755003 63.098494) (width 0.109) (layer "In6.Cu") (net 189))
  (segment (start 142.285752 63.666979) (end 142.268749 63.631673) (width 0.109) (layer "In6.Cu") (net 189))
  (segment (start 147.8625 105.9845) (end 147.8625 105.382186) (width 0.109) (layer "In6.Cu") (net 189))
  (segment (start 133.0575 87.487186) (end 132.5875 87.017186) (width 0.109) (layer "In6.Cu") (net 189))
  (segment (start 142.288478 63.978469) (end 142.319116 63.954035) (width 0.109) (layer "In6.Cu") (net 189))
  (segment (start 132.5875 87.017186) (end 132.5875 81.042814) (width 0.109) (layer "In6.Cu") (net 189))
  (segment (start 142.838521 63.428425) (end 142.855524 63.393117) (width 0.109) (layer "In6.Cu") (net 189))
  (segment (start 142.137574 63.995471) (end 142.175778 64.004192) (width 0.109) (layer "In6.Cu") (net 189))
  (segment (start 142.102266 63.97847) (end 142.137574 63.995471) (width 0.109) (layer "In6.Cu") (net 189))
  (segment (start 142.310184 63.45013) (end 142.340822 63.4257) (width 0.109) (layer "In6.Cu") (net 189))
  (segment (start 142.814088 63.211576) (end 142.805157 63.202645) (width 0.109) (layer "In6.Cu") (net 189))
  (segment (start 142.709939 63.509219) (end 142.748145 63.500498) (width 0.109) (layer "In6.Cu") (net 189))
  (segment (start 141.919362 63.894949) (end 141.95855 63.894949) (width 0.109) (layer "In6.Cu") (net 189))
  (segment (start 142.319116 63.954035) (end 142.343548 63.923398) (width 0.109) (layer "In6.Cu") (net 189))
  (segment (start 142.805157 62.955157) (end 143.072814 62.6875) (width 0.109) (layer "In6.Cu") (net 189))
  (segment (start 142.071628 63.954036) (end 142.102266 63.97847) (width 0.109) (layer "In6.Cu") (net 189))
  (segment (start 142.414335 63.399976) (end 142.453523 63.399976) (width 0.109) (layer "In6.Cu") (net 189))
  (segment (start 146.5725 62.862814) (end 146.5725 63.377502) (width 0.109) (layer "In6.Cu") (net 189))
  (segment (start 141.845849 63.920673) (end 141.881157 63.90367) (width 0.109) (layer "In6.Cu") (net 189))
  (segment (start 147.352814 104.8725) (end 137.922814 104.8725) (width 0.109) (layer "In6.Cu") (net 189))
  (segment (start 146.397186 62.6875) (end 146.5725 62.862814) (width 0.109) (layer "In6.Cu") (net 189))
  (segment (start 142.26003 63.593467) (end 142.26003 63.554279) (width 0.109) (layer "In6.Cu") (net 189))
  (segment (start 141.815211 63.945104) (end 141.845849 63.920673) (width 0.109) (layer "In6.Cu") (net 189))
  (segment (start 133.0575 100.007186) (end 133.0575 87.487186) (width 0.109) (layer "In6.Cu") (net 189))
  (segment (start 142.062698 63.945106) (end 142.071628 63.954036) (width 0.109) (layer "In6.Cu") (net 189))
  (segment (start 142.527034 63.425699) (end 142.557671 63.450133) (width 0.109) (layer "In6.Cu") (net 189))
  (segment (start 142.763722 63.021102) (end 142.780724 62.985796) (width 0.109) (layer "In6.Cu") (net 189))
  (segment (start 142.175778 64.004192) (end 142.214966 64.004192) (width 0.109) (layer "In6.Cu") (net 189))
  (segment (start 142.360551 63.88809) (end 142.369272 63.849885) (width 0.109) (layer "In6.Cu") (net 189))
  (segment (start 132.5875 81.042814) (end 140.7475 72.882814) (width 0.109) (layer "In6.Cu") (net 189))
  (segment (start 142.369272 63.849885) (end 142.369272 63.810697) (width 0.109) (layer "In6.Cu") (net 189))
  (segment (start 142.340822 63.4257) (end 142.37613 63.408697) (width 0.109) (layer "In6.Cu") (net 189))
  (segment (start 142.360551 63.772492) (end 142.343549 63.737186) (width 0.109) (layer "In6.Cu") (net 189))
  (segment (start 148.008 106.13) (end 147.8625 105.9845) (width 0.109) (layer "In6.Cu") (net 189))
  (segment (start 146.5725 63.377502) (end 146.402 63.548002) (width 0.109) (layer "In6.Cu") (net 189))
  (segment (start 142.285751 63.480769) (end 142.310184 63.45013) (width 0.109) (layer "In6.Cu") (net 189))
  (segment (start 142.780724 62.985796) (end 142.805157 62.955157) (width 0.109) (layer "In6.Cu") (net 189))
  (segment (start 142.557671 63.450133) (end 142.566601 63.459063) (width 0.109) (layer "In6.Cu") (net 189))
  (segment (start 148.02 106.13) (end 148.008 106.13) (width 0.109) (layer "In6.Cu") (net 189))
  (segment (start 141.881157 63.90367) (end 141.919362 63.894949) (width 0.109) (layer "In6.Cu") (net 189))
  (segment (start 142.343549 63.737186) (end 142.319115 63.706549) (width 0.109) (layer "In6.Cu") (net 189))
  (segment (start 142.780725 63.172006) (end 142.763722 63.1367) (width 0.109) (layer "In6.Cu") (net 189))
  (segment (start 142.864245 63.315724) (end 142.855524 63.277519) (width 0.109) (layer "In6.Cu") (net 189))
  (segment (start 142.26003 63.554279) (end 142.268749 63.516075) (width 0.109) (layer "In6.Cu") (net 189))
  (segment (start 142.566601 63.459063) (end 142.597239 63.483497) (width 0.109) (layer "In6.Cu") (net 189))
  (segment (start 142.032061 63.920672) (end 142.062698 63.945106) (width 0.109) (layer "In6.Cu") (net 189))
  (segment (start 142.453523 63.399976) (end 142.491728 63.408697) (width 0.109) (layer "In6.Cu") (net 189))
  (segment (start 142.214966 64.004192) (end 142.253172 63.995471) (width 0.109) (layer "In6.Cu") (net 189))
  (segment (start 142.814089 63.459062) (end 142.838521 63.428425) (width 0.109) (layer "In6.Cu") (net 189))
  (segment (start 142.805157 63.202645) (end 142.780725 63.172006) (width 0.109) (layer "In6.Cu") (net 189))
  (segment (start 142.632547 63.500498) (end 142.670751 63.509219) (width 0.109) (layer "In6.Cu") (net 189))
  (segment (start 140 93.65) (end 140.25 93.4) (width 0.182) (layer "F.Cu") (net 190))
  (segment (start 139.45 93.65) (end 140 93.65) (width 0.182) (layer "F.Cu") (net 190))
  (via (at 140.25 93.4) (size 0.45) (drill 0.1) (layers "F.Cu" "B.Cu") (net 190))
  (segment (start 140.25 93.4) (end 140.25 93.385) (width 0.182) (layer "B.Cu") (net 190))
  (segment (start 140.25 93.385) (end 139.465 92.6) (width 0.182) (layer "B.Cu") (net 190))
  (segment (start 177.525 137.825) (end 178.390001 137.825) (width 0.182) (layer "F.Cu") (net 191))
  (segment (start 178.390001 137.825) (end 178.49 137.725001) (width 0.182) (layer "F.Cu") (net 191))
  (segment (start 187.025 137.675) (end 187.89 137.675) (width 0.182) (layer "F.Cu") (net 192))
  (segment (start 187.89 137.675) (end 187.99 137.575) (width 0.182) (layer "F.Cu") (net 192))
  (segment (start 83.565 93.25) (end 83.565 93.295) (width 0.182) (layer "F.Cu") (net 193))
  (segment (start 81.259822 123.025) (end 80.352822 123.025) (width 0.182) (layer "F.Cu") (net 193))
  (segment (start 80.352822 123.025) (end 78.475 121.147178) (width 0.182) (layer "F.Cu") (net 193))
  (segment (start 78.475 121.147178) (end 78.475 119.735) (width 0.182) (layer "F.Cu") (net 193))
  (segment (start 81.6 93.0492) (end 82.0492 93.0492) (width 0.2) (layer "F.Cu") (net 193))
  (segment (start 83.565 93.295) (end 83.26 93.6) (width 0.182) (layer "F.Cu") (net 193))
  (segment (start 82.6 93.6) (end 82.9 93.6) (width 0.2) (layer "F.Cu") (net 193))
  (segment (start 81.259822 123.025) (end 82.325 123.025) (width 0.182) (layer "F.Cu") (net 193))
  (segment (start 83.26 93.6) (end 82.9 93.6) (width 0.182) (layer "F.Cu") (net 193))
  (segment (start 82.0492 93.0492) (end 82.6 93.6) (width 0.2) (layer "F.Cu") (net 193))
  (via (at 82.325 123.025) (size 0.45) (drill 0.1) (layers "F.Cu" "B.Cu") (net 193))
  (via (at 82.9 93.6) (size 0.45) (drill 0.1) (layers "F.Cu" "B.Cu") (net 193))
  (segment (start 81.2 117.075) (end 80.6 117.675) (width 0.109) (layer "In4.Cu") (net 193))
  (segment (start 81.2 99.375) (end 81.2 117.075) (width 0.109) (layer "In4.Cu") (net 193))
  (segment (start 81.8 123.025) (end 82.325 123.025) (width 0.109) (layer "In4.Cu") (net 193))
  (segment (start 81.475 94.3) (end 81.475 99.1) (width 0.109) (layer "In4.Cu") (net 193))
  (segment (start 81.475 99.1) (end 81.2 99.375) (width 0.109) (layer "In4.Cu") (net 193))
  (segment (start 82.9 93.6) (end 82.175 93.6) (width 0.109) (layer "In4.Cu") (net 193))
  (segment (start 82.175 93.6) (end 81.475 94.3) (width 0.109) (layer "In4.Cu") (net 193))
  (segment (start 80.6 117.675) (end 80.6 121.825) (width 0.109) (layer "In4.Cu") (net 193))
  (segment (start 80.6 121.825) (end 81.8 123.025) (width 0.109) (layer "In4.Cu") (net 193))
  (segment (start 81.9 93.75) (end 82.75 93.75) (width 0.182) (layer "B.Cu") (net 193))
  (segment (start 82.75 93.75) (end 82.9 93.6) (width 0.182) (layer "B.Cu") (net 193))
  (segment (start 82.1992 94.0492) (end 82.35 94.2) (width 0.2) (layer "F.Cu") (net 194))
  (segment (start 82.9 94.2) (end 83.512 94.2) (width 0.182) (layer "F.Cu") (net 194))
  (segment (start 80.3 122.375) (end 81.259822 122.375) (width 0.182) (layer "F.Cu") (net 194))
  (segment (start 81.6 94.0492) (end 82.1992 94.0492) (width 0.2) (layer "F.Cu") (net 194))
  (segment (start 83.512 94.2) (end 83.561 94.249) (width 0.182) (layer "F.Cu") (net 194))
  (segment (start 79.65 119.96) (end 79.65 121.725) (width 0.182) (layer "F.Cu") (net 194))
  (segment (start 81.259822 122.375) (end 82.275 122.375) (width 0.182) (layer "F.Cu") (net 194))
  (segment (start 82.275 122.375) (end 82.3 122.4) (width 0.2) (layer "F.Cu") (net 194))
  (segment (start 79.65 121.725) (end 80.3 122.375) (width 0.182) (layer "F.Cu") (net 194))
  (segment (start 79.425 119.735) (end 79.65 119.96) (width 0.182) (layer "F.Cu") (net 194))
  (segment (start 82.35 94.2) (end 82.9 94.2) (width 0.2) (layer "F.Cu") (net 194))
  (via (at 82.9 94.2) (size 0.45) (drill 0.1) (layers "F.Cu" "B.Cu") (net 194))
  (via (at 82.3 122.4) (size 0.45) (drill 0.1) (layers "F.Cu" "B.Cu") (net 194))
  (segment (start 81.85 94.625) (end 81.85 99.625) (width 0.109) (layer "In4.Cu") (net 194))
  (segment (start 81.175 118) (end 81.175 121.7) (width 0.109) (layer "In4.Cu") (net 194))
  (segment (start 82.9 94.2) (end 82.275 94.2) (width 0.109) (layer "In4.Cu") (net 194))
  (segment (start 81.85 99.625) (end 81.675 99.8) (width 0.109) (layer "In4.Cu") (net 194))
  (segment (start 81.875 122.4) (end 82.3 122.4) (width 0.109) (layer "In4.Cu") (net 194))
  (segment (start 81.675 99.8) (end 81.675 117.5) (width 0.109) (layer "In4.Cu") (net 194))
  (segment (start 81.175 121.7) (end 81.875 122.4) (width 0.109) (layer "In4.Cu") (net 194))
  (segment (start 82.275 94.2) (end 81.85 94.625) (width 0.109) (layer "In4.Cu") (net 194))
  (segment (start 81.675 117.5) (end 81.175 118) (width 0.109) (layer "In4.Cu") (net 194))
  (segment (start 81.9 94.25) (end 82.85 94.25) (width 0.182) (layer "B.Cu") (net 194))
  (segment (start 82.85 94.25) (end 82.9 94.2) (width 0.182) (layer "B.Cu") (net 194))
  (segment (start 81.6 95.15) (end 81.95 94.8) (width 0.2) (layer "F.Cu") (net 195))
  (segment (start 82.9 94.8) (end 83.111 94.8) (width 0.182) (layer "F.Cu") (net 195))
  (segment (start 81.259822 121.075) (end 80.25 121.075) (width 0.182) (layer "F.Cu") (net 195))
  (segment (start 81.95 94.8) (end 82.9 94.8) (width 0.2) (layer "F.Cu") (net 195))
  (segment (start 80.025 120.85) (end 80.025 120.085) (width 0.182) (layer "F.Cu") (net 195))
  (segment (start 83.111 94.8) (end 83.561 95.25) (width 0.182) (layer "F.Cu") (net 195))
  (segment (start 82.325 121.075) (end 82.35 121.1) (width 0.182) (layer "F.Cu") (net 195))
  (segment (start 80.25 121.075) (end 80.025 120.85) (width 0.182) (layer "F.Cu") (net 195))
  (segment (start 81.259822 121.075) (end 82.325 121.075) (width 0.182) (layer "F.Cu") (net 195))
  (segment (start 80.025 120.085) (end 80.375 119.735) (width 0.182) (layer "F.Cu") (net 195))
  (via (at 82.9 94.8) (size 0.45) (drill 0.1) (layers "F.Cu" "B.Cu") (net 195))
  (via (at 82.35 121.1) (size 0.45) (drill 0.1) (layers "F.Cu" "B.Cu") (net 195))
  (segment (start 81.65 118.275) (end 82.175 117.75) (width 0.109) (layer "In4.Cu") (net 195))
  (segment (start 82.35 121.1) (end 81.875 121.1) (width 0.109) (layer "In4.Cu") (net 195))
  (segment (start 81.65 120.875) (end 81.65 118.275) (width 0.109) (layer "In4.Cu") (net 195))
  (segment (start 81.875 121.1) (end 81.65 120.875) (width 0.109) (layer "In4.Cu") (net 195))
  (segment (start 82.475 94.8) (end 82.9 94.8) (width 0.109) (layer "In4.Cu") (net 195))
  (segment (start 82.175 117.75) (end 82.175 95.1) (width 0.109) (layer "In4.Cu") (net 195))
  (segment (start 82.175 95.1) (end 82.475 94.8) (width 0.109) (layer "In4.Cu") (net 195))
  (segment (start 81.95 94.8) (end 81.9 94.75) (width 0.109) (layer "B.Cu") (net 195))
  (segment (start 82.9 94.8) (end 81.95 94.8) (width 0.182) (layer "B.Cu") (net 195))
  (segment (start 81.325 119.735) (end 81.325 120.2) (width 0.182) (layer "F.Cu") (net 196))
  (segment (start 81.425 120.3) (end 82.575 120.3) (width 0.182) (layer "F.Cu") (net 196))
  (segment (start 83.625 121.075) (end 83.6 121.1) (width 0.182) (layer "F.Cu") (net 196))
  (segment (start 82.1508 96.1492) (end 82.6 95.7) (width 0.2) (layer "F.Cu") (net 196))
  (segment (start 83.015 95.7) (end 83.565 96.25) (width 0.182) (layer "F.Cu") (net 196))
  (segment (start 83 95.7) (end 83.015 95.7) (width 0.182) (layer "F.Cu") (net 196))
  (segment (start 85.659822 121.075) (end 83.625 121.075) (width 0.182) (layer "F.Cu") (net 196))
  (segment (start 82.6 95.7) (end 83 95.7) (width 0.2) (layer "F.Cu") (net 196))
  (segment (start 81.325 120.2) (end 81.425 120.3) (width 0.182) (layer "F.Cu") (net 196))
  (segment (start 81.6 96.1492) (end 82.1508 96.1492) (width 0.2) (layer "F.Cu") (net 196))
  (via (at 82.575 120.3) (size 0.45) (drill 0.1) (layers "F.Cu" "B.Cu") (net 196))
  (via (at 83 95.7) (size 0.45) (drill 0.1) (layers "F.Cu" "B.Cu") (net 196))
  (via (at 83.6 121.1) (size 0.45) (drill 0.1) (layers "F.Cu" "B.Cu") (net 196))
  (segment (start 82.59 118.185) (end 82.59 96.635) (width 0.109) (layer "In4.Cu") (net 196))
  (segment (start 82.575 120.3) (end 82.2 120.3) (width 0.109) (layer "In4.Cu") (net 196))
  (segment (start 82.2 120.3) (end 82.1 120.2) (width 0.109) (layer "In4.Cu") (net 196))
  (segment (start 82.1 118.675) (end 82.59 118.185) (width 0.109) (layer "In4.Cu") (net 196))
  (segment (start 82.1 120.2) (end 82.1 118.675) (width 0.109) (layer "In4.Cu") (net 196))
  (segment (start 82.59 96.635) (end 83 96.225) (width 0.109) (layer "In4.Cu") (net 196))
  (segment (start 83 96.225) (end 83 95.7) (width 0.109) (layer "In4.Cu") (net 196))
  (segment (start 83.6 121.1) (end 83.2125 120.7125) (width 0.109) (layer "In6.Cu") (net 196))
  (segment (start 82.575 120.6) (end 82.575 120.3) (width 0.109) (layer "In6.Cu") (net 196))
  (segment (start 83.2125 120.7125) (end 82.6875 120.7125) (width 0.109) (layer "In6.Cu") (net 196))
  (segment (start 82.6875 120.7125) (end 82.575 120.6) (width 0.109) (layer "In6.Cu") (net 196))
  (segment (start 82.625 95.25) (end 83 95.625) (width 0.182) (layer "B.Cu") (net 196))
  (segment (start 83 95.625) (end 83 95.7) (width 0.182) (layer "B.Cu") (net 196))
  (segment (start 81.9 95.25) (end 82.625 95.25) (width 0.182) (layer "B.Cu") (net 196))
  (segment (start 93.3265 127.464) (end 93.7115 127.154) (width 0.182) (layer "F.Cu") (net 197))
  (via (at 93.7115 127.154) (size 0.45) (drill 0.1) (layers "F.Cu" "B.Cu") (net 197))
  (via (at 80.175 97.75) (size 0.45) (drill 0.1) (layers "F.Cu" "B.Cu") (net 197))
  (segment (start 80.925 97.75) (end 80.175 97.75) (width 0.109) (layer "In4.Cu") (net 197))
  (segment (start 93.331999 126.779499) (end 93.331999 126.256999) (width 0.109) (layer "In4.Cu") (net 197))
  (segment (start 81.775 124.275) (end 79.825 122.325) (width 0.109) (layer "In4.Cu") (net 197))
  (segment (start 79.825 122.325) (end 79.825 117.3) (width 0.109) (layer "In4.Cu") (net 197))
  (segment (start 89.1 125.725) (end 87.65 124.275) (width 0.109) (layer "In4.Cu") (net 197))
  (segment (start 81.175 98) (end 80.925 97.75) (width 0.109) (layer "In4.Cu") (net 197))
  (segment (start 81.175 98.575) (end 81.175 98) (width 0.109) (layer "In4.Cu") (net 197))
  (segment (start 87.65 124.275) (end 81.775 124.275) (width 0.109) (layer "In4.Cu") (net 197))
  (segment (start 80.6 99.15) (end 81.175 98.575) (width 0.109) (layer "In4.Cu") (net 197))
  (segment (start 92.8 125.725) (end 89.1 125.725) (width 0.109) (layer "In4.Cu") (net 197))
  (segment (start 79.825 117.3) (end 80.6 116.525) (width 0.109) (layer "In4.Cu") (net 197))
  (segment (start 80.6 116.525) (end 80.6 99.15) (width 0.109) (layer "In4.Cu") (net 197))
  (segment (start 93.331999 126.256999) (end 92.8 125.725) (width 0.109) (layer "In4.Cu") (net 197))
  (segment (start 93.7065 127.154) (end 93.331999 126.779499) (width 0.109) (layer "In4.Cu") (net 197))
  (segment (start 81.9 97.75) (end 80.175 97.75) (width 0.182) (layer "B.Cu") (net 197))
  (segment (start 94.575 147.235) (end 94.565 147.225) (width 0.182) (layer "F.Cu") (net 198))
  (segment (start 94.575 148.075) (end 94.575 147.235) (width 0.182) (layer "F.Cu") (net 198))
  (segment (start 113.3 146.5) (end 113.3 147.2) (width 0.2) (layer "F.Cu") (net 198))
  (segment (start 92.775 147.225) (end 91.7 148.3) (width 0.182) (layer "F.Cu") (net 198))
  (segment (start 88.575 140.025) (end 88.575 122.7625) (width 0.182) (layer "F.Cu") (net 198))
  (segment (start 86.33125 120.46875) (end 87.51875 120.46875) (width 0.2) (layer "F.Cu") (net 198))
  (segment (start 87.3 148.3) (end 85.8 146.8) (width 0.182) (layer "F.Cu") (net 198))
  (segment (start 85.475 119.6125) (end 85.475 113.95) (width 0.182) (layer "F.Cu") (net 198))
  (segment (start 80.7 109.175) (end 80.7 98.250008) (width 0.182) (layer "F.Cu") (net 198))
  (segment (start 85.8 142.8) (end 88.575 140.025) (width 0.182) (layer "F.Cu") (net 198))
  (segment (start 87.51875 120.46875) (end 88.6 121.55) (width 0.2) (layer "F.Cu") (net 198))
  (segment (start 88.6 121.55) (end 88.6 122.7375) (width 0.2) (layer "F.Cu") (net 198))
  (segment (start 85.8 146.8) (end 85.8 142.8) (width 0.182) (layer "F.Cu") (net 198))
  (segment (start 88.575 122.7625) (end 88.6 122.7375) (width 0.182) (layer "F.Cu") (net 198))
  (segment (start 94.564999 147.225) (end 92.775 147.225) (width 0.182) (layer "F.Cu") (net 198))
  (segment (start 91.7 148.3) (end 87.3 148.3) (width 0.182) (layer "F.Cu") (net 198))
  (segment (start 113.3 148.4) (end 113.3 147.2) (width 0.182) (layer "F.Cu") (net 198))
  (segment (start 86.33125 120.46875) (end 85.475 119.6125) (width 0.182) (layer "F.Cu") (net 198))
  (segment (start 85.475 113.95) (end 80.7 109.175) (width 0.182) (layer "F.Cu") (net 198))
  (via (at 94.575 148.075) (size 0.45) (drill 0.1) (layers "F.Cu" "B.Cu") (net 198))
  (via (at 80.7 98.250008) (size 0.45) (drill 0.1) (layers "F.Cu" "B.Cu") (net 198))
  (via (at 113.3 147.2) (size 0.45) (drill 0.1) (layers "F.Cu" "B.Cu") (net 198))
  (segment (start 96.75 144.25) (end 98.9 144.25) (width 0.109) (layer "In6.Cu") (net 198))
  (segment (start 94.575 146.425) (end 96.75 144.25) (width 0.109) (layer "In6.Cu") (net 198))
  (segment (start 112.2 148.6) (end 113.3 147.5) (width 0.109) (layer "In6.Cu") (net 198))
  (segment (start 104.9 148.6) (end 112.2 148.6) (width 0.109) (layer "In6.Cu") (net 198))
  (segment (start 102.15 147.5) (end 103.8 147.5) (width 0.109) (layer "In6.Cu") (net 198))
  (segment (start 113.3 147.5) (end 113.3 147.2) (width 0.109) (layer "In6.Cu") (net 198))
  (segment (start 103.8 147.5) (end 104.9 148.6) (width 0.109) (layer "In6.Cu") (net 198))
  (segment (start 98.9 144.25) (end 102.15 147.5) (width 0.109) (layer "In6.Cu") (net 198))
  (segment (start 94.575 148.075) (end 94.575 146.425) (width 0.109) (layer "In6.Cu") (net 198))
  (segment (start 94.575 147.445) (end 94.575 148.075) (width 0.182) (layer "B.Cu") (net 198))
  (segment (start 80.700008 98.25) (end 80.7 98.250008) (width 0.182) (layer "B.Cu") (net 198))
  (segment (start 81.9 98.25) (end 80.700008 98.25) (width 0.182) (layer "B.Cu") (net 198))
  (segment (start 91.9815 126.504) (end 92.3665 126.194) (width 0.182) (layer "F.Cu") (net 199))
  (via (at 91.9815 126.504) (size 0.45) (drill 0.1) (layers "F.Cu" "B.Cu") (net 199))
  (via (at 80.2 98.75) (size 0.45) (drill 0.1) (layers "F.Cu" "B.Cu") (net 199))
  (segment (start 91.491511 126.009011) (end 88.159011 126.009011) (width 0.109) (layer "In4.Cu") (net 199))
  (segment (start 79.2 122.8) (end 79.2 117.175) (width 0.109) (layer "In4.Cu") (net 199))
  (segment (start 87.055 124.905) (end 81.305 124.905) (width 0.109) (layer "In4.Cu") (net 199))
  (segment (start 80.2 116.175) (end 80.2 98.75) (width 0.109) (layer "In4.Cu") (net 199))
  (segment (start 81.305 124.905) (end 79.2 122.8) (width 0.109) (layer "In4.Cu") (net 199))
  (segment (start 79.2 117.175) (end 80.2 116.175) (width 0.109) (layer "In4.Cu") (net 199))
  (segment (start 91.9865 126.504) (end 91.491511 126.009011) (width 0.109) (layer "In4.Cu") (net 199))
  (segment (start 88.159011 126.009011) (end 87.055 124.905) (width 0.109) (layer "In4.Cu") (net 199))
  (segment (start 80.2 98.75) (end 81.9 98.75) (width 0.182) (layer "B.Cu") (net 199))
  (segment (start 91.9815 136.664) (end 92.3665 136.354) (width 0.182) (layer "F.Cu") (net 200))
  (via (at 91.9815 136.664) (size 0.45) (drill 0.1) (layers "F.Cu" "B.Cu") (net 200))
  (via (at 78.35 99.872981) (size 0.45) (drill 0.1) (layers "F.Cu" "B.Cu") (net 200))
  (segment (start 91.9815 136.659) (end 91.9815 136.664) (width 0.109) (layer "In6.Cu") (net 200))
  (segment (start 78.1795 100.043481) (end 77.026205 100.043481) (width 0.109) (layer "In6.Cu") (net 200))
  (segment (start 75.018499 124.458813) (end 88.319686 137.76) (width 0.109) (layer "In6.Cu") (net 200))
  (segment (start 90.260314 137.76) (end 91.546314 136.474) (width 0.109) (layer "In6.Cu") (net 200))
  (segment (start 77.026205 100.043481) (end 75.018499 102.051187) (width 0.109) (layer "In6.Cu") (net 200))
  (segment (start 91.546314 136.474) (end 91.7965 136.474) (width 0.109) (layer "In6.Cu") (net 200))
  (segment (start 78.35 99.872981) (end 78.1795 100.043481) (width 0.109) (layer "In6.Cu") (net 200))
  (segment (start 75.018499 102.051187) (end 75.018499 124.458813) (width 0.109) (layer "In6.Cu") (net 200))
  (segment (start 88.319686 137.76) (end 90.260314 137.76) (width 0.109) (layer "In6.Cu") (net 200))
  (segment (start 91.7965 136.474) (end 91.9815 136.659) (width 0.109) (layer "In6.Cu") (net 200))
  (segment (start 80.678288 100.311) (end 80.349269 99.981981) (width 0.182) (layer "B.Cu") (net 200))
  (segment (start 78.459 99.981981) (end 78.35 99.872981) (width 0.182) (layer "B.Cu") (net 200))
  (segment (start 80.999999 100.25) (end 80.938999 100.311) (width 0.182) (layer "B.Cu") (net 200))
  (segment (start 80.938999 100.311) (end 80.678288 100.311) (width 0.182) (layer "B.Cu") (net 200))
  (segment (start 81.9 100.25) (end 80.999999 100.25) (width 0.182) (layer "B.Cu") (net 200))
  (segment (start 80.349269 99.981981) (end 78.459 99.981981) (width 0.182) (layer "B.Cu") (net 200))
  (segment (start 91.9815 136.029) (end 92.3665 135.719) (width 0.182) (layer "F.Cu") (net 201))
  (via (at 91.9815 136.029) (size 0.45) (drill 0.1) (layers "F.Cu" "B.Cu") (net 201))
  (via (at 78.35 100.468982) (size 0.45) (drill 0.1) (layers "F.Cu" "B.Cu") (net 201))
  (segment (start 76.08782 101.475614) (end 76.031838 101.475613) (width 0.109) (layer "In6.Cu") (net 201))
  (segment (start 76.609765 101.213319) (end 76.64467 101.257087) (width 0.109) (layer "In6.Cu") (net 201))
  (segment (start 76.530964 100.934363) (end 76.518507 100.988942) (width 0.109) (layer "In6.Cu") (net 201))
  (segment (start 76.681417 101.418086) (end 76.668959 101.472665) (width 0.109) (layer "In6.Cu") (net 201))
  (segment (start 76.46098 101.638524) (end 76.404998 101.638524) (width 0.109) (layer "In6.Cu") (net 201))
  (segment (start 75.275997 123.557742) (end 75.283393 123.578878) (width 0.109) (layer "In6.Cu") (net 201))
  (segment (start 76.299981 101.601777) (end 76.256212 101.566872) (width 0.109) (layer "In6.Cu") (net 201))
  (segment (start 76.555254 100.883925) (end 76.530964 100.934363) (width 0.109) (layer "In6.Cu") (net 201))
  (segment (start 75.463586 123.796878) (end 75.451673 123.815838) (width 0.109) (layer "In6.Cu") (net 201))
  (segment (start 75.977259 101.488071) (end 75.926821 101.51236) (width 0.109) (layer "In6.Cu") (net 201))
  (segment (start 75.27349 123.95349) (end 75.27349 124.353176) (width 0.109) (layer "In6.Cu") (net 201))
  (segment (start 76.64467 101.523103) (end 76.609766 101.566871) (width 0.109) (layer "In6.Cu") (net 201))
  (segment (start 76.515559 101.626067) (end 76.46098 101.638524) (width 0.109) (layer "In6.Cu") (net 201))
  (segment (start 76.031838 101.475613) (end 75.977259 101.488071) (width 0.109) (layer "In6.Cu") (net 201))
  (segment (start 75.926821 101.51236) (end 75.883052 101.547263) (width 0.109) (layer "In6.Cu") (net 201))
  (segment (start 75.27349 102.156824) (end 75.883052 101.547263) (width 0.109) (layer "In6.Cu") (net 201))
  (segment (start 76.609766 101.566871) (end 76.565997 101.601777) (width 0.109) (layer "In6.Cu") (net 201))
  (segment (start 75.311141 123.613673) (end 75.330101 123.625586) (width 0.109) (layer "In6.Cu") (net 201))
  (segment (start 75.435838 123.831673) (end 75.416878 123.843586) (width 0.109) (layer "In6.Cu") (net 201))
  (segment (start 76.555254 101.149941) (end 76.590157 101.193711) (width 0.109) (layer "In6.Cu") (net 201))
  (segment (start 76.590157 100.840157) (end 76.555254 100.883925) (width 0.109) (layer "In6.Cu") (net 201))
  (segment (start 75.27349 123.53549) (end 75.275997 123.557742) (width 0.109) (layer "In6.Cu") (net 201))
  (segment (start 75.330101 123.625586) (end 75.351237 123.632982) (width 0.109) (layer "In6.Cu") (net 201))
  (segment (start 75.27349 102.156824) (end 75.27349 123.53549) (width 0.109) (layer "In6.Cu") (net 201))
  (segment (start 75.435838 123.657306) (end 75.451673 123.673141) (width 0.109) (layer "In6.Cu") (net 201))
  (segment (start 78.35 100.468981) (end 78.1795 100.298481) (width 0.109) (layer "In6.Cu") (net 201))
  (segment (start 91.440686 136.219) (end 91.7965 136.219) (width 0.109) (layer "In6.Cu") (net 201))
  (segment (start 76.530964 101.099503) (end 76.555254 101.149941) (width 0.109) (layer "In6.Cu") (net 201))
  (segment (start 76.66896 101.307525) (end 76.681416 101.362104) (width 0.109) (layer "In6.Cu") (net 201))
  (segment (start 76.236605 101.547265) (end 76.192837 101.51236) (width 0.109) (layer "In6.Cu") (net 201))
  (segment (start 91.7965 136.219) (end 91.9815 136.034) (width 0.109) (layer "In6.Cu") (net 201))
  (segment (start 75.47349 123.73549) (end 75.47349 123.75349) (width 0.109) (layer "In6.Cu") (net 201))
  (segment (start 75.283393 123.578878) (end 75.295306 123.597838) (width 0.109) (layer "In6.Cu") (net 201))
  (segment (start 75.470982 123.775742) (end 75.463586 123.796878) (width 0.109) (layer "In6.Cu") (net 201))
  (segment (start 77.131832 100.298482) (end 76.590157 100.840157) (width 0.109) (layer "In6.Cu") (net 201))
  (segment (start 76.404998 101.638524) (end 76.350419 101.626067) (width 0.109) (layer "In6.Cu") (net 201))
  (segment (start 75.451673 123.815838) (end 75.435838 123.831673) (width 0.109) (layer "In6.Cu") (net 201))
  (segment (start 91.9815 136.034) (end 91.9815 136.029) (width 0.109) (layer "In6.Cu") (net 201))
  (segment (start 75.351237 123.632982) (end 75.395742 123.637997) (width 0.109) (layer "In6.Cu") (net 201))
  (segment (start 75.395742 123.850982) (end 75.351237 123.855997) (width 0.109) (layer "In6.Cu") (net 201))
  (segment (start 75.416878 123.645393) (end 75.435838 123.657306) (width 0.109) (layer "In6.Cu") (net 201))
  (segment (start 75.295306 123.597838) (end 75.311141 123.613673) (width 0.109) (layer "In6.Cu") (net 201))
  (segment (start 75.395742 123.637997) (end 75.416878 123.645393) (width 0.109) (layer "In6.Cu") (net 201))
  (segment (start 75.451673 123.673141) (end 75.463586 123.692101) (width 0.109) (layer "In6.Cu") (net 201))
  (segment (start 75.27349 124.353176) (end 88.420314 137.5) (width 0.109) (layer "In6.Cu") (net 201))
  (segment (start 76.256212 101.566872) (end 76.236605 101.547265) (width 0.109) (layer "In6.Cu") (net 201))
  (segment (start 75.351237 123.855997) (end 75.330101 123.863393) (width 0.109) (layer "In6.Cu") (net 201))
  (segment (start 75.295306 123.891141) (end 75.283393 123.910101) (width 0.109) (layer "In6.Cu") (net 201))
  (segment (start 75.311141 123.875306) (end 75.295306 123.891141) (width 0.109) (layer "In6.Cu") (net 201))
  (segment (start 76.668959 101.472665) (end 76.64467 101.523103) (width 0.109) (layer "In6.Cu") (net 201))
  (segment (start 88.420314 137.5) (end 90.159686 137.5) (width 0.109) (layer "In6.Cu") (net 201))
  (segment (start 76.142399 101.48807) (end 76.08782 101.475614) (width 0.109) (layer "In6.Cu") (net 201))
  (segment (start 78.35 100.468982) (end 78.35 100.468981) (width 0.109) (layer "In6.Cu") (net 201))
  (segment (start 76.350419 101.626067) (end 76.299981 101.601777) (width 0.109) (layer "In6.Cu") (net 201))
  (segment (start 76.192837 101.51236) (end 76.142399 101.48807) (width 0.109) (layer "In6.Cu") (net 201))
  (segment (start 75.470982 123.713237) (end 75.47349 123.73549) (width 0.109) (layer "In6.Cu") (net 201))
  (segment (start 75.463586 123.692101) (end 75.470982 123.713237) (width 0.109) (layer "In6.Cu") (net 201))
  (segment (start 90.159686 137.5) (end 91.440686 136.219) (width 0.109) (layer "In6.Cu") (net 201))
  (segment (start 75.47349 123.75349) (end 75.470982 123.775742) (width 0.109) (layer "In6.Cu") (net 201))
  (segment (start 76.64467 101.257087) (end 76.66896 101.307525) (width 0.109) (layer "In6.Cu") (net 201))
  (segment (start 75.275997 123.931237) (end 75.27349 123.95349) (width 0.109) (layer "In6.Cu") (net 201))
  (segment (start 76.518507 101.044924) (end 76.530964 101.099503) (width 0.109) (layer "In6.Cu") (net 201))
  (segment (start 76.518507 100.988942) (end 76.518507 101.044924) (width 0.109) (layer "In6.Cu") (net 201))
  (segment (start 75.416878 123.843586) (end 75.395742 123.850982) (width 0.109) (layer "In6.Cu") (net 201))
  (segment (start 78.1795 100.298481) (end 77.131832 100.298482) (width 0.109) (layer "In6.Cu") (net 201))
  (segment (start 75.330101 123.863393) (end 75.311141 123.875306) (width 0.109) (layer "In6.Cu") (net 201))
  (segment (start 76.565997 101.601777) (end 76.515559 101.626067) (width 0.109) (layer "In6.Cu") (net 201))
  (segment (start 76.681416 101.362104) (end 76.681417 101.418086) (width 0.109) (layer "In6.Cu") (net 201))
  (segment (start 75.283393 123.910101) (end 75.275997 123.931237) (width 0.109) (layer "In6.Cu") (net 201))
  (segment (start 76.590157 101.193711) (end 76.609765 101.213319) (width 0.109) (layer "In6.Cu") (net 201))
  (segment (start 78.35 100.468981) (end 78.35 100.468982) (width 0.182) (layer "B.Cu") (net 201))
  (segment (start 80.999999 100.75) (end 80.938999 100.689) (width 0.182) (layer "B.Cu") (net 201))
  (segment (start 81.9 100.75) (end 80.999999 100.75) (width 0.182) (layer "B.Cu") (net 201))
  (segment (start 80.938999 100.689) (end 80.521712 100.689) (width 0.182) (layer "B.Cu") (net 201))
  (segment (start 80.521712 100.689) (end 80.192693 100.359981) (width 0.182) (layer "B.Cu") (net 201))
  (segment (start 78.459 100.359981) (end 78.35 100.468981) (width 0.182) (layer "B.Cu") (net 201))
  (segment (start 80.192693 100.359981) (end 78.459 100.359981) (width 0.182) (layer "B.Cu") (net 201))
  (segment (start 93.3265 135.084) (end 93.7115 134.774) (width 0.182) (layer "F.Cu") (net 202))
  (via (at 78.35 101.298532) (size 0.45) (drill 0.1) (layers "F.Cu" "B.Cu") (net 202))
  (via (at 93.7115 134.774) (size 0.45) (drill 0.1) (layers "F.Cu" "B.Cu") (net 202))
  (segment (start 93.53 135.19) (end 93.1925 135.5275) (width 0.109) (layer "In2.Cu") (net 202))
  (segment (start 91.447306 135.640724) (end 91.432514 135.682996) (width 0.109) (layer "In2.Cu") (net 202))
  (segment (start 91.4275 135.7275) (end 91.4275 135.734767) (width 0.109) (layer "In2.Cu") (net 202))
  (segment (start 91.352197 135.891134) (end 91.314276 135.914961) (width 0.109) (layer "In2.Cu") (net 202))
  (segment (start 91.314276 135.914961) (end 91.272004 135.929753) (width 0.109) (layer "In2.Cu") (net 202))
  (segment (start 91.407693 135.821544) (end 91.383866 135.859465) (width 0.109) (layer "In2.Cu") (net 202))
  (segment (start 91.007693 135.640724) (end 90.983866 135.602803) (width 0.109) (layer "In2.Cu") (net 202))
  (segment (start 91.471133 135.602803) (end 91.447306 135.640724) (width 0.109) (layer "In2.Cu") (net 202))
  (segment (start 85.697186 135.5275) (end 75.6475 125.477814) (width 0.109) (layer "In2.Cu") (net 202))
  (segment (start 91.422485 135.779272) (end 91.407693 135.821544) (width 0.109) (layer "In2.Cu") (net 202))
  (segment (start 91.272004 135.929753) (end 91.2275 135.934767) (width 0.109) (layer "In2.Cu") (net 202))
  (segment (start 93.7115 134.774) (end 93.53 134.9555) (width 0.109) (layer "In2.Cu") (net 202))
  (segment (start 91.047306 135.821544) (end 91.032514 135.779272) (width 0.109) (layer "In2.Cu") (net 202))
  (segment (start 78.1795 101.469032) (end 78.35 101.298532) (width 0.109) (layer "In2.Cu") (net 202))
  (segment (start 93.53 134.9555) (end 93.53 135.19) (width 0.109) (layer "In2.Cu") (net 202))
  (segment (start 91.582995 135.532515) (end 91.540723 135.547307) (width 0.109) (layer "In2.Cu") (net 202))
  (segment (start 91.140723 135.914961) (end 91.102802 135.891134) (width 0.109) (layer "In2.Cu") (net 202))
  (segment (start 91.182995 135.929753) (end 91.140723 135.914961) (width 0.109) (layer "In2.Cu") (net 202))
  (segment (start 91.0275 135.734767) (end 91.0275 135.7275) (width 0.109) (layer "In2.Cu") (net 202))
  (segment (start 91.4275 135.734767) (end 91.422485 135.779272) (width 0.109) (layer "In2.Cu") (net 202))
  (segment (start 90.8275 135.5275) (end 85.697186 135.5275) (width 0.109) (layer "In2.Cu") (net 202))
  (segment (start 91.6275 135.5275) (end 91.582995 135.532515) (width 0.109) (layer "In2.Cu") (net 202))
  (segment (start 90.914276 135.547307) (end 90.872004 135.532515) (width 0.109) (layer "In2.Cu") (net 202))
  (segment (start 91.0275 135.7275) (end 91.022485 135.682996) (width 0.109) (layer "In2.Cu") (net 202))
  (segment (start 91.502802 135.571134) (end 91.471133 135.602803) (width 0.109) (layer "In2.Cu") (net 202))
  (segment (start 91.540723 135.547307) (end 91.502802 135.571134) (width 0.109) (layer "In2.Cu") (net 202))
  (segment (start 91.032514 135.779272) (end 91.0275 135.734767) (width 0.109) (layer "In2.Cu") (net 202))
  (segment (start 91.071133 135.859465) (end 91.047306 135.821544) (width 0.109) (layer "In2.Cu") (net 202))
  (segment (start 90.872004 135.532515) (end 90.8275 135.5275) (width 0.109) (layer "In2.Cu") (net 202))
  (segment (start 90.983866 135.602803) (end 90.952197 135.571134) (width 0.109) (layer "In2.Cu") (net 202))
  (segment (start 75.0725 103.247186) (end 76.850654 101.469032) (width 0.109) (layer "In2.Cu") (net 202))
  (segment (start 75.6475 125.477814) (end 75.6475 120.577814) (width 0.109) (layer "In2.Cu") (net 202))
  (segment (start 91.022485 135.682996) (end 91.007693 135.640724) (width 0.109) (layer "In2.Cu") (net 202))
  (segment (start 91.2275 135.934767) (end 91.182995 135.929753) (width 0.109) (layer "In2.Cu") (net 202))
  (segment (start 90.952197 135.571134) (end 90.914276 135.547307) (width 0.109) (layer "In2.Cu") (net 202))
  (segment (start 91.383866 135.859465) (end 91.352197 135.891134) (width 0.109) (layer "In2.Cu") (net 202))
  (segment (start 75.6475 120.577814) (end 75.0725 120.002814) (width 0.109) (layer "In2.Cu") (net 202))
  (segment (start 75.0725 120.002814) (end 75.0725 103.247186) (width 0.109) (layer "In2.Cu") (net 202))
  (segment (start 76.850654 101.469032) (end 78.1795 101.469032) (width 0.109) (layer "In2.Cu") (net 202))
  (segment (start 93.1925 135.5275) (end 91.6275 135.5275) (width 0.109) (layer "In2.Cu") (net 202))
  (segment (start 91.432514 135.682996) (end 91.4275 135.7275) (width 0.109) (layer "In2.Cu") (net 202))
  (segment (start 91.102802 135.891134) (end 91.071133 135.859465) (width 0.109) (layer "In2.Cu") (net 202))
  (segment (start 80.32482 101.407532) (end 78.459 101.407532) (width 0.182) (layer "B.Cu") (net 202))
  (segment (start 81.9 101.75) (end 80.999999 101.75) (width 0.182) (layer "B.Cu") (net 202))
  (segment (start 78.459 101.407532) (end 78.35 101.298532) (width 0.182) (layer "B.Cu") (net 202))
  (segment (start 80.999999 101.75) (end 80.938999 101.811) (width 0.182) (layer "B.Cu") (net 202))
  (segment (start 80.938999 101.811) (end 80.728288 101.811) (width 0.182) (layer "B.Cu") (net 202))
  (segment (start 80.728288 101.811) (end 80.32482 101.407532) (width 0.182) (layer "B.Cu") (net 202))
  (segment (start 93.3265 134.449) (end 93.7115 134.138999) (width 0.182) (layer "F.Cu") (net 203))
  (via (at 78.35 101.894533) (size 0.45) (drill 0.1) (layers "F.Cu" "B.Cu") (net 203))
  (via (at 93.7115 134.138999) (size 0.45) (drill 0.1) (layers "F.Cu" "B.Cu") (net 203))
  (segment (start 85.691479 135.081104) (end 85.686496 135.102935) (width 0.109) (layer "In2.Cu") (net 203))
  (segment (start 85.523324 134.912948) (end 85.543499 134.903232) (width 0.109) (layer "In2.Cu") (net 203))
  (segment (start 85.802814 135.2725) (end 92.997186 135.2725) (width 0.109) (layer "In2.Cu") (net 203))
  (segment (start 76.172302 102.727919) (end 76.131952 102.708487) (width 0.109) (layer "In2.Cu") (net 203))
  (segment (start 76.464421 125.934107) (end 85.419585 134.889271) (width 0.109) (layer "In2.Cu") (net 203))
  (segment (start 85.543499 134.903232) (end 85.578515 134.875309) (width 0.109) (layer "In2.Cu") (net 203))
  (segment (start 85.715157 135.184843) (end 85.802814 135.2725) (width 0.109) (layer "In2.Cu") (net 203))
  (segment (start 85.729118 135.025913) (end 85.701195 135.060929) (width 0.109) (layer "In2.Cu") (net 203))
  (segment (start 76.335719 102.822538) (end 76.292055 102.812573) (width 0.109) (layer "In2.Cu") (net 203))
  (segment (start 76.499936 125.665449) (end 76.485363 125.695713) (width 0.109) (layer "In2.Cu") (net 203))
  (segment (start 85.738834 134.939682) (end 85.743817 134.961513) (width 0.109) (layer "In2.Cu") (net 203))
  (segment (start 76.42143 125.811246) (end 76.421429 125.844834) (width 0.109) (layer "In2.Cu") (net 203))
  (segment (start 76.499533 102.482374) (end 76.527456 102.517389) (width 0.109) (layer "In2.Cu") (net 203))
  (segment (start 76.462235 102.437984) (end 76.490158 102.472999) (width 0.109) (layer "In2.Cu") (net 203))
  (segment (start 76.421429 125.844834) (end 76.428904 125.877582) (width 0.109) (layer "In2.Cu") (net 203))
  (segment (start 85.686496 135.125328) (end 85.691479 135.14716) (width 0.109) (layer "In2.Cu") (net 203))
  (segment (start 85.437093 134.903232) (end 85.457268 134.912948) (width 0.109) (layer "In2.Cu") (net 203))
  (segment (start 85.684921 134.875309) (end 85.702429 134.889271) (width 0.109) (layer "In2.Cu") (net 203))
  (segment (start 85.578515 134.875309) (end 85.59869 134.865593) (width 0.109) (layer "In2.Cu") (net 203))
  (segment (start 85.691479 135.14716) (end 85.701195 135.167335) (width 0.109) (layer "In2.Cu") (net 203))
  (segment (start 76.066417 125.530784) (end 76.096681 125.545359) (width 0.109) (layer "In2.Cu") (net 203))
  (segment (start 76.432836 102.353972) (end 76.442803 102.397634) (width 0.109) (layer "In2.Cu") (net 203))
  (segment (start 76.432836 102.309186) (end 76.432836 102.353972) (width 0.109) (layer "In2.Cu") (net 203))
  (segment (start 76.556853 102.601403) (end 76.556853 102.646189) (width 0.109) (layer "In2.Cu") (net 203))
  (segment (start 76.464519 102.79314) (end 76.424167 102.812573) (width 0.109) (layer "In2.Cu") (net 203))
  (segment (start 76.490157 102.190157) (end 76.462234 102.225172) (width 0.109) (layer "In2.Cu") (net 203))
  (segment (start 85.743817 134.983906) (end 85.738834 135.005738) (width 0.109) (layer "In2.Cu") (net 203))
  (segment (start 76.485362 125.536103) (end 76.499937 125.566367) (width 0.109) (layer "In2.Cu") (net 203))
  (segment (start 85.642914 134.86061) (end 85.664746 134.865593) (width 0.109) (layer "In2.Cu") (net 203))
  (segment (start 85.729118 134.919507) (end 85.738834 134.939682) (width 0.109) (layer "In2.Cu") (net 203))
  (segment (start 76.527456 102.517389) (end 76.546888 102.557739) (width 0.109) (layer "In2.Cu") (net 203))
  (segment (start 76.27855 125.4889) (end 76.308812 125.474325) (width 0.109) (layer "In2.Cu") (net 203))
  (segment (start 85.701195 135.060929) (end 85.691479 135.081104) (width 0.109) (layer "In2.Cu") (net 203))
  (segment (start 76.490158 102.472999) (end 76.499533 102.482374) (width 0.109) (layer "In2.Cu") (net 203))
  (segment (start 76.442803 102.397634) (end 76.462235 102.437984) (width 0.109) (layer "In2.Cu") (net 203))
  (segment (start 76.292055 102.812573) (end 76.251705 102.793141) (width 0.109) (layer "In2.Cu") (net 203))
  (segment (start 85.738834 135.005738) (end 85.729118 135.025913) (width 0.109) (layer "In2.Cu") (net 203))
  (segment (start 76.485363 125.695713) (end 76.443478 125.748236) (width 0.109) (layer "In2.Cu") (net 203))
  (segment (start 76.428903 125.778498) (end 76.42143 125.811246) (width 0.109) (layer "In2.Cu") (net 203))
  (segment (start 75.99984 102.708487) (end 75.95949 102.727919) (width 0.109) (layer "In2.Cu") (net 203))
  (segment (start 76.251705 102.793141) (end 76.216691 102.765216) (width 0.109) (layer "In2.Cu") (net 203))
  (segment (start 92.997186 135.2725) (end 93.27 134.999686) (width 0.109) (layer "In2.Cu") (net 203))
  (segment (start 76.438158 125.488899) (end 76.464421 125.509843) (width 0.109) (layer "In2.Cu") (net 203))
  (segment (start 75.3275 119.897186) (end 75.9025 120.472186) (width 0.109) (layer "In2.Cu") (net 203))
  (segment (start 76.424167 102.812573) (end 76.380505 102.822538) (width 0.109) (layer "In2.Cu") (net 203))
  (segment (start 85.59869 134.865593) (end 85.620521 134.86061) (width 0.109) (layer "In2.Cu") (net 203))
  (segment (start 76.956282 101.724032) (end 76.490157 102.190157) (width 0.109) (layer "In2.Cu") (net 203))
  (segment (start 78.35 101.894533) (end 78.35 101.894532) (width 0.109) (layer "In2.Cu") (net 203))
  (segment (start 78.1795 101.724032) (end 76.956282 101.724032) (width 0.109) (layer "In2.Cu") (net 203))
  (segment (start 76.040157 125.509843) (end 76.066417 125.530784) (width 0.109) (layer "In2.Cu") (net 203))
  (segment (start 76.096681 125.545359) (end 76.129427 125.552832) (width 0.109) (layer "In2.Cu") (net 203))
  (segment (start 85.419585 134.889271) (end 85.437093 134.903232) (width 0.109) (layer "In2.Cu") (net 203))
  (segment (start 76.308812 125.474325) (end 76.34156 125.466852) (width 0.109) (layer "In2.Cu") (net 203))
  (segment (start 76.527456 102.730201) (end 76.499533 102.765216) (width 0.109) (layer "In2.Cu") (net 203))
  (segment (start 85.664746 134.865593) (end 85.684921 134.875309) (width 0.109) (layer "In2.Cu") (net 203))
  (segment (start 76.464421 125.509843) (end 76.485362 125.536103) (width 0.109) (layer "In2.Cu") (net 203))
  (segment (start 85.457268 134.912948) (end 85.479099 134.917931) (width 0.109) (layer "In2.Cu") (net 203))
  (segment (start 76.131952 102.708487) (end 76.088288 102.698522) (width 0.109) (layer "In2.Cu") (net 203))
  (segment (start 76.216691 102.765216) (end 76.207317 102.755842) (width 0.109) (layer "In2.Cu") (net 203))
  (segment (start 76.546888 102.689851) (end 76.527456 102.730201) (width 0.109) (layer "In2.Cu") (net 203))
  (segment (start 75.9025 125.372186) (end 76.040157 125.509843) (width 0.109) (layer "In2.Cu") (net 203))
  (segment (start 76.50741 125.599113) (end 76.507411 125.632703) (width 0.109) (layer "In2.Cu") (net 203))
  (segment (start 76.226027 125.530785) (end 76.27855 125.4889) (width 0.109) (layer "In2.Cu") (net 203))
  (segment (start 76.043502 102.698522) (end 75.99984 102.708487) (width 0.109) (layer "In2.Cu") (net 203))
  (segment (start 85.743817 134.961513) (end 85.743817 134.983906) (width 0.109) (layer "In2.Cu") (net 203))
  (segment (start 76.428904 125.877582) (end 76.443477 125.907844) (width 0.109) (layer "In2.Cu") (net 203))
  (segment (start 76.546888 102.557739) (end 76.556853 102.601403) (width 0.109) (layer "In2.Cu") (net 203))
  (segment (start 93.27 134.999686) (end 93.27 134.580499) (width 0.109) (layer "In2.Cu") (net 203))
  (segment (start 85.715157 134.901999) (end 85.729118 134.919507) (width 0.109) (layer "In2.Cu") (net 203))
  (segment (start 85.701195 135.167335) (end 85.715157 135.184843) (width 0.109) (layer "In2.Cu") (net 203))
  (segment (start 75.95949 102.727919) (end 75.924473 102.755842) (width 0.109) (layer "In2.Cu") (net 203))
  (segment (start 85.686496 135.102935) (end 85.686496 135.125328) (width 0.109) (layer "In2.Cu") (net 203))
  (segment (start 76.499533 102.765216) (end 76.464519 102.79314) (width 0.109) (layer "In2.Cu") (net 203))
  (segment (start 76.380505 102.822538) (end 76.335719 102.822538) (width 0.109) (layer "In2.Cu") (net 203))
  (segment (start 76.129427 125.552832) (end 76.163017 125.552833) (width 0.109) (layer "In2.Cu") (net 203))
  (segment (start 75.9025 120.472186) (end 75.9025 125.372186) (width 0.109) (layer "In2.Cu") (net 203))
  (segment (start 76.34156 125.466852) (end 76.375148 125.466851) (width 0.109) (layer "In2.Cu") (net 203))
  (segment (start 75.924473 102.755842) (end 75.3275 103.352814) (width 0.109) (layer "In2.Cu") (net 203))
  (segment (start 93.27 134.580499) (end 93.7115 134.138999) (width 0.109) (layer "In2.Cu") (net 203))
  (segment (start 85.501492 134.917931) (end 85.523324 134.912948) (width 0.109) (layer "In2.Cu") (net 203))
  (segment (start 76.442803 102.265522) (end 76.432836 102.309186) (width 0.109) (layer "In2.Cu") (net 203))
  (segment (start 85.620521 134.86061) (end 85.642914 134.86061) (width 0.109) (layer "In2.Cu") (net 203))
  (segment (start 75.3275 103.352814) (end 75.3275 119.897186) (width 0.109) (layer "In2.Cu") (net 203))
  (segment (start 85.702429 134.889271) (end 85.715157 134.901999) (width 0.109) (layer "In2.Cu") (net 203))
  (segment (start 76.507411 125.632703) (end 76.499936 125.665449) (width 0.109) (layer "In2.Cu") (net 203))
  (segment (start 76.207317 102.755842) (end 76.172302 102.727919) (width 0.109) (layer "In2.Cu") (net 203))
  (segment (start 76.556853 102.646189) (end 76.546888 102.689851) (width 0.109) (layer "In2.Cu") (net 203))
  (segment (start 76.375148 125.466851) (end 76.407896 125.474326) (width 0.109) (layer "In2.Cu") (net 203))
  (segment (start 76.443478 125.748236) (end 76.428903 125.778498) (width 0.109) (layer "In2.Cu") (net 203))
  (segment (start 85.479099 134.917931) (end 85.501492 134.917931) (width 0.109) (layer "In2.Cu") (net 203))
  (segment (start 76.443477 125.907844) (end 76.464421 125.934107) (width 0.109) (layer "In2.Cu") (net 203))
  (segment (start 76.195763 125.545358) (end 76.226027 125.530785) (width 0.109) (layer "In2.Cu") (net 203))
  (segment (start 78.35 101.894532) (end 78.1795 101.724032) (width 0.109) (layer "In2.Cu") (net 203))
  (segment (start 76.163017 125.552833) (end 76.195763 125.545358) (width 0.109) (layer "In2.Cu") (net 203))
  (segment (start 76.407896 125.474326) (end 76.438158 125.488899) (width 0.109) (layer "In2.Cu") (net 203))
  (segment (start 76.499937 125.566367) (end 76.50741 125.599113) (width 0.109) (layer "In2.Cu") (net 203))
  (segment (start 76.088288 102.698522) (end 76.043502 102.698522) (width 0.109) (layer "In2.Cu") (net 203))
  (segment (start 76.462234 102.225172) (end 76.442803 102.265522) (width 0.109) (layer "In2.Cu") (net 203))
  (segment (start 80.999999 102.25) (end 81.9 102.25) (width 0.182) (layer "B.Cu") (net 203))
  (segment (start 80.938999 102.189) (end 80.999999 102.25) (width 0.182) (layer "B.Cu") (net 203))
  (segment (start 80.168244 101.785532) (end 78.459 101.785532) (width 0.182) (layer "B.Cu") (net 203))
  (segment (start 80.168244 101.785532) (end 80.571712 102.189) (width 0.182) (layer "B.Cu") (net 203))
  (segment (start 78.459 101.785532) (end 78.35 101.894532) (width 0.182) (layer "B.Cu") (net 203))
  (segment (start 78.35 101.894532) (end 78.35 101.894533) (width 0.182) (layer "B.Cu") (net 203))
  (segment (start 80.571712 102.189) (end 80.938999 102.189) (width 0.182) (layer "B.Cu") (net 203))
  (segment (start 91.9815 132.854) (end 92.3665 132.544) (width 0.182) (layer "F.Cu") (net 204))
  (via (at 78.2 102.705467) (size 0.45) (drill 0.1) (layers "F.Cu" "B.Cu") (net 204))
  (via (at 91.9815 132.854) (size 0.45) (drill 0.1) (layers "F.Cu" "B.Cu") (net 204))
  (segment (start 78.063915 121.429324) (end 78.100375 121.442082) (width 0.109) (layer "In2.Cu") (net 204))
  (segment (start 77.430417 123.922655) (end 77.443175 123.959115) (width 0.109) (layer "In2.Cu") (net 204))
  (segment (start 76.736859 123.19803) (end 76.707068 123.283166) (width 0.109) (layer "In2.Cu") (net 204))
  (segment (start 75.8725 104.222186) (end 75.8725 108.427814) (width 0.109) (layer "In2.Cu") (net 204))
  (segment (start 77.382551 123.862634) (end 77.409865 123.889948) (width 0.109) (layer "In2.Cu") (net 204))
  (segment (start 78.0295 102.875967) (end 77.218719 102.875967) (width 0.109) (layer "In2.Cu") (net 204))
  (segment (start 76.784847 120.721657) (end 76.736859 120.79803) (width 0.109) (layer "In2.Cu") (net 204))
  (segment (start 77.313384 123.829324) (end 77.349844 123.842082) (width 0.109) (layer "In2.Cu") (net 204))
  (segment (start 90.913952 133.631735) (end 90.939359 133.615771) (width 0.109) (layer "In2.Cu") (net 204))
  (segment (start 78.133082 121.462634) (end 78.160396 121.489948) (width 0.109) (layer "In2.Cu") (net 204))
  (segment (start 90.645952 133.923266) (end 90.671359 133.93923) (width 0.109) (layer "In2.Cu") (net 204))
  (segment (start 78.2 102.705467) (end 78.0295 102.875967) (width 0.109) (layer "In2.Cu") (net 204))
  (segment (start 76.69697 123.372797) (end 76.69697 123.422202) (width 0.109) (layer "In2.Cu") (net 204))
  (segment (start 76.925 120.609889) (end 76.848627 120.657877) (width 0.109) (layer "In2.Cu") (net 204))
  (segment (start 76.707068 121.111833) (end 76.736859 121.196969) (width 0.109) (layer "In2.Cu") (net 204))
  (segment (start 76.848627 122.537122) (end 76.925 122.58511) (width 0.109) (layer "In2.Cu") (net 204))
  (segment (start 77.443175 123.959115) (end 77.4475 123.9975) (width 0.109) (layer "In2.Cu") (net 204))
  (segment (start 78.180948 121.522655) (end 78.193706 121.559115) (width 0.109) (layer "In2.Cu") (net 204))
  (segment (start 90.8635 133.7365) (end 90.866859 133.706683) (width 0.109) (layer "In2.Cu") (net 204))
  (segment (start 76.707068 122.083166) (end 76.69697 122.172797) (width 0.109) (layer "In2.Cu") (net 204))
  (segment (start 76.925 121.809889) (end 76.848627 121.857877) (width 0.109) (layer "In2.Cu") (net 204))
  (segment (start 90.566265 133.652953) (end 90.582229 133.67836) (width 0.109) (layer "In2.Cu") (net 204))
  (segment (start 77.010136 120.580098) (end 76.925 120.609889) (width 0.109) (layer "In2.Cu") (net 204))
  (segment (start 77.099767 122.97) (end 77.010136 122.980098) (width 0.109) (layer "In2.Cu") (net 204))
  (segment (start 77.349844 123.842082) (end 77.382551 123.862634) (width 0.109) (layer "In2.Cu") (net 204))
  (segment (start 78.063915 122.629324) (end 78.100375 122.642082) (width 0.109) (layer "In2.Cu") (net 204))
  (segment (start 90.624734 133.902048) (end 90.645952 133.923266) (width 0.109) (layer "In2.Cu") (net 204))
  (segment (start 90.7295 133.9525) (end 90.759317 133.949141) (width 0.109) (layer "In2.Cu") (net 204))
  (segment (start 76.736859 121.196969) (end 76.784847 121.273342) (width 0.109) (layer "In2.Cu") (net 204))
  (segment (start 78.02553 121.425) (end 78.063915 121.429324) (width 0.109) (layer "In2.Cu") (net 204))
  (segment (start 90.671359 133.93923) (end 90.699682 133.949141) (width 0.109) (layer "In2.Cu") (net 204))
  (segment (start 90.60877 133.876641) (end 90.624734 133.902048) (width 0.109) (layer "In2.Cu") (net 204))
  (segment (start 75.8725 108.427814) (end 76.1475 108.702814) (width 0.109) (layer "In2.Cu") (net 204))
  (segment (start 76.784847 123.673342) (end 76.848627 123.737122) (width 0.109) (layer "In2.Cu") (net 204))
  (segment (start 78.160396 122.689948) (end 78.180948 122.722655) (width 0.109) (layer "In2.Cu") (net 204))
  (segment (start 90.834265 133.902048) (end 90.850229 133.876641) (width 0.109) (layer "In2.Cu") (net 204))
  (segment (start 76.707068 122.311833) (end 76.736859 122.396969) (width 0.109) (layer "In2.Cu") (net 204))
  (segment (start 90.59214 133.706683) (end 90.5955 133.7365) (width 0.109) (layer "In2.Cu") (net 204))
  (segment (start 78.160396 121.489948) (end 78.180948 121.522655) (width 0.109) (layer "In2.Cu") (net 204))
  (segment (start 78.100375 122.952917) (end 78.063915 122.965675) (width 0.109) (layer "In2.Cu") (net 204))
  (segment (start 90.78764 133.93923) (end 90.813047 133.923266) (width 0.109) (layer "In2.Cu") (net 204))
  (segment (start 77.010136 121.414901) (end 77.099767 121.425) (width 0.109) (layer "In2.Cu") (net 204))
  (segment (start 77.010136 123.814901) (end 77.099767 123.825) (width 0.109) (layer "In2.Cu") (net 204))
  (segment (start 78.02553 122.625) (end 78.063915 122.629324) (width 0.109) (layer "In2.Cu") (net 204))
  (segment (start 77.275 120.57) (end 77.099767 120.57) (width 0.109) (layer "In2.Cu") (net 204))
  (segment (start 76.69697 122.172797) (end 76.69697 122.222202) (width 0.109) (layer "In2.Cu") (net 204))
  (segment (start 76.784847 122.473342) (end 76.848627 122.537122) (width 0.109) (layer "In2.Cu") (net 204))
  (segment (start 78.02553 122.97) (end 77.099767 122.97) (width 0.109) (layer "In2.Cu") (net 204))
  (segment (start 77.099767 121.77) (end 77.010136 121.780098) (width 0.109) (layer "In2.Cu") (net 204))
  (segment (start 77.099767 121.425) (end 78.02553 121.425) (width 0.109) (layer "In2.Cu") (net 204))
  (segment (start 90.582229 133.67836) (end 90.59214 133.706683) (width 0.109) (layer "In2.Cu") (net 204))
  (segment (start 78.193706 122.759115) (end 78.19803 122.7975) (width 0.109) (layer "In2.Cu") (net 204))
  (segment (start 76.848627 123.737122) (end 76.925 123.78511) (width 0.109) (layer "In2.Cu") (net 204))
  (segment (start 75.8725 118.302814) (end 77.4475 119.877814) (width 0.109) (layer "In2.Cu") (net 204))
  (segment (start 78.100375 121.442082) (end 78.133082 121.462634) (width 0.109) (layer "In2.Cu") (net 204))
  (segment (start 76.925 123.78511) (end 77.010136 123.814901) (width 0.109) (layer "In2.Cu") (net 204))
  (segment (start 76.1475 109.747186) (end 75.8725 110.022186) (width 0.109) (layer "In2.Cu") (net 204))
  (segment (start 76.784847 121.273342) (end 76.848627 121.337122) (width 0.109) (layer "In2.Cu") (net 204))
  (segment (start 90.598859 133.848318) (end 90.60877 133.876641) (width 0.109) (layer "In2.Cu") (net 204))
  (segment (start 76.784847 123.121657) (end 76.736859 123.19803) (width 0.109) (layer "In2.Cu") (net 204))
  (segment (start 91.8 133.0355) (end 91.9815 132.854) (width 0.109) (layer "In2.Cu") (net 204))
  (segment (start 78.180948 121.672344) (end 78.160396 121.705051) (width 0.109) (layer "In2.Cu") (net 204))
  (segment (start 77.010136 122.614901) (end 77.099767 122.625) (width 0.109) (layer "In2.Cu") (net 204))
  (segment (start 78.160396 122.905051) (end 78.133082 122.932365) (width 0.109) (layer "In2.Cu") (net 204))
  (segment (start 85.922186 133.6025) (end 90.4615 133.6025) (width 0.109) (layer "In2.Cu") (net 204))
  (segment (start 90.967682 133.60586) (end 90.9975 133.6025) (width 0.109) (layer "In2.Cu") (net 204))
  (segment (start 90.86014 133.848318) (end 90.8635 133.8185) (width 0.109) (layer "In2.Cu") (net 204))
  (segment (start 78.160396 121.705051) (end 78.133082 121.732365) (width 0.109) (layer "In2.Cu") (net 204))
  (segment (start 78.063915 121.765675) (end 78.02553 121.77) (width 0.109) (layer "In2.Cu") (net 204))
  (segment (start 90.813047 133.923266) (end 90.834265 133.902048) (width 0.109) (layer "In2.Cu") (net 204))
  (segment (start 77.409865 120.505051) (end 77.382551 120.532365) (width 0.109) (layer "In2.Cu") (net 204))
  (segment (start 76.925 122.58511) (end 77.010136 122.614901) (width 0.109) (layer "In2.Cu") (net 204))
  (segment (start 77.099767 122.625) (end 78.02553 122.625) (width 0.109) (layer "In2.Cu") (net 204))
  (segment (start 77.443175 120.435884) (end 77.430417 120.472344) (width 0.109) (layer "In2.Cu") (net 204))
  (segment (start 90.850229 133.876641) (end 90.86014 133.848318) (width 0.109) (layer "In2.Cu") (net 204))
  (segment (start 75.8725 110.022186) (end 75.8725 118.302814) (width 0.109) (layer "In2.Cu") (net 204))
  (segment (start 76.848627 123.057877) (end 76.784847 123.121657) (width 0.109) (layer "In2.Cu") (net 204))
  (segment (start 76.69697 123.422202) (end 76.707068 123.511833) (width 0.109) (layer "In2.Cu") (net 204))
  (segment (start 76.736859 122.396969) (end 76.784847 122.473342) (width 0.109) (layer "In2.Cu") (net 204))
  (segment (start 91.8 133.270001) (end 91.8 133.0355) (width 0.109) (layer "In2.Cu") (net 204))
  (segment (start 76.736859 120.79803) (end 76.707068 120.883166) (width 0.109) (layer "In2.Cu") (net 204))
  (segment (start 77.010136 122.980098) (end 76.925 123.009889) (width 0.109) (layer "In2.Cu") (net 204))
  (segment (start 76.707068 123.511833) (end 76.736859 123.596969) (width 0.109) (layer "In2.Cu") (net 204))
  (segment (start 76.848627 121.857877) (end 76.784847 121.921657) (width 0.109) (layer "In2.Cu") (net 204))
  (segment (start 77.430417 120.472344) (end 77.409865 120.505051) (width 0.109) (layer "In2.Cu") (net 204))
  (segment (start 90.8635 133.8185) (end 90.8635 133.7365) (width 0.109) (layer "In2.Cu") (net 204))
  (segment (start 90.87677 133.67836) (end 90.892734 133.652953) (width 0.109) (layer "In2.Cu") (net 204))
  (segment (start 76.69697 120.972797) (end 76.69697 121.022202) (width 0.109) (layer "In2.Cu") (net 204))
  (segment (start 76.69697 121.022202) (end 76.707068 121.111833) (width 0.109) (layer "In2.Cu") (net 204))
  (segment (start 77.4475 125.127814) (end 85.922186 133.6025) (width 0.109) (layer "In2.Cu") (net 204))
  (segment (start 78.180948 122.872344) (end 78.160396 122.905051) (width 0.109) (layer "In2.Cu") (net 204))
  (segment (start 76.736859 123.596969) (end 76.784847 123.673342) (width 0.109) (layer "In2.Cu") (net 204))
  (segment (start 90.866859 133.706683) (end 90.87677 133.67836) (width 0.109) (layer "In2.Cu") (net 204))
  (segment (start 77.275 123.825) (end 77.313384 123.829324) (width 0.109) (layer "In2.Cu") (net 204))
  (segment (start 78.19803 122.7975) (end 78.193706 122.835884) (width 0.109) (layer "In2.Cu") (net 204))
  (segment (start 76.69697 122.222202) (end 76.707068 122.311833) (width 0.109) (layer "In2.Cu") (net 204))
  (segment (start 90.5955 133.8185) (end 90.598859 133.848318) (width 0.109) (layer "In2.Cu") (net 204))
  (segment (start 78.193706 122.835884) (end 78.180948 122.872344) (width 0.109) (layer "In2.Cu") (net 204))
  (segment (start 76.784847 121.921657) (end 76.736859 121.99803) (width 0.109) (layer "In2.Cu") (net 204))
  (segment (start 90.699682 133.949141) (end 90.7295 133.9525) (width 0.109) (layer "In2.Cu") (net 204))
  (segment (start 78.100375 121.752917) (end 78.063915 121.765675) (width 0.109) (layer "In2.Cu") (net 204))
  (segment (start 90.545047 133.631735) (end 90.566265 133.652953) (width 0.109) (layer "In2.Cu") (net 204))
  (segment (start 76.707068 120.883166) (end 76.69697 120.972797) (width 0.109) (layer "In2.Cu") (net 204))
  (segment (start 77.010136 121.780098) (end 76.925 121.809889) (width 0.109) (layer "In2.Cu") (net 204))
  (segment (start 90.759317 133.949141) (end 90.78764 133.93923) (width 0.109) (layer "In2.Cu") (net 204))
  (segment (start 77.4475 119.877814) (end 77.4475 120.3975) (width 0.109) (layer "In2.Cu") (net 204))
  (segment (start 77.349844 120.552917) (end 77.313384 120.565675) (width 0.109) (layer "In2.Cu") (net 204))
  (segment (start 76.925 123.009889) (end 76.848627 123.057877) (width 0.109) (layer "In2.Cu") (net 204))
  (segment (start 90.5955 133.7365) (end 90.5955 133.8185) (width 0.109) (layer "In2.Cu") (net 204))
  (segment (start 77.099767 123.825) (end 77.275 123.825) (width 0.109) (layer "In2.Cu") (net 204))
  (segment (start 77.218719 102.875967) (end 75.8725 104.222186) (width 0.109) (layer "In2.Cu") (net 204))
  (segment (start 77.099767 120.57) (end 77.010136 120.580098) (width 0.109) (layer "In2.Cu") (net 204))
  (segment (start 78.02553 121.77) (end 77.099767 121.77) (width 0.109) (layer "In2.Cu") (net 204))
  (segment (start 77.382551 120.532365) (end 77.349844 120.552917) (width 0.109) (layer "In2.Cu") (net 204))
  (segment (start 91.467501 133.6025) (end 91.8 133.270001) (width 0.109) (layer "In2.Cu") (net 204))
  (segment (start 78.133082 122.662634) (end 78.160396 122.689948) (width 0.109) (layer "In2.Cu") (net 204))
  (segment (start 90.491317 133.60586) (end 90.51964 133.615771) (width 0.109) (layer "In2.Cu") (net 204))
  (segment (start 76.848627 121.337122) (end 76.925 121.38511) (width 0.109) (layer "In2.Cu") (net 204))
  (segment (start 90.939359 133.615771) (end 90.967682 133.60586) (width 0.109) (layer "In2.Cu") (net 204))
  (segment (start 78.193706 121.559115) (end 78.19803 121.5975) (width 0.109) (layer "In2.Cu") (net 204))
  (segment (start 76.848627 120.657877) (end 76.784847 120.721657) (width 0.109) (layer "In2.Cu") (net 204))
  (segment (start 90.892734 133.652953) (end 90.913952 133.631735) (width 0.109) (layer "In2.Cu") (net 204))
  (segment (start 78.19803 121.5975) (end 78.193706 121.635884) (width 0.109) (layer "In2.Cu") (net 204))
  (segment (start 90.4615 133.6025) (end 90.491317 133.60586) (width 0.109) (layer "In2.Cu") (net 204))
  (segment (start 77.4475 120.3975) (end 77.443175 120.435884) (width 0.109) (layer "In2.Cu") (net 204))
  (segment (start 78.133082 122.932365) (end 78.100375 122.952917) (width 0.109) (layer "In2.Cu") (net 204))
  (segment (start 76.1475 108.702814) (end 76.1475 109.747186) (width 0.109) (layer "In2.Cu") (net 204))
  (segment (start 78.100375 122.642082) (end 78.133082 122.662634) (width 0.109) (layer "In2.Cu") (net 204))
  (segment (start 90.51964 133.615771) (end 90.545047 133.631735) (width 0.109) (layer "In2.Cu") (net 204))
  (segment (start 77.4475 123.9975) (end 77.4475 125.127814) (width 0.109) (layer "In2.Cu") (net 204))
  (segment (start 77.313384 120.565675) (end 77.275 120.57) (width 0.109) (layer "In2.Cu") (net 204))
  (segment (start 76.925 121.38511) (end 77.010136 121.414901) (width 0.109) (layer "In2.Cu") (net 204))
  (segment (start 78.180948 122.722655) (end 78.193706 122.759115) (width 0.109) (layer "In2.Cu") (net 204))
  (segment (start 90.9975 133.6025) (end 91.467501 133.6025) (width 0.109) (layer "In2.Cu") (net 204))
  (segment (start 76.736859 121.99803) (end 76.707068 122.083166) (width 0.109) (layer "In2.Cu") (net 204))
  (segment (start 76.707068 123.283166) (end 76.69697 123.372797) (width 0.109) (layer "In2.Cu") (net 204))
  (segment (start 77.409865 123.889948) (end 77.430417 123.922655) (width 0.109) (layer "In2.Cu") (net 204))
  (segment (start 78.063915 122.965675) (end 78.02553 122.97) (width 0.109) (layer "In2.Cu") (net 204))
  (segment (start 78.133082 121.732365) (end 78.100375 121.752917) (width 0.109) (layer "In2.Cu") (net 204))
  (segment (start 78.193706 121.635884) (end 78.180948 121.672344) (width 0.109) (layer "In2.Cu") (net 204))
  (segment (start 78.309 102.814467) (end 78.2 102.705467) (width 0.182) (layer "B.Cu") (net 204))
  (segment (start 80.999999 102.75) (end 81.9 102.75) (width 0.182) (layer "B.Cu") (net 204))
  (segment (start 80.935532 102.814467) (end 78.309 102.814467) (width 0.182) (layer "B.Cu") (net 204))
  (segment (start 80.935532 102.814467) (end 80.999999 102.75) (width 0.182) (layer "B.Cu") (net 204))
  (segment (start 91.9815 132.219) (end 92.3665 131.909) (width 0.182) (layer "F.Cu") (net 205))
  (via (at 78.2 103.301468) (size 0.45) (drill 0.1) (layers "F.Cu" "B.Cu") (net 205))
  (via (at 91.9815 132.219) (size 0.45) (drill 0.1) (layers "F.Cu" "B.Cu") (net 205))
  (segment (start 78.016933 125.159843) (end 78.038816 125.142389) (width 0.109) (layer "In2.Cu") (net 205))
  (segment (start 85.910559 133.130169) (end 85.904331 133.157459) (width 0.109) (layer "In2.Cu") (net 205))
  (segment (start 77.66261 123.79803) (end 77.692401 123.883166) (width 0.109) (layer "In2.Cu") (net 205))
  (segment (start 76.95197 120.9975) (end 76.956294 121.035884) (width 0.109) (layer "In2.Cu") (net 205))
  (segment (start 78.139864 123.214901) (end 78.050233 123.225) (width 0.109) (layer "In2.Cu") (net 205))
  (segment (start 91.3275 133.3475) (end 91.55 133.125) (width 0.109) (layer "In2.Cu") (net 205))
  (segment (start 76.666734 103.845354) (end 76.626564 103.854522) (width 0.109) (layer "In2.Cu") (net 205))
  (segment (start 77.12447 121.17) (end 78.050233 121.17) (width 0.109) (layer "In2.Cu") (net 205))
  (segment (start 78.188983 125.504239) (end 78.206435 125.526122) (width 0.109) (layer "In2.Cu") (net 205))
  (segment (start 78.2 103.301468) (end 78.2 103.301467) (width 0.109) (layer "In2.Cu") (net 205))
  (segment (start 85.741495 132.923741) (end 85.763379 132.906289) (width 0.109) (layer "In2.Cu") (net 205))
  (segment (start 78.223889 125.194455) (end 78.236032 125.219673) (width 0.109) (layer "In2.Cu") (net 205))
  (segment (start 76.1275 110.127814) (end 76.1275 118.197186) (width 0.109) (layer "In2.Cu") (net 205))
  (segment (start 77.474469 120.78511) (end 77.389333 120.814901) (width 0.109) (layer "In2.Cu") (net 205))
  (segment (start 85.660996 132.942114) (end 85.688987 132.942114) (width 0.109) (layer "In2.Cu") (net 205))
  (segment (start 85.940157 133.259843) (end 86.027814 133.3475) (width 0.109) (layer "In2.Cu") (net 205))
  (segment (start 77.550842 123.657877) (end 77.614622 123.721657) (width 0.109) (layer "In2.Cu") (net 205))
  (segment (start 77.125075 103.832603) (end 77.107197 103.869725) (width 0.109) (layer "In2.Cu") (net 205))
  (segment (start 78.413141 122.996969) (end 78.365153 123.073342) (width 0.109) (layer "In2.Cu") (net 205))
  (segment (start 85.964376 133.054414) (end 85.946924 133.076298) (width 0.109) (layer "In2.Cu") (net 205))
  (segment (start 77.389333 120.814901) (end 77.299702 120.825) (width 0.109) (layer "In2.Cu") (net 205))
  (segment (start 78.139864 121.180098) (end 78.225 121.209889) (width 0.109) (layer "In2.Cu") (net 205))
  (segment (start 77.049625 122.042082) (end 77.016918 122.062634) (width 0.109) (layer "In2.Cu") (net 205))
  (segment (start 76.89063 103.945506) (end 76.853507 103.927629) (width 0.109) (layer "In2.Cu") (net 205))
  (segment (start 85.964376 132.921406) (end 85.976521 132.946625) (width 0.109) (layer "In2.Cu") (net 205))
  (segment (start 77.7025 120.422202) (end 77.692401 120.511833) (width 0.109) (layer "In2.Cu") (net 205))
  (segment (start 76.95197 123.3975) (end 76.956294 123.435884) (width 0.109) (layer "In2.Cu") (net 205))
  (segment (start 76.1275 108.322186) (end 76.4025 108.597186) (width 0.109) (layer "In2.Cu") (net 205))
  (segment (start 76.956294 123.359115) (end 76.95197 123.3975) (width 0.109) (layer "In2.Cu") (net 205))
  (segment (start 78.301373 123.137122) (end 78.225 123.18511) (width 0.109) (layer "In2.Cu") (net 205))
  (segment (start 78.225 121.209889) (end 78.301373 121.257877) (width 0.109) (layer "In2.Cu") (net 205))
  (segment (start 78.365153 121.321657) (end 78.413141 121.39803) (width 0.109) (layer "In2.Cu") (net 205))
  (segment (start 78.365153 122.521657) (end 78.413141 122.59803) (width 0.109) (layer "In2.Cu") (net 205))
  (segment (start 76.956294 122.235884) (end 76.969052 122.272344) (width 0.109) (layer "In2.Cu") (net 205))
  (segment (start 78.365153 123.073342) (end 78.301373 123.137122) (width 0.109) (layer "In2.Cu") (net 205))
  (segment (start 77.134243 103.792433) (end 77.125075 103.832603) (width 0.109) (layer "In2.Cu") (net 205))
  (segment (start 78.225 123.18511) (end 78.139864 123.214901) (width 0.109) (layer "In2.Cu") (net 205))
  (segment (start 77.049625 123.552917) (end 77.086085 123.565675) (width 0.109) (layer "In2.Cu") (net 205))
  (segment (start 77.66261 120.596969) (end 77.614622 120.673342) (width 0.109) (layer "In2.Cu") (net 205))
  (segment (start 77.016918 123.262634) (end 76.989604 123.289948) (width 0.109) (layer "In2.Cu") (net 205))
  (segment (start 77.051969 103.605658) (end 77.077657 103.637873) (width 0.109) (layer "In2.Cu") (net 205))
  (segment (start 78.242261 125.246962) (end 78.242262 125.274954) (width 0.109) (layer "In2.Cu") (net 205))
  (segment (start 78.236032 125.219673) (end 78.242261 125.246962) (width 0.109) (layer "In2.Cu") (net 205))
  (segment (start 78.176838 125.47902) (end 78.188983 125.504239) (width 0.109) (layer "In2.Cu") (net 205))
  (segment (start 77.914548 125.195667) (end 77.94254 125.195668) (width 0.109) (layer "In2.Cu") (net 205))
  (segment (start 77.7025 119.772186) (end 77.7025 120.422202) (width 0.109) (layer "In2.Cu") (net 205))
  (segment (start 76.956294 120.959115) (end 76.95197 120.9975) (width 0.109) (layer "In2.Cu") (net 205))
  (segment (start 85.982749 133.001906) (end 85.976521 133.029195) (width 0.109) (layer "In2.Cu") (net 205))
  (segment (start 85.81725 132.869924) (end 85.84454 132.863696) (width 0.109) (layer "In2.Cu") (net 205))
  (segment (start 76.589442 103.8724) (end 76.557228 103.898087) (width 0.109) (layer "In2.Cu") (net 205))
  (segment (start 77.299702 123.57) (end 77.389333 123.580098) (width 0.109) (layer "In2.Cu") (net 205))
  (segment (start 78.442932 122.911833) (end 78.413141 122.996969) (width 0.109) (layer "In2.Cu") (net 205))
  (segment (start 85.89982 132.869924) (end 85.925039 132.882069) (width 0.109) (layer "In2.Cu") (net 205))
  (segment (start 76.969052 123.472344) (end 76.989604 123.505051) (width 0.109) (layer "In2.Cu") (net 205))
  (segment (start 77.016918 122.332365) (end 77.049625 122.352917) (width 0.109) (layer "In2.Cu") (net 205))
  (segment (start 76.1275 104.327814) (end 76.1275 108.322186) (width 0.109) (layer "In2.Cu") (net 205))
  (segment (start 78.0295 103.130967) (end 77.324347 103.130967) (width 0.109) (layer "In2.Cu") (net 205))
  (segment (start 77.077657 103.637873) (end 77.081508 103.641724) (width 0.109) (layer "In2.Cu") (net 205))
  (segment (start 77.12447 122.37) (end 78.050233 122.37) (width 0.109) (layer "In2.Cu") (net 205))
  (segment (start 77.086085 121.165675) (end 77.12447 121.17) (width 0.109) (layer "In2.Cu") (net 205))
  (segment (start 77.692401 123.883166) (end 77.7025 123.972797) (width 0.109) (layer "In2.Cu") (net 205))
  (segment (start 78.45303 122.772797) (end 78.45303 122.822202) (width 0.109) (layer "In2.Cu") (net 205))
  (segment (start 76.4025 108.597186) (end 76.4025 109.852814) (width 0.109) (layer "In2.Cu") (net 205))
  (segment (start 76.956294 123.435884) (end 76.969052 123.472344) (width 0.109) (layer "In2.Cu") (net 205))
  (segment (start 78.301373 122.457877) (end 78.365153 122.521657) (width 0.109) (layer "In2.Cu") (net 205))
  (segment (start 76.956294 121.035884) (end 76.969052 121.072344) (width 0.109) (layer "In2.Cu") (net 205))
  (segment (start 78.442932 121.483166) (end 78.45303 121.572797) (width 0.109) (layer "In2.Cu") (net 205))
  (segment (start 77.550842 120.737122) (end 77.474469 120.78511) (width 0.109) (layer "In2.Cu") (net 205))
  (segment (start 76.989604 121.105051) (end 77.016918 121.132365) (width 0.109) (layer "In2.Cu") (net 205))
  (segment (start 76.989604 122.305051) (end 77.016918 122.332365) (width 0.109) (layer "In2.Cu") (net 205))
  (segment (start 85.910559 133.212739) (end 85.922704 133.237958) (width 0.109) (layer "In2.Cu") (net 205))
  (segment (start 77.051969 103.40987) (end 77.034092 103.446993) (width 0.109) (layer "In2.Cu") (net 205))
  (segment (start 76.626564 103.854522) (end 76.589442 103.8724) (width 0.109) (layer "In2.Cu") (net 205))
  (segment (start 78.45303 121.572797) (end 78.45303 121.622202) (width 0.109) (layer "In2.Cu") (net 205))
  (segment (start 85.633706 132.935886) (end 85.660996 132.942114) (width 0.109) (layer "In2.Cu") (net 205))
  (segment (start 77.034092 103.446993) (end 77.024922 103.487164) (width 0.109) (layer "In2.Cu") (net 205))
  (segment (start 76.969052 122.122655) (end 76.956294 122.159115) (width 0.109) (layer "In2.Cu") (net 205))
  (segment (start 78.050233 121.17) (end 78.139864 121.180098) (width 0.109) (layer "In2.Cu") (net 205))
  (segment (start 78.050233 123.225) (end 77.12447 123.225) (width 0.109) (layer "In2.Cu") (net 205))
  (segment (start 77.049625 122.352917) (end 77.086085 122.365675) (width 0.109) (layer "In2.Cu") (net 205))
  (segment (start 78.119315 125.124016) (end 78.146605 125.130244) (width 0.109) (layer "In2.Cu") (net 205))
  (segment (start 77.474469 123.609889) (end 77.550842 123.657877) (width 0.109) (layer "In2.Cu") (net 205))
  (segment (start 77.049295 103.927629) (end 77.012172 103.945506) (width 0.109) (layer "In2.Cu") (net 205))
  (segment (start 77.299702 120.825) (end 77.12447 120.825) (width 0.109) (layer "In2.Cu") (net 205))
  (segment (start 85.904331 133.157459) (end 85.904331 133.18545) (width 0.109) (layer "In2.Cu") (net 205))
  (segment (start 77.107197 103.869725) (end 77.081509 103.901938) (width 0.109) (layer "In2.Cu") (net 205))
  (segment (start 78.17061 125.45173) (end 78.176838 125.47902) (width 0.109) (layer "In2.Cu") (net 205))
  (segment (start 76.748108 103.854521) (end 76.707938 103.845353) (width 0.109) (layer "In2.Cu") (net 205))
  (segment (start 78.301373 121.257877) (end 78.365153 121.321657) (width 0.109) (layer "In2.Cu") (net 205))
  (segment (start 78.413141 121.796969) (end 78.365153 121.873342) (width 0.109) (layer "In2.Cu") (net 205))
  (segment (start 78.206436 125.17257) (end 78.223889 125.194455) (width 0.109) (layer "In2.Cu") (net 205))
  (segment (start 78.225 122.409889) (end 78.301373 122.457877) (width 0.109) (layer "In2.Cu") (net 205))
  (segment (start 78.091325 125.124017) (end 78.119315 125.124016) (width 0.109) (layer "In2.Cu") (net 205))
  (segment (start 85.922704 133.237958) (end 85.940157 133.259843) (width 0.109) (layer "In2.Cu") (net 205))
  (segment (start 78.188983 125.371231) (end 78.176838 125.39645) (width 0.109) (layer "In2.Cu") (net 205))
  (segment (start 78.2 103.301467) (end 78.0295 103.130967) (width 0.109) (layer "In2.Cu") (net 205))
  (segment (start 85.904331 133.18545) (end 85.910559 133.212739) (width 0.109) (layer "In2.Cu") (net 205))
  (segment (start 78.45303 121.622202) (end 78.442932 121.711833) (width 0.109) (layer "In2.Cu") (net 205))
  (segment (start 77.7025 123.972797) (end 77.7025 125.022186) (width 0.109) (layer "In2.Cu") (net 205))
  (segment (start 77.692401 120.511833) (end 77.66261 120.596969) (width 0.109) (layer "In2.Cu") (net 205))
  (segment (start 76.956294 122.159115) (end 76.95197 122.1975) (width 0.109) (layer "In2.Cu") (net 205))
  (segment (start 77.12447 123.225) (end 77.086085 123.229324) (width 0.109) (layer "In2.Cu") (net 205))
  (segment (start 77.081508 103.641724) (end 77.107197 103.673937) (width 0.109) (layer "In2.Cu") (net 205))
  (segment (start 76.817443 103.898089) (end 76.78523 103.8724) (width 0.109) (layer "In2.Cu") (net 205))
  (segment (start 77.134244 103.751229) (end 77.134243 103.792433) (width 0.109) (layer "In2.Cu") (net 205))
  (segment (start 76.989604 123.289948) (end 76.969052 123.322655) (width 0.109) (layer "In2.Cu") (net 205))
  (segment (start 91.55 133.125) (end 91.55 133.052162) (width 0.109) (layer "In2.Cu") (net 205))
  (segment (start 78.301373 121.937122) (end 78.225 121.98511) (width 0.109) (layer "In2.Cu") (net 205))
  (segment (start 76.972003 103.954674) (end 76.930799 103.954675) (width 0.109) (layer "In2.Cu") (net 205))
  (segment (start 85.922704 133.10495) (end 85.910559 133.130169) (width 0.109) (layer "In2.Cu") (net 205))
  (segment (start 78.442932 122.683166) (end 78.45303 122.772797) (width 0.109) (layer "In2.Cu") (net 205))
  (segment (start 91.55 133.052162) (end 91.551001 133.051161) (width 0.109) (layer "In2.Cu") (net 205))
  (segment (start 76.821293 103.901939) (end 76.817443 103.898089) (width 0.109) (layer "In2.Cu") (net 205))
  (segment (start 78.45303 122.822202) (end 78.442932 122.911833) (width 0.109) (layer "In2.Cu") (net 205))
  (segment (start 77.389333 123.580098) (end 77.474469 123.609889) (width 0.109) (layer "In2.Cu") (net 205))
  (segment (start 76.969052 120.922655) (end 76.956294 120.959115) (width 0.109) (layer "In2.Cu") (net 205))
  (segment (start 86.027814 133.3475) (end 91.3275 133.3475) (width 0.109) (layer "In2.Cu") (net 205))
  (segment (start 77.12447 120.825) (end 77.086085 120.829324) (width 0.109) (layer "In2.Cu") (net 205))
  (segment (start 76.969052 121.072344) (end 76.989604 121.105051) (width 0.109) (layer "In2.Cu") (net 205))
  (segment (start 77.077657 103.377657) (end 77.051969 103.40987) (width 0.109) (layer "In2.Cu") (net 205))
  (segment (start 91.551001 133.051161) (end 91.551001 132.649499) (width 0.109) (layer "In2.Cu") (net 205))
  (segment (start 76.557228 103.898087) (end 76.1275 104.327814) (width 0.109) (layer "In2.Cu") (net 205))
  (segment (start 76.969052 122.272344) (end 76.989604 122.305051) (width 0.109) (layer "In2.Cu") (net 205))
  (segment (start 78.413141 122.59803) (end 78.442932 122.683166) (width 0.109) (layer "In2.Cu") (net 205))
  (segment (start 78.176838 125.39645) (end 78.170609 125.423738) (width 0.109) (layer "In2.Cu") (net 205))
  (segment (start 76.930799 103.954675) (end 76.89063 103.945506) (width 0.109) (layer "In2.Cu") (net 205))
  (segment (start 78.050233 122.025) (end 77.12447 122.025) (width 0.109) (layer "In2.Cu") (net 205))
  (segment (start 85.976521 133.029195) (end 85.964376 133.054414) (width 0.109) (layer "In2.Cu") (net 205))
  (segment (start 85.770147 132.899522) (end 85.792031 132.882069) (width 0.109) (layer "In2.Cu") (net 205))
  (segment (start 77.086085 120.829324) (end 77.049625 120.842082) (width 0.109) (layer "In2.Cu") (net 205))
  (segment (start 85.792031 132.882069) (end 85.81725 132.869924) (width 0.109) (layer "In2.Cu") (net 205))
  (segment (start 85.946924 132.899522) (end 85.964376 132.921406) (width 0.109) (layer "In2.Cu") (net 205))
  (segment (start 78.206435 125.526122) (end 85.586603 132.906289) (width 0.109) (layer "In2.Cu") (net 205))
  (segment (start 77.995049 125.177295) (end 78.016933 125.159843) (width 0.109) (layer "In2.Cu") (net 205))
  (segment (start 78.225 121.98511) (end 78.139864 122.014901) (width 0.109) (layer "In2.Cu") (net 205))
  (segment (start 85.763379 132.906289) (end 85.770147 132.899522) (width 0.109) (layer "In2.Cu") (net 205))
  (segment (start 78.050233 122.37) (end 78.139864 122.380098) (width 0.109) (layer "In2.Cu") (net 205))
  (segment (start 91.551001 132.649499) (end 91.9815 132.219) (width 0.109) (layer "In2.Cu") (net 205))
  (segment (start 76.989604 123.505051) (end 77.016918 123.532365) (width 0.109) (layer "In2.Cu") (net 205))
  (segment (start 77.034092 103.568535) (end 77.051969 103.605658) (width 0.109) (layer "In2.Cu") (net 205))
  (segment (start 77.081509 103.901938) (end 77.049295 103.927629) (width 0.109) (layer "In2.Cu") (net 205))
  (segment (start 76.707938 103.845353) (end 76.666734 103.845354) (width 0.109) (layer "In2.Cu") (net 205))
  (segment (start 77.024922 103.487164) (end 77.024923 103.528366) (width 0.109) (layer "In2.Cu") (net 205))
  (segment (start 76.989604 120.889948) (end 76.969052 120.922655) (width 0.109) (layer "In2.Cu") (net 205))
  (segment (start 85.976521 132.946625) (end 85.982749 132.973915) (width 0.109) (layer "In2.Cu") (net 205))
  (segment (start 77.862041 125.177295) (end 77.88726 125.18944) (width 0.109) (layer "In2.Cu") (net 205))
  (segment (start 77.086085 123.565675) (end 77.12447 123.57) (width 0.109) (layer "In2.Cu") (net 205))
  (segment (start 85.872531 132.863696) (end 85.89982 132.869924) (width 0.109) (layer "In2.Cu") (net 205))
  (segment (start 85.688987 132.942114) (end 85.716276 132.935886) (width 0.109) (layer "In2.Cu") (net 205))
  (segment (start 77.049625 120.842082) (end 77.016918 120.862634) (width 0.109) (layer "In2.Cu") (net 205))
  (segment (start 77.086085 122.029324) (end 77.049625 122.042082) (width 0.109) (layer "In2.Cu") (net 205))
  (segment (start 77.016918 123.532365) (end 77.049625 123.552917) (width 0.109) (layer "In2.Cu") (net 205))
  (segment (start 85.925039 132.882069) (end 85.946924 132.899522) (width 0.109) (layer "In2.Cu") (net 205))
  (segment (start 78.365153 121.873342) (end 78.301373 121.937122) (width 0.109) (layer "In2.Cu") (net 205))
  (segment (start 77.049625 123.242082) (end 77.016918 123.262634) (width 0.109) (layer "In2.Cu") (net 205))
  (segment (start 78.413141 121.39803) (end 78.442932 121.483166) (width 0.109) (layer "In2.Cu") (net 205))
  (segment (start 77.016918 120.862634) (end 76.989604 120.889948) (width 0.109) (layer "In2.Cu") (net 205))
  (segment (start 77.88726 125.18944) (end 77.914548 125.195667) (width 0.109) (layer "In2.Cu") (net 205))
  (segment (start 78.139864 122.380098) (end 78.225 122.409889) (width 0.109) (layer "In2.Cu") (net 205))
  (segment (start 77.086085 122.365675) (end 77.12447 122.37) (width 0.109) (layer "In2.Cu") (net 205))
  (segment (start 77.12447 123.57) (end 77.299702 123.57) (width 0.109) (layer "In2.Cu") (net 205))
  (segment (start 77.94254 125.195668) (end 77.96983 125.18944) (width 0.109) (layer "In2.Cu") (net 205))
  (segment (start 78.206435 125.349346) (end 78.188983 125.371231) (width 0.109) (layer "In2.Cu") (net 205))
  (segment (start 76.969052 123.322655) (end 76.956294 123.359115) (width 0.109) (layer "In2.Cu") (net 205))
  (segment (start 78.064035 125.130244) (end 78.091325 125.124017) (width 0.109) (layer "In2.Cu") (net 205))
  (segment (start 85.940157 133.083066) (end 85.922704 133.10495) (width 0.109) (layer "In2.Cu") (net 205))
  (segment (start 77.125076 103.711059) (end 77.134244 103.751229) (width 0.109) (layer "In2.Cu") (net 205))
  (segment (start 78.193709 125.159843) (end 78.206436 125.17257) (width 0.109) (layer "In2.Cu") (net 205))
  (segment (start 77.614622 123.721657) (end 77.66261 123.79803) (width 0.109) (layer "In2.Cu") (net 205))
  (segment (start 78.242262 125.274954) (end 78.236032 125.302243) (width 0.109) (layer "In2.Cu") (net 205))
  (segment (start 77.96983 125.18944) (end 77.995049 125.177295) (width 0.109) (layer "In2.Cu") (net 205))
  (segment (start 85.982749 132.973915) (end 85.982749 133.001906) (width 0.109) (layer "In2.Cu") (net 205))
  (segment (start 77.086085 123.229324) (end 77.049625 123.242082) (width 0.109) (layer "In2.Cu") (net 205))
  (segment (start 85.946924 133.076298) (end 85.940157 133.083066) (width 0.109) (layer "In2.Cu") (net 205))
  (segment (start 77.324347 103.130967) (end 77.077657 103.377657) (width 0.109) (layer "In2.Cu") (net 205))
  (segment (start 78.223889 125.327463) (end 78.206435 125.349346) (width 0.109) (layer "In2.Cu") (net 205))
  (segment (start 78.442932 121.711833) (end 78.413141 121.796969) (width 0.109) (layer "In2.Cu") (net 205))
  (segment (start 78.236032 125.302243) (end 78.223889 125.327463) (width 0.109) (layer "In2.Cu") (net 205))
  (segment (start 78.170609 125.423738) (end 78.17061 125.45173) (width 0.109) (layer "In2.Cu") (net 205))
  (segment (start 78.171824 125.142389) (end 78.193709 125.159843) (width 0.109) (layer "In2.Cu") (net 205))
  (segment (start 85.586603 132.906289) (end 85.608487 132.923741) (width 0.109) (layer "In2.Cu") (net 205))
  (segment (start 77.049625 121.152917) (end 77.086085 121.165675) (width 0.109) (layer "In2.Cu") (net 205))
  (segment (start 76.95197 122.1975) (end 76.956294 122.235884) (width 0.109) (layer "In2.Cu") (net 205))
  (segment (start 78.038816 125.142389) (end 78.064035 125.130244) (width 0.109) (layer "In2.Cu") (net 205))
  (segment (start 77.840157 125.159843) (end 77.862041 125.177295) (width 0.109) (layer "In2.Cu") (net 205))
  (segment (start 77.016918 122.062634) (end 76.989604 122.089948) (width 0.109) (layer "In2.Cu") (net 205))
  (segment (start 76.1275 118.197186) (end 77.7025 119.772186) (width 0.109) (layer "In2.Cu") (net 205))
  (segment (start 77.12447 122.025) (end 77.086085 122.029324) (width 0.109) (layer "In2.Cu") (net 205))
  (segment (start 77.012172 103.945506) (end 76.972003 103.954674) (width 0.109) (layer "In2.Cu") (net 205))
  (segment (start 77.614622 120.673342) (end 77.550842 120.737122) (width 0.109) (layer "In2.Cu") (net 205))
  (segment (start 85.84454 132.863696) (end 85.872531 132.863696) (width 0.109) (layer "In2.Cu") (net 205))
  (segment (start 77.107197 103.673937) (end 77.125076 103.711059) (width 0.109) (layer "In2.Cu") (net 205))
  (segment (start 76.4025 109.852814) (end 76.1275 110.127814) (width 0.109) (layer "In2.Cu") (net 205))
  (segment (start 85.608487 132.923741) (end 85.633706 132.935886) (width 0.109) (layer "In2.Cu") (net 205))
  (segment (start 78.146605 125.130244) (end 78.171824 125.142389) (width 0.109) (layer "In2.Cu") (net 205))
  (segment (start 76.989604 122.089948) (end 76.969052 122.122655) (width 0.109) (layer "In2.Cu") (net 205))
  (segment (start 77.024923 103.528366) (end 77.034092 103.568535) (width 0.109) (layer "In2.Cu") (net 205))
  (segment (start 77.016918 121.132365) (end 77.049625 121.152917) (width 0.109) (layer "In2.Cu") (net 205))
  (segment (start 78.139864 122.014901) (end 78.050233 122.025) (width 0.109) (layer "In2.Cu") (net 205))
  (segment (start 77.7025 125.022186) (end 77.840157 125.159843) (width 0.109) (layer "In2.Cu") (net 205))
  (segment (start 76.853507 103.927629) (end 76.821293 103.901939) (width 0.109) (layer "In2.Cu") (net 205))
  (segment (start 76.78523 103.8724) (end 76.748108 103.854521) (width 0.109) (layer "In2.Cu") (net 205))
  (segment (start 85.716276 132.935886) (end 85.741495 132.923741) (width 0.109) (layer "In2.Cu") (net 205))
  (segment (start 80.938999 103.189) (end 80.999999 103.25) (width 0.182) (layer "B.Cu") (net 205))
  (segment (start 78.309 103.192467) (end 78.2 103.301467) (width 0.182) (layer "B.Cu") (net 205))
  (segment (start 78.2 103.301467) (end 78.2 103.301468) (width 0.182) (layer "B.Cu") (net 205))
  (segment (start 80.935532 103.192467) (end 78.309 103.192467) (width 0.182) (layer "B.Cu") (net 205))
  (segment (start 80.935532 103.192467) (end 80.938999 103.189) (width 0.182) (layer "B.Cu") (net 205))
  (segment (start 80.999999 103.25) (end 81.9 103.25) (width 0.182) (layer "B.Cu") (net 205))
  (segment (start 90.7865 131.274) (end 91.1715 130.964) (width 0.182) (layer "F.Cu") (net 206))
  (via (at 78.35 104.098532) (size 0.45) (drill 0.1) (layers "F.Cu" "B.Cu") (net 206))
  (via (at 91.1715 130.964) (size 0.45) (drill 0.1) (layers "F.Cu" "B.Cu") (net 206))
  (segment (start 81.835363 128.351961) (end 81.835363 128.442159) (width 0.109) (layer "In2.Cu") (net 206))
  (segment (start 83.333835 127.944476) (end 83.368637 127.927716) (width 0.109) (layer "In2.Cu") (net 206))
  (segment (start 89.929047 131.998265) (end 89.950265 131.977047) (width 0.109) (layer "In2.Cu") (net 206))
  (segment (start 89.740734 131.977047) (end 89.761952 131.998265) (width 0.109) (layer "In2.Cu") (net 206))
  (segment (start 82.799331 128.960763) (end 82.743093 129.031283) (width 0.109) (layer "In2.Cu") (net 206))
  (segment (start 89.982859 131.781682) (end 89.99277 131.753359) (width 0.109) (layer "In2.Cu") (net 206))
  (segment (start 89.8455 132.0275) (end 89.875317 132.02414) (width 0.109) (layer "In2.Cu") (net 206))
  (segment (start 84.260735 129.196407) (end 84.204498 129.266926) (width 0.109) (layer "In2.Cu") (net 206))
  (segment (start 84.182359 128.793) (end 84.217161 128.77624) (width 0.109) (layer "In2.Cu") (net 206))
  (segment (start 78.1795 104.269032) (end 77.300654 104.269032) (width 0.109) (layer "In2.Cu") (net 206))
  (segment (start 77.300654 104.269032) (end 76.6725 104.897186) (width 0.109) (layer "In2.Cu") (net 206))
  (segment (start 84.445548 128.958372) (end 84.436952 128.996032) (width 0.109) (layer "In2.Cu") (net 206))
  (segment (start 83.073987 129.680783) (end 83.164185 129.680783) (width 0.109) (layer "In2.Cu") (net 206))
  (segment (start 82.484863 128.773052) (end 82.555383 128.716815) (width 0.109) (layer "In2.Cu") (net 206))
  (segment (start 90.083682 131.680859) (end 90.1135 131.6775) (width 0.109) (layer "In2.Cu") (net 206))
  (segment (start 81.855434 128.530096) (end 81.894569 128.611361) (width 0.109) (layer "In2.Cu") (net 206))
  (segment (start 82.634059 127.079191) (end 82.668861 127.095951) (width 0.109) (layer "In2.Cu") (net 206))
  (segment (start 89.950265 131.977047) (end 89.966229 131.95164) (width 0.109) (layer "In2.Cu") (net 206))
  (segment (start 82.520113 127.079192) (end 82.557773 127.070596) (width 0.109) (layer "In2.Cu") (net 206))
  (segment (start 80.459842 126.209107) (end 80.253758 126.41519) (width 0.109) (layer "In2.Cu") (net 206))
  (segment (start 89.97614 131.923317) (end 89.9795 131.8935) (width 0.109) (layer "In2.Cu") (net 206))
  (segment (start 81.874621 126.301711) (end 81.891381 126.336514) (width 0.109) (layer "In2.Cu") (net 206))
  (segment (start 84.331107 128.776239) (end 84.365909 128.792999) (width 0.109) (layer "In2.Cu") (net 206))
  (segment (start 90.029952 131.706734) (end 90.055359 131.69077) (width 0.109) (layer "In2.Cu") (net 206))
  (segment (start 82.98605 129.660712) (end 83.073987 129.680783) (width 0.109) (layer "In2.Cu") (net 206))
  (segment (start 81.747875 126.222071) (end 81.785535 126.230667) (width 0.109) (layer "In2.Cu") (net 206))
  (segment (start 80.986839 127.503437) (end 80.986839 127.593635) (width 0.109) (layer "In2.Cu") (net 206))
  (segment (start 81.00691 127.4155) (end 80.986839 127.503437) (width 0.109) (layer "In2.Cu") (net 206))
  (segment (start 76.6725 116.502814) (end 79.3725 119.202814) (width 0.109) (layer "In2.Cu") (net 206))
  (segment (start 80.618612 127.13521) (end 80.706548 127.115139) (width 0.109) (layer "In2.Cu") (net 206))
  (segment (start 84.145292 129.436129) (end 84.145292 129.526327) (width 0.109) (layer "In2.Cu") (net 206))
  (segment (start 76.6725 107.702814) (end 76.9725 108.002814) (width 0.109) (layer "In2.Cu") (net 206))
  (segment (start 89.70814 131.781682) (end 89.7115 131.8115) (width 0.109) (layer "In2.Cu") (net 206))
  (segment (start 84.217161 128.77624) (end 84.254821 128.767644) (width 0.109) (layer "In2.Cu") (net 206))
  (segment (start 80.158385 126.833047) (end 80.19752 126.914312) (width 0.109) (layer "In2.Cu") (net 206))
  (segment (start 84.436953 128.882086) (end 84.445549 128.919746) (width 0.109) (layer "In2.Cu") (net 206))
  (segment (start 81.137217 127.868291) (end 81.207736 127.924528) (width 0.109) (layer "In2.Cu") (net 206))
  (segment (start 89.63564 131.69077) (end 89.661047 131.706734) (width 0.109) (layer "In2.Cu") (net 206))
  (segment (start 82.557773 127.070596) (end 82.596399 127.070595) (width 0.109) (layer "In2.Cu") (net 206))
  (segment (start 80.500686 126.030158) (end 80.509282 126.067818) (width 0.109) (layer "In2.Cu") (net 206))
  (segment (start 89.966229 131.95164) (end 89.97614 131.923317) (width 0.109) (layer "In2.Cu") (net 206))
  (segment (start 82.596399 127.070595) (end 82.634059 127.079191) (width 0.109) (layer "In2.Cu") (net 206))
  (segment (start 82.703958 129.112548) (end 82.683887 129.200485) (width 0.109) (layer "In2.Cu") (net 206))
  (segment (start 89.5775 131.6775) (end 89.607317 131.680859) (width 0.109) (layer "In2.Cu") (net 206))
  (segment (start 83.333387 129.621576) (end 83.403907 129.565339) (width 0.109) (layer "In2.Cu") (net 206))
  (segment (start 80.19752 126.914312) (end 80.253758 126.984832) (width 0.109) (layer "In2.Cu") (net 206))
  (segment (start 80.528414 127.13521) (end 80.618612 127.13521) (width 0.109) (layer "In2.Cu") (net 206))
  (segment (start 82.683887 129.290683) (end 82.703958 129.37862) (width 0.109) (layer "In2.Cu") (net 206))
  (segment (start 83.403907 129.565339) (end 84.152157 128.817083) (width 0.109) (layer "In2.Cu") (net 206))
  (segment (start 81.636339 127.924528) (end 81.706859 127.868291) (width 0.109) (layer "In2.Cu") (net 206))
  (segment (start 84.254821 128.767644) (end 84.293447 128.767643) (width 0.109) (layer "In2.Cu") (net 206))
  (segment (start 81.894569 128.182759) (end 81.855434 128.264024) (width 0.109) (layer "In2.Cu") (net 206))
  (segment (start 82.668861 127.095951) (end 82.699061 127.120035) (width 0.109) (layer "In2.Cu") (net 206))
  (segment (start 81.899976 126.4128) (end 81.89138 126.45046) (width 0.109) (layer "In2.Cu") (net 206))
  (segment (start 81.820337 126.247427) (end 81.850537 126.271511) (width 0.109) (layer "In2.Cu") (net 206))
  (segment (start 80.483926 125.995356) (end 80.500686 126.030158) (width 0.109) (layer "In2.Cu") (net 206))
  (segment (start 82.723145 127.150235) (end 82.739905 127.185038) (width 0.109) (layer "In2.Cu") (net 206))
  (segment (start 90.1135 131.6775) (end 90.6925 131.6775) (width 0.109) (layer "In2.Cu") (net 206))
  (segment (start 84.145292 129.526327) (end 84.165363 129.614264) (width 0.109) (layer "In2.Cu") (net 206))
  (segment (start 81.709249 126.222072) (end 81.747875 126.222071) (width 0.109) (layer "In2.Cu") (net 206))
  (segment (start 82.739904 127.298984) (end 82.723146 127.333787) (width 0.109) (layer "In2.Cu") (net 206))
  (segment (start 90.99 131.38) (end 90.99 131.1455) (width 0.109) (layer "In2.Cu") (net 206))
  (segment (start 80.986839 127.593635) (end 81.00691 127.681572) (width 0.109) (layer "In2.Cu") (net 206))
  (segment (start 83.597025 128.071222) (end 83.597024 128.109848) (width 0.109) (layer "In2.Cu") (net 206))
  (segment (start 80.359211 127.076003) (end 80.440477 127.115139) (width 0.109) (layer "In2.Cu") (net 206))
  (segment (start 83.482583 127.927715) (end 83.517385 127.944475) (width 0.109) (layer "In2.Cu") (net 206))
  (segment (start 80.19752 126.48571) (end 80.158385 126.566976) (width 0.109) (layer "In2.Cu") (net 206))
  (segment (start 90.99 131.1455) (end 91.1715 130.964) (width 0.109) (layer "In2.Cu") (net 206))
  (segment (start 80.459842 125.965156) (end 80.483926 125.995356) (width 0.109) (layer "In2.Cu") (net 206))
  (segment (start 80.706548 127.115139) (end 80.787814 127.076003) (width 0.109) (layer "In2.Cu") (net 206))
  (segment (start 80.253758 126.41519) (end 80.19752 126.48571) (width 0.109) (layer "In2.Cu") (net 206))
  (segment (start 89.761952 131.998265) (end 89.787359 132.014229) (width 0.109) (layer "In2.Cu") (net 206))
  (segment (start 82.904784 129.621576) (end 82.98605 129.660712) (width 0.109) (layer "In2.Cu") (net 206))
  (segment (start 89.714859 131.923317) (end 89.72477 131.95164) (width 0.109) (layer "In2.Cu") (net 206))
  (segment (start 83.406297 127.91912) (end 83.444923 127.919119) (width 0.109) (layer "In2.Cu") (net 206))
  (segment (start 76.9725 110.422186) (end 76.6725 110.722186) (width 0.109) (layer "In2.Cu") (net 206))
  (segment (start 84.445549 128.919746) (end 84.445548 128.958372) (width 0.109) (layer "In2.Cu") (net 206))
  (segment (start 83.588429 128.033562) (end 83.597025 128.071222) (width 0.109) (layer "In2.Cu") (net 206))
  (segment (start 84.204499 129.69553) (end 84.260736 129.766049) (width 0.109) (layer "In2.Cu") (net 206))
  (segment (start 80.158385 126.566976) (end 80.138314 126.654912) (width 0.109) (layer "In2.Cu") (net 206))
  (segment (start 84.420194 129.030835) (end 84.39611 129.061035) (width 0.109) (layer "In2.Cu") (net 206))
  (segment (start 81.102283 127.833357) (end 81.137217 127.868291) (width 0.109) (layer "In2.Cu") (net 206))
  (segment (start 84.365909 128.792999) (end 84.396109 128.817083) (width 0.109) (layer "In2.Cu") (net 206))
  (segment (start 81.874622 126.485263) (end 81.850538 126.515463) (width 0.109) (layer "In2.Cu") (net 206))
  (segment (start 80.500686 126.144105) (end 80.483926 126.178907) (width 0.109) (layer "In2.Cu") (net 206))
  (segment (start 84.204498 129.266926) (end 84.165362 129.348192) (width 0.109) (layer "In2.Cu") (net 206))
  (segment (start 79.3725 124.877814) (end 80.459842 125.965156) (width 0.109) (layer "In2.Cu") (net 206))
  (segment (start 89.72477 131.95164) (end 89.740734 131.977047) (width 0.109) (layer "In2.Cu") (net 206))
  (segment (start 81.891381 126.336514) (end 81.899977 126.374174) (width 0.109) (layer "In2.Cu") (net 206))
  (segment (start 84.260736 129.766049) (end 86.172186 131.6775) (width 0.109) (layer "In2.Cu") (net 206))
  (segment (start 89.7115 131.8935) (end 89.714859 131.923317) (width 0.109) (layer "In2.Cu") (net 206))
  (segment (start 76.6725 104.897186) (end 76.6725 107.702814) (width 0.109) (layer "In2.Cu") (net 206))
  (segment (start 81.102283 127.263715) (end 81.046045 127.334235) (width 0.109) (layer "In2.Cu") (net 206))
  (segment (start 89.698229 131.753359) (end 89.70814 131.781682) (width 0.109) (layer "In2.Cu") (net 206))
  (segment (start 83.597024 128.109848) (end 83.588428 128.147508) (width 0.109) (layer "In2.Cu") (net 206))
  (segment (start 84.436952 128.996032) (end 84.420194 129.030835) (width 0.109) (layer "In2.Cu") (net 206))
  (segment (start 80.858334 127.019766) (end 81.606585 126.271511) (width 0.109) (layer "In2.Cu") (net 206))
  (segment (start 84.152157 128.817083) (end 84.182359 128.793) (width 0.109) (layer "In2.Cu") (net 206))
  (segment (start 81.207736 127.924528) (end 81.289002 127.963664) (width 0.109) (layer "In2.Cu") (net 206))
  (segment (start 80.509282 126.067818) (end 80.509282 126.106445) (width 0.109) (layer "In2.Cu") (net 206))
  (segment (start 82.834265 129.565339) (end 82.904784 129.621576) (width 0.109) (layer "In2.Cu") (net 206))
  (segment (start 83.303633 127.968559) (end 83.333835 127.944476) (width 0.109) (layer "In2.Cu") (net 206))
  (segment (start 81.850537 126.271511) (end 81.874621 126.301711) (width 0.109) (layer "In2.Cu") (net 206))
  (segment (start 82.748501 127.222698) (end 82.7485 127.261324) (width 0.109) (layer "In2.Cu") (net 206))
  (segment (start 89.875317 132.02414) (end 89.90364 132.014229) (width 0.109) (layer "In2.Cu") (net 206))
  (segment (start 81.785535 126.230667) (end 81.820337 126.247427) (width 0.109) (layer "In2.Cu") (net 206))
  (segment (start 80.253758 126.984832) (end 80.288692 127.019766) (width 0.109) (layer "In2.Cu") (net 206))
  (segment (start 83.517385 127.944475) (end 83.547585 127.968559) (width 0.109) (layer "In2.Cu") (net 206))
  (segment (start 84.293447 128.767643) (end 84.331107 128.776239) (width 0.109) (layer "In2.Cu") (net 206))
  (segment (start 81.606585 126.271511) (end 81.636787 126.247428) (width 0.109) (layer "In2.Cu") (net 206))
  (segment (start 83.547585 127.968559) (end 83.571669 127.998759) (width 0.109) (layer "In2.Cu") (net 206))
  (segment (start 81.985741 128.716815) (end 82.05626 128.773052) (width 0.109) (layer "In2.Cu") (net 206))
  (segment (start 83.588428 128.147508) (end 83.57167 128.182311) (width 0.109) (layer "In2.Cu") (net 206))
  (segment (start 81.894569 128.611361) (end 81.950807 128.681881) (width 0.109) (layer "In2.Cu") (net 206))
  (segment (start 79.3725 119.202814) (end 79.3725 124.877814) (width 0.109) (layer "In2.Cu") (net 206))
  (segment (start 83.547586 128.212511) (end 82.799331 128.960763) (width 0.109) (layer "In2.Cu") (net 206))
  (segment (start 82.225463 128.832259) (end 82.315661 128.832259) (width 0.109) (layer "In2.Cu") (net 206))
  (segment (start 89.9795 131.8935) (end 89.9795 131.8115) (width 0.109) (layer "In2.Cu") (net 206))
  (segment (start 81.855434 128.264024) (end 81.835363 128.351961) (width 0.109) (layer "In2.Cu") (net 206))
  (segment (start 90.055359 131.69077) (end 90.083682 131.680859) (width 0.109) (layer "In2.Cu") (net 206))
  (segment (start 82.05626 128.773052) (end 82.137526 128.812188) (width 0.109) (layer "In2.Cu") (net 206))
  (segment (start 83.444923 127.919119) (end 83.482583 127.927715) (width 0.109) (layer "In2.Cu") (net 206))
  (segment (start 82.723146 127.333787) (end 82.699062 127.363987) (width 0.109) (layer "In2.Cu") (net 206))
  (segment (start 90.008734 131.727952) (end 90.029952 131.706734) (width 0.109) (layer "In2.Cu") (net 206))
  (segment (start 81.950807 128.681881) (end 81.985741 128.716815) (width 0.109) (layer "In2.Cu") (net 206))
  (segment (start 89.682265 131.727952) (end 89.698229 131.753359) (width 0.109) (layer "In2.Cu") (net 206))
  (segment (start 89.99277 131.753359) (end 90.008734 131.727952) (width 0.109) (layer "In2.Cu") (net 206))
  (segment (start 81.89138 126.45046) (end 81.874622 126.485263) (width 0.109) (layer "In2.Cu") (net 206))
  (segment (start 82.743093 129.031283) (end 82.703958 129.112548) (width 0.109) (layer "In2.Cu") (net 206))
  (segment (start 80.138314 126.654912) (end 80.138314 126.74511) (width 0.109) (layer "In2.Cu") (net 206))
  (segment (start 82.7485 127.261324) (end 82.739904 127.298984) (width 0.109) (layer "In2.Cu") (net 206))
  (segment (start 84.165362 129.348192) (end 84.145292 129.436129) (width 0.109) (layer "In2.Cu") (net 206))
  (segment (start 89.815682 132.02414) (end 89.8455 132.0275) (width 0.109) (layer "In2.Cu") (net 206))
  (segment (start 83.252121 129.660712) (end 83.333387 129.621576) (width 0.109) (layer "In2.Cu") (net 206))
  (segment (start 86.172186 131.6775) (end 89.5775 131.6775) (width 0.109) (layer "In2.Cu") (net 206))
  (segment (start 84.165363 129.614264) (end 84.204499 129.69553) (width 0.109) (layer "In2.Cu") (net 206))
  (segment (start 82.739905 127.185038) (end 82.748501 127.222698) (width 0.109) (layer "In2.Cu") (net 206))
  (segment (start 82.403597 128.812188) (end 82.484863 128.773052) (width 0.109) (layer "In2.Cu") (net 206))
  (segment (start 83.368637 127.927716) (end 83.406297 127.91912) (width 0.109) (layer "In2.Cu") (net 206))
  (segment (start 80.787814 127.076003) (end 80.858334 127.019766) (width 0.109) (layer "In2.Cu") (net 206))
  (segment (start 80.483926 126.178907) (end 80.459842 126.209107) (width 0.109) (layer "In2.Cu") (net 206))
  (segment (start 83.164185 129.680783) (end 83.252121 129.660712) (width 0.109) (layer "In2.Cu") (net 206))
  (segment (start 78.35 104.098532) (end 78.1795 104.269032) (width 0.109) (layer "In2.Cu") (net 206))
  (segment (start 82.485311 127.095952) (end 82.520113 127.079192) (width 0.109) (layer "In2.Cu") (net 206))
  (segment (start 81.899977 126.374174) (end 81.899976 126.4128) (width 0.109) (layer "In2.Cu") (net 206))
  (segment (start 83.571669 127.998759) (end 83.588429 128.033562) (width 0.109) (layer "In2.Cu") (net 206))
  (segment (start 82.555383 128.716815) (end 83.303633 127.968559) (width 0.109) (layer "In2.Cu") (net 206))
  (segment (start 89.9795 131.8115) (end 89.982859 131.781682) (width 0.109) (layer "In2.Cu") (net 206))
  (segment (start 81.467137 127.983735) (end 81.555073 127.963664) (width 0.109) (layer "In2.Cu") (net 206))
  (segment (start 82.683887 129.200485) (end 82.683887 129.290683) (width 0.109) (layer "In2.Cu") (net 206))
  (segment (start 82.743093 129.459885) (end 82.799331 129.530405) (width 0.109) (layer "In2.Cu") (net 206))
  (segment (start 82.455109 127.120035) (end 82.485311 127.095952) (width 0.109) (layer "In2.Cu") (net 206))
  (segment (start 81.835363 128.442159) (end 81.855434 128.530096) (width 0.109) (layer "In2.Cu") (net 206))
  (segment (start 81.555073 127.963664) (end 81.636339 127.924528) (width 0.109) (layer "In2.Cu") (net 206))
  (segment (start 84.420193 128.847283) (end 84.436953 128.882086) (width 0.109) (layer "In2.Cu") (net 206))
  (segment (start 89.787359 132.014229) (end 89.815682 132.02414) (width 0.109) (layer "In2.Cu") (net 206))
  (segment (start 81.850538 126.515463) (end 81.102283 127.263715) (width 0.109) (layer "In2.Cu") (net 206))
  (segment (start 81.671589 126.230668) (end 81.709249 126.222072) (width 0.109) (layer "In2.Cu") (net 206))
  (segment (start 81.706859 127.868291) (end 82.455109 127.120035) (width 0.109) (layer "In2.Cu") (net 206))
  (segment (start 80.509282 126.106445) (end 80.500686 126.144105) (width 0.109) (layer "In2.Cu") (net 206))
  (segment (start 82.799331 129.530405) (end 82.834265 129.565339) (width 0.109) (layer "In2.Cu") (net 206))
  (segment (start 81.376939 127.983735) (end 81.467137 127.983735) (width 0.109) (layer "In2.Cu") (net 206))
  (segment (start 82.699062 127.363987) (end 81.950807 128.112239) (width 0.109) (layer "In2.Cu") (net 206))
  (segment (start 89.7115 131.8115) (end 89.7115 131.8935) (width 0.109) (layer "In2.Cu") (net 206))
  (segment (start 82.703958 129.37862) (end 82.743093 129.459885) (width 0.109) (layer "In2.Cu") (net 206))
  (segment (start 81.636787 126.247428) (end 81.671589 126.230668) (width 0.109) (layer "In2.Cu") (net 206))
  (segment (start 81.00691 127.681572) (end 81.046045 127.762837) (width 0.109) (layer "In2.Cu") (net 206))
  (segment (start 76.9725 108.002814) (end 76.9725 110.422186) (width 0.109) (layer "In2.Cu") (net 206))
  (segment (start 83.57167 128.182311) (end 83.547586 128.212511) (width 0.109) (layer "In2.Cu") (net 206))
  (segment (start 80.288692 127.019766) (end 80.359211 127.076003) (width 0.109) (layer "In2.Cu") (net 206))
  (segment (start 81.046045 127.762837) (end 81.102283 127.833357) (width 0.109) (layer "In2.Cu") (net 206))
  (segment (start 90.6925 131.6775) (end 90.99 131.38) (width 0.109) (layer "In2.Cu") (net 206))
  (segment (start 76.6725 110.722186) (end 76.6725 116.502814) (width 0.109) (layer "In2.Cu") (net 206))
  (segment (start 80.440477 127.115139) (end 80.528414 127.13521) (width 0.109) (layer "In2.Cu") (net 206))
  (segment (start 84.39611 129.061035) (end 84.260735 129.196407) (width 0.109) (layer "In2.Cu") (net 206))
  (segment (start 81.950807 128.112239) (end 81.894569 128.182759) (width 0.109) (layer "In2.Cu") (net 206))
  (segment (start 82.315661 128.832259) (end 82.403597 128.812188) (width 0.109) (layer "In2.Cu") (net 206))
  (segment (start 81.046045 127.334235) (end 81.00691 127.4155) (width 0.109) (layer "In2.Cu") (net 206))
  (segment (start 82.137526 128.812188) (end 82.225463 128.832259) (width 0.109) (layer "In2.Cu") (net 206))
  (segment (start 89.661047 131.706734) (end 89.682265 131.727952) (width 0.109) (layer "In2.Cu") (net 206))
  (segment (start 80.138314 126.74511) (end 80.158385 126.833047) (width 0.109) (layer "In2.Cu") (net 206))
  (segment (start 84.396109 128.817083) (end 84.420193 128.847283) (width 0.109) (layer "In2.Cu") (net 206))
  (segment (start 82.699061 127.120035) (end 82.723145 127.150235) (width 0.109) (layer "In2.Cu") (net 206))
  (segment (start 89.607317 131.680859) (end 89.63564 131.69077) (width 0.109) (layer "In2.Cu") (net 206))
  (segment (start 89.90364 132.014229) (end 89.929047 131.998265) (width 0.109) (layer "In2.Cu") (net 206))
  (segment (start 81.289002 127.963664) (end 81.376939 127.983735) (width 0.109) (layer "In2.Cu") (net 206))
  (segment (start 80.938999 103.811) (end 80.999999 103.75) (width 0.182) (layer "B.Cu") (net 206))
  (segment (start 80.22518 104.207532) (end 78.459 104.207532) (width 0.182) (layer "B.Cu") (net 206))
  (segment (start 80.621712 103.811) (end 80.938999 103.811) (width 0.182) (layer "B.Cu") (net 206))
  (segment (start 80.999999 103.75) (end 81.9 103.75) (width 0.182) (layer "B.Cu") (net 206))
  (segment (start 80.22518 104.207532) (end 80.621712 103.811) (width 0.182) (layer "B.Cu") (net 206))
  (segment (start 78.459 104.207532) (end 78.35 104.098532) (width 0.182) (layer "B.Cu") (net 206))
  (segment (start 90.7865 130.639) (end 91.1715 130.328999) (width 0.182) (layer "F.Cu") (net 207))
  (via (at 78.35 104.694533) (size 0.45) (drill 0.1) (layers "F.Cu" "B.Cu") (net 207))
  (via (at 91.1715 130.328999) (size 0.45) (drill 0.1) (layers "F.Cu" "B.Cu") (net 207))
  (segment (start 82.992214 127.375046) (end 82.953078 127.456312) (width 0.109) (layer "In2.Cu") (net 207))
  (segment (start 82.163762 126.438587) (end 82.14369 126.526522) (width 0.109) (layer "In2.Cu") (net 207))
  (segment (start 82.362786 126.86602) (end 82.444052 126.826884) (width 0.109) (layer "In2.Cu") (net 207))
  (segment (start 84.409076 129.500542) (end 84.417673 129.538202) (width 0.109) (layer "In2.Cu") (net 207))
  (segment (start 82.107742 128.340087) (end 82.099147 128.377746) (width 0.109) (layer "In2.Cu") (net 207))
  (segment (start 80.451538 126.578036) (end 80.427454 126.608236) (width 0.109) (layer "In2.Cu") (net 207))
  (segment (start 80.481738 126.846072) (end 80.51654 126.862831) (width 0.109) (layer "In2.Cu") (net 207))
  (segment (start 83.727899 128.392824) (end 82.99711 129.123608) (width 0.109) (layer "In2.Cu") (net 207))
  (segment (start 76.9275 105.8725) (end 76.9275 107.597186) (width 0.109) (layer "In2.Cu") (net 207))
  (segment (start 80.51654 126.862831) (end 80.5542 126.871427) (width 0.109) (layer "In2.Cu") (net 207))
  (segment (start 82.289875 128.568475) (end 82.327535 128.559879) (width 0.109) (layer "In2.Cu") (net 207))
  (segment (start 90.497186 131.4225) (end 90.73 131.189686) (width 0.109) (layer "In2.Cu") (net 207))
  (segment (start 77.2275 110.527814) (end 76.9275 110.827814) (width 0.109) (layer "In2.Cu") (net 207))
  (segment (start 80.640155 126.38942) (end 80.451538 126.578036) (width 0.109) (layer "In2.Cu") (net 207))
  (segment (start 86.270645 131.037349) (end 86.270645 131.070938) (width 0.109) (layer "In2.Cu") (net 207))
  (segment (start 82.973026 129.153809) (end 82.956266 129.188611) (width 0.109) (layer "In2.Cu") (net 207))
  (segment (start 84.650127 128.724758) (end 84.689263 128.806024) (width 0.109) (layer "In2.Cu") (net 207))
  (segment (start 83.840738 128.22357) (end 83.801602 128.304836) (width 0.109) (layer "In2.Cu") (net 207))
  (segment (start 76.930859 105.366317) (end 76.94077 105.39464) (width 0.109) (layer "In2.Cu") (net 207))
  (segment (start 90.73 130.770499) (end 91.1715 130.328999) (width 0.109) (layer "In2.Cu") (net 207))
  (segment (start 77.270255 105.66264) (end 77.254291 105.688047) (width 0.109) (layer "In2.Cu") (net 207))
  (segment (start 77.031682 105.741859) (end 77.003359 105.75177) (width 0.109) (layer "In2.Cu") (net 207))
  (segment (start 82.710122 126.826883) (end 82.791388 126.866019) (width 0.109) (layer "In2.Cu") (net 207))
  (segment (start 82.327535 128.559879) (end 82.362337 128.54312) (width 0.109) (layer "In2.Cu") (net 207))
  (segment (start 80.227657 125.089501) (end 80.241618 125.107009) (width 0.109) (layer "In2.Cu") (net 207))
  (segment (start 81.443741 126.073732) (end 81.514262 126.017496) (width 0.109) (layer "In2.Cu") (net 207))
  (segment (start 84.1411 128.523932) (end 84.229035 128.50386) (width 0.109) (layer "In2.Cu") (net 207))
  (segment (start 86.263171 131.004602) (end 86.270645 131.037349) (width 0.109) (layer "In2.Cu") (net 207))
  (segment (start 80.035824 125.100449) (end 80.055999 125.090733) (width 0.109) (layer "In2.Cu") (net 207))
  (segment (start 77.0615 105.4705) (end 77.149526 105.4705) (width 0.109) (layer "In2.Cu") (net 207))
  (segment (start 79.991599 125.105432) (end 80.013992 125.105432) (width 0.109) (layer "In2.Cu") (net 207))
  (segment (start 77.0615 105.7385) (end 77.031682 105.741859) (width 0.109) (layer "In2.Cu") (net 207))
  (segment (start 79.969768 125.100449) (end 79.991599 125.105432) (width 0.109) (layer "In2.Cu") (net 207))
  (segment (start 80.198996 125.31283) (end 80.203979 125.334662) (width 0.109) (layer "In2.Cu") (net 207))
  (segment (start 82.622185 126.806812) (end 82.710122 126.826883) (width 0.109) (layer "In2.Cu") (net 207))
  (segment (start 81.250623 127.56785) (end 81.259218 127.605509) (width 0.109) (layer "In2.Cu") (net 207))
  (segment (start 77.207666 105.48377) (end 77.233073 105.499734) (width 0.109) (layer "In2.Cu") (net 207))
  (segment (start 85.859914 130.983593) (end 85.892661 130.991067) (width 0.109) (layer "In2.Cu") (net 207))
  (segment (start 83.140789 127.77078) (end 83.21131 127.714544) (width 0.109) (layer "In2.Cu") (net 207))
  (segment (start 86.248597 131.133948) (end 86.206712 131.186472) (width 0.109) (layer "In2.Cu") (net 207))
  (segment (start 83.241061 129.36756) (end 83.989313 128.619304) (width 0.109) (layer "In2.Cu") (net 207))
  (segment (start 80.155414 125.048112) (end 80.177246 125.053095) (width 0.109) (layer "In2.Cu") (net 207))
  (segment (start 80.5542 126.871427) (end 80.592827 126.871427) (width 0.109) (layer "In2.Cu") (net 207))
  (segment (start 80.752995 126.220167) (end 80.713859 126.301433) (width 0.109) (layer "In2.Cu") (net 207))
  (segment (start 76.977952 105.767734) (end 76.956734 105.788952) (width 0.109) (layer "In2.Cu") (net 207))
  (segment (start 82.124502 128.305285) (end 82.107742 128.340087) (width 0.109) (layer "In2.Cu") (net 207))
  (segment (start 84.434432 129.573004) (end 84.458516 129.603204) (width 0.109) (layer "In2.Cu") (net 207))
  (segment (start 76.956734 105.788952) (end 76.94077 105.814359) (width 0.109) (layer "In2.Cu") (net 207))
  (segment (start 80.427454 126.608236) (end 80.410694 126.643039) (width 0.109) (layer "In2.Cu") (net 207))
  (segment (start 85.892661 130.991067) (end 85.92625 130.991067) (width 0.109) (layer "In2.Cu") (net 207))
  (segment (start 77.233073 105.499734) (end 77.254291 105.520952) (width 0.109) (layer "In2.Cu") (net 207))
  (segment (start 80.402099 126.680698) (end 80.402099 126.719326) (width 0.109) (layer "In2.Cu") (net 207))
  (segment (start 80.203979 125.268606) (end 80.198996 125.290437) (width 0.109) (layer "In2.Cu") (net 207))
  (segment (start 76.94077 105.39464) (end 76.956734 105.420047) (width 0.109) (layer "In2.Cu") (net 207))
  (segment (start 81.683463 125.958288) (end 81.773661 125.958288) (width 0.109) (layer "In2.Cu") (net 207))
  (segment (start 82.953078 127.456312) (end 82.896842 127.526833) (width 0.109) (layer "In2.Cu") (net 207))
  (segment (start 84.229035 128.50386) (end 84.319233 128.50386) (width 0.109) (layer "In2.Cu") (net 207))
  (segment (start 82.791388 126.866019) (end 82.861907 126.922256) (width 0.109) (layer "In2.Cu") (net 207))
  (segment (start 83.099772 129.416999) (end 83.138399 129.416999) (width 0.109) (layer "In2.Cu") (net 207))
  (segment (start 82.956266 129.188611) (end 82.947671 129.22627) (width 0.109) (layer "In2.Cu") (net 207))
  (segment (start 86.206712 131.346081) (end 86.227655 131.372343) (width 0.109) (layer "In2.Cu") (net 207))
  (segment (start 80.713859 126.301433) (end 80.657622 126.371952) (width 0.109) (layer "In2.Cu") (net 207))
  (segment (start 85.80339 130.948078) (end 85.829651 130.969019) (width 0.109) (layer "In2.Cu") (net 207))
  (segment (start 80.197421 125.062811) (end 80.214929 125.076773) (width 0.109) (layer "In2.Cu") (net 207))
  (segment (start 81.595528 125.97836) (end 81.683463 125.958288) (width 0.109) (layer "In2.Cu") (net 207))
  (segment (start 77.280166 105.634317) (end 77.270255 105.66264) (width 0.109) (layer "In2.Cu") (net 207))
  (segment (start 78.35 104.694533) (end 78.35 104.694532) (width 0.109) (layer "In2.Cu") (net 207))
  (segment (start 77.149526 105.4705) (end 77.179343 105.473859) (width 0.109) (layer "In2.Cu") (net 207))
  (segment (start 79.949593 125.090733) (end 79.969768 125.100449) (width 0.109) (layer "In2.Cu") (net 207))
  (segment (start 81.513813 127.694596) (end 81.544013 127.670512) (width 0.109) (layer "In2.Cu") (net 207))
  (segment (start 84.709334 128.893961) (end 84.709334 128.984159) (width 0.109) (layer "In2.Cu") (net 207))
  (segment (start 80.713859 125.87283) (end 80.752995 125.954096) (width 0.109) (layer "In2.Cu") (net 207))
  (segment (start 86.201393 130.927134) (end 86.227655 130.948077) (width 0.109) (layer "In2.Cu") (net 207))
  (segment (start 83.292576 127.675408) (end 83.380511 127.655336) (width 0.109) (layer "In2.Cu") (net 207))
  (segment (start 80.410694 126.643039) (end 80.402099 126.680698) (width 0.109) (layer "In2.Cu") (net 207))
  (segment (start 83.801603 127.876234) (end 83.840739 127.9575) (width 0.109) (layer "In2.Cu") (net 207))
  (segment (start 80.177246 125.053095) (end 80.197421 125.062811) (width 0.109) (layer "In2.Cu") (net 207))
  (segment (start 78.1795 104.524032) (end 77.406282 104.524032) (width 0.109) (layer "In2.Cu") (net 207))
  (segment (start 85.98926 130.969019) (end 86.041784 130.927134) (width 0.109) (layer "In2.Cu") (net 207))
  (segment (start 77.2275 107.897186) (end 77.2275 110.527814) (width 0.109) (layer "In2.Cu") (net 207))
  (segment (start 81.330262 127.694596) (end 81.365064 127.711355) (width 0.109) (layer "In2.Cu") (net 207))
  (segment (start 76.94077 105.814359) (end 76.930859 105.842682) (width 0.109) (layer "In2.Cu") (net 207))
  (segment (start 82.124502 128.488836) (end 82.148586 128.519036) (width 0.109) (layer "In2.Cu") (net 207))
  (segment (start 82.879375 127.5443) (end 82.148586 128.275084) (width 0.109) (layer "In2.Cu") (net 207))
  (segment (start 80.665289 126.846072) (end 80.695489 126.821988) (width 0.109) (layer "In2.Cu") (net 207))
  (segment (start 85.958997 130.983593) (end 85.98926 130.969019) (width 0.109) (layer "In2.Cu") (net 207))
  (segment (start 77.283526 105.6045) (end 77.280166 105.634317) (width 0.109) (layer "In2.Cu") (net 207))
  (segment (start 81.861598 125.978359) (end 81.942864 126.017495) (width 0.109) (layer "In2.Cu") (net 207))
  (segment (start 82.104554 126.607788) (end 82.048318 126.678309) (width 0.109) (layer "In2.Cu") (net 207))
  (segment (start 76.9275 116.397186) (end 79.6275 119.097186) (width 0.109) (layer "In2.Cu") (net 207))
  (segment (start 76.9275 105.002814) (end 76.9275 105.3365) (width 0.109) (layer "In2.Cu") (net 207))
  (segment (start 82.953079 127.02771) (end 82.992215 127.108976) (width 0.109) (layer "In2.Cu") (net 207))
  (segment (start 84.576423 129.241348) (end 84.458516 129.359252) (width 0.109) (layer "In2.Cu") (net 207))
  (segment (start 83.86081 128.045437) (end 83.86081 128.135635) (width 0.109) (layer "In2.Cu") (net 207))
  (segment (start 82.896842 126.957191) (end 82.953079 127.02771) (width 0.109) (layer "In2.Cu") (net 207))
  (segment (start 81.514262 126.017496) (end 81.595528 125.97836) (width 0.109) (layer "In2.Cu") (net 207))
  (segment (start 82.956266 129.302557) (end 82.973026 129.33736) (width 0.109) (layer "In2.Cu") (net 207))
  (segment (start 82.013383 126.073732) (end 82.048318 126.108667) (width 0.109) (layer "In2.Cu") (net 207))
  (segment (start 79.6275 124.772187) (end 79.932085 125.076771) (width 0.109) (layer "In2.Cu") (net 207))
  (segment (start 84.689262 129.072094) (end 84.650126 129.15336) (width 0.109) (layer "In2.Cu") (net 207))
  (segment (start 84.40717 128.523931) (end 84.488436 128.563067) (width 0.109) (layer "In2.Cu") (net 207))
  (segment (start 80.451538 126.821988) (end 80.481738 126.846072) (width 0.109) (layer "In2.Cu") (net 207))
  (segment (start 84.059834 128.563068) (end 84.1411 128.523932) (width 0.109) (layer "In2.Cu") (net 207))
  (segment (start 81.250623 127.529222) (end 81.250623 127.56785) (width 0.109) (layer "In2.Cu") (net 207))
  (segment (start 85.92625 130.991067) (end 85.958997 130.983593) (width 0.109) (layer "In2.Cu") (net 207))
  (segment (start 82.947671 129.22627) (end 82.947671 129.264898) (width 0.109) (layer "In2.Cu") (net 207))
  (segment (start 83.02731 129.391644) (end 83.062112 129.408403) (width 0.109) (layer "In2.Cu") (net 207))
  (segment (start 80.251334 125.19324) (end 80.241618 125.213415) (width 0.109) (layer "In2.Cu") (net 207))
  (segment (start 82.099147 128.416374) (end 82.107742 128.454033) (width 0.109) (layer "In2.Cu") (net 207))
  (segment (start 83.138399 129.416999) (end 83.176059 129.408403) (width 0.109) (layer "In2.Cu") (net 207))
  (segment (start 77.179343 105.73514) (end 77.149526 105.7385) (width 0.109) (layer "In2.Cu") (net 207))
  (segment (start 86.104794 130.905086) (end 86.138383 130.905086) (width 0.109) (layer "In2.Cu") (net 207))
  (segment (start 81.259218 127.491563) (end 81.250623 127.529222) (width 0.109) (layer "In2.Cu") (net 207))
  (segment (start 77.406282 104.524032) (end 76.9275 105.002814) (width 0.109) (layer "In2.Cu") (net 207))
  (segment (start 80.241618 125.107009) (end 80.251334 125.127184) (width 0.109) (layer "In2.Cu") (net 207))
  (segment (start 81.402724 127.719951) (end 81.441351 127.719951) (width 0.109) (layer "In2.Cu") (net 207))
  (segment (start 86.17113 130.91256) (end 86.201393 130.927134) (width 0.109) (layer "In2.Cu") (net 207))
  (segment (start 84.458516 129.603204) (end 85.80339 130.948078) (width 0.109) (layer "In2.Cu") (net 207))
  (segment (start 86.227655 131.372343) (end 86.277813 131.4225) (width 0.109) (layer "In2.Cu") (net 207))
  (segment (start 79.6275 119.097186) (end 79.6275 124.772187) (width 0.109) (layer "In2.Cu") (net 207))
  (segment (start 83.801602 128.304836) (end 83.745366 128.375357) (width 0.109) (layer "In2.Cu") (net 207))
  (segment (start 83.062112 129.408403) (end 83.099772 129.416999) (width 0.109) (layer "In2.Cu") (net 207))
  (segment (start 83.745366 128.375357) (end 83.727899 128.392824) (width 0.109) (layer "In2.Cu") (net 207))
  (segment (start 84.417673 129.424256) (end 84.409076 129.461914) (width 0.109) (layer "In2.Cu") (net 207))
  (segment (start 84.417673 129.538202) (end 84.434432 129.573004) (width 0.109) (layer "In2.Cu") (net 207))
  (segment (start 76.9275 105.3365) (end 76.930859 105.366317) (width 0.109) (layer "In2.Cu") (net 207))
  (segment (start 86.184664 131.283071) (end 86.192138 131.315818) (width 0.109) (layer "In2.Cu") (net 207))
  (segment (start 86.184664 131.249482) (end 86.184664 131.283071) (width 0.109) (layer "In2.Cu") (net 207))
  (segment (start 80.11119 125.053095) (end 80.133021 125.048112) (width 0.109) (layer "In2.Cu") (net 207))
  (segment (start 84.59389 128.654239) (end 84.650127 128.724758) (width 0.109) (layer "In2.Cu") (net 207))
  (segment (start 82.14369 126.526522) (end 82.104554 126.607788) (width 0.109) (layer "In2.Cu") (net 207))
  (segment (start 80.241618 125.213415) (end 80.213695 125.248431) (width 0.109) (layer "In2.Cu") (net 207))
  (segment (start 81.544013 127.670512) (end 82.292265 126.922256) (width 0.109) (layer "In2.Cu") (net 207))
  (segment (start 83.012286 127.287111) (end 82.992214 127.375046) (width 0.109) (layer "In2.Cu") (net 207))
  (segment (start 80.402099 126.719326) (end 80.410694 126.756985) (width 0.109) (layer "In2.Cu") (net 207))
  (segment (start 81.365064 127.711355) (end 81.402724 127.719951) (width 0.109) (layer "In2.Cu") (net 207))
  (segment (start 80.214929 125.076773) (end 80.227657 125.089501) (width 0.109) (layer "In2.Cu") (net 207))
  (segment (start 84.59389 129.223881) (end 84.576423 129.241348) (width 0.109) (layer "In2.Cu") (net 207))
  (segment (start 80.198996 125.290437) (end 80.198996 125.31283) (width 0.109) (layer "In2.Cu") (net 207))
  (segment (start 76.930859 105.842682) (end 76.9275 105.8725) (width 0.109) (layer "In2.Cu") (net 207))
  (segment (start 86.192138 131.216735) (end 86.184664 131.249482) (width 0.109) (layer "In2.Cu") (net 207))
  (segment (start 82.213588 128.559879) (end 82.251248 128.568475) (width 0.109) (layer "In2.Cu") (net 207))
  (segment (start 82.292265 126.922256) (end 82.362786 126.86602) (width 0.109) (layer "In2.Cu") (net 207))
  (segment (start 82.143691 126.260452) (end 82.163762 126.348389) (width 0.109) (layer "In2.Cu") (net 207))
  (segment (start 84.434433 129.389454) (end 84.417673 129.424256) (width 0.109) (layer "In2.Cu") (net 207))
  (segment (start 82.362337 128.54312) (end 82.392537 128.519036) (width 0.109) (layer "In2.Cu") (net 207))
  (segment (start 76.956734 105.420047) (end 76.977952 105.441265) (width 0.109) (layer "In2.Cu") (net 207))
  (segment (start 81.275978 127.640312) (end 81.300062 127.670512) (width 0.109) (layer "In2.Cu") (net 207))
  (segment (start 80.773066 126.042033) (end 80.773066 126.132231) (width 0.109) (layer "In2.Cu") (net 207))
  (segment (start 81.441351 127.719951) (end 81.479011 127.711355) (width 0.109) (layer "In2.Cu") (net 207))
  (segment (start 86.072047 130.91256) (end 86.104794 130.905086) (width 0.109) (layer "In2.Cu") (net 207))
  (segment (start 82.973026 129.33736) (end 82.99711 129.36756) (width 0.109) (layer "In2.Cu") (net 207))
  (segment (start 82.531987 126.806812) (end 82.622185 126.806812) (width 0.109) (layer "In2.Cu") (net 207))
  (segment (start 82.251248 128.568475) (end 82.289875 128.568475) (width 0.109) (layer "In2.Cu") (net 207))
  (segment (start 83.470709 127.655336) (end 83.558646 127.675407) (width 0.109) (layer "In2.Cu") (net 207))
  (segment (start 80.410694 126.756985) (end 80.427454 126.791787) (width 0.109) (layer "In2.Cu") (net 207))
  (segment (start 83.840739 127.9575) (end 83.86081 128.045437) (width 0.109) (layer "In2.Cu") (net 207))
  (segment (start 81.259218 127.605509) (end 81.275978 127.640312) (width 0.109) (layer "In2.Cu") (net 207))
  (segment (start 81.300062 127.670512) (end 81.330262 127.694596) (width 0.109) (layer "In2.Cu") (net 207))
  (segment (start 77.031682 105.46714) (end 77.0615 105.4705) (width 0.109) (layer "In2.Cu") (net 207))
  (segment (start 80.695489 126.821988) (end 81.443741 126.073732) (width 0.109) (layer "In2.Cu") (net 207))
  (segment (start 90.73 131.189686) (end 90.73 130.770499) (width 0.109) (layer "In2.Cu") (net 207))
  (segment (start 83.21131 127.714544) (end 83.292576 127.675408) (width 0.109) (layer "In2.Cu") (net 207))
  (segment (start 84.409076 129.461914) (end 84.409076 129.500542) (width 0.109) (layer "In2.Cu") (net 207))
  (segment (start 84.488436 128.563067) (end 84.558955 128.619304) (width 0.109) (layer "In2.Cu") (net 207))
  (segment (start 80.773066 126.132231) (end 80.752995 126.220167) (width 0.109) (layer "In2.Cu") (net 207))
  (segment (start 80.251334 125.127184) (end 80.256317 125.149015) (width 0.109) (layer "In2.Cu") (net 207))
  (segment (start 83.86081 128.135635) (end 83.840738 128.22357) (width 0.109) (layer "In2.Cu") (net 207))
  (segment (start 83.380511 127.655336) (end 83.470709 127.655336) (width 0.109) (layer "In2.Cu") (net 207))
  (segment (start 84.458516 129.359252) (end 84.434433 129.389454) (width 0.109) (layer "In2.Cu") (net 207))
  (segment (start 81.275978 127.456761) (end 81.259218 127.491563) (width 0.109) (layer "In2.Cu") (net 207))
  (segment (start 83.558646 127.675407) (end 83.639912 127.714543) (width 0.109) (layer "In2.Cu") (net 207))
  (segment (start 77.254291 105.688047) (end 77.233073 105.709265) (width 0.109) (layer "In2.Cu") (net 207))
  (segment (start 83.745366 127.805715) (end 83.801603 127.876234) (width 0.109) (layer "In2.Cu") (net 207))
  (segment (start 86.138383 130.905086) (end 86.17113 130.91256) (width 0.109) (layer "In2.Cu") (net 207))
  (segment (start 82.107742 128.454033) (end 82.124502 128.488836) (width 0.109) (layer "In2.Cu") (net 207))
  (segment (start 86.270645 131.070938) (end 86.263171 131.103685) (width 0.109) (layer "In2.Cu") (net 207))
  (segment (start 77.254291 105.520952) (end 77.270255 105.546359) (width 0.109) (layer "In2.Cu") (net 207))
  (segment (start 82.896842 127.526833) (end 82.879375 127.5443) (width 0.109) (layer "In2.Cu") (net 207))
  (segment (start 86.206712 131.186472) (end 86.192138 131.216735) (width 0.109) (layer "In2.Cu") (net 207))
  (segment (start 84.650126 129.15336) (end 84.59389 129.223881) (width 0.109) (layer "In2.Cu") (net 207))
  (segment (start 82.992215 127.108976) (end 83.012286 127.196913) (width 0.109) (layer "In2.Cu") (net 207))
  (segment (start 81.300062 127.42656) (end 81.275978 127.456761) (width 0.109) (layer "In2.Cu") (net 207))
  (segment (start 82.030851 126.695776) (end 81.300062 127.42656) (width 0.109) (layer "In2.Cu") (net 207))
  (segment (start 81.773661 125.958288) (end 81.861598 125.978359) (width 0.109) (layer "In2.Cu") (net 207))
  (segment (start 81.942864 126.017495) (end 82.013383 126.073732) (width 0.109) (layer "In2.Cu") (net 207))
  (segment (start 82.861907 126.922256) (end 82.896842 126.957191) (width 0.109) (layer "In2.Cu") (net 207))
  (segment (start 82.048318 126.108667) (end 82.104555 126.179186) (width 0.109) (layer "In2.Cu") (net 207))
  (segment (start 80.256317 125.149015) (end 80.256317 125.171408) (width 0.109) (layer "In2.Cu") (net 207))
  (segment (start 82.178786 128.54312) (end 82.213588 128.559879) (width 0.109) (layer "In2.Cu") (net 207))
  (segment (start 80.213695 125.248431) (end 80.203979 125.268606) (width 0.109) (layer "In2.Cu") (net 207))
  (segment (start 80.657622 126.371952) (end 80.640155 126.38942) (width 0.109) (layer "In2.Cu") (net 207))
  (segment (start 76.9275 107.597186) (end 77.2275 107.897186) (width 0.109) (layer "In2.Cu") (net 207))
  (segment (start 80.213695 125.354837) (end 80.227657 125.372345) (width 0.109) (layer "In2.Cu") (net 207))
  (segment (start 80.055999 125.090733) (end 80.091015 125.062811) (width 0.109) (layer "In2.Cu") (net 207))
  (segment (start 77.149526 105.7385) (end 77.0615 105.7385) (width 0.109) (layer "In2.Cu") (net 207))
  (segment (start 86.277813 131.4225) (end 90.497186 131.4225) (width 0.109) (layer "In2.Cu") (net 207))
  (segment (start 82.99711 129.123608) (end 82.973026 129.153809) (width 0.109) (layer "In2.Cu") (net 207))
  (segment (start 76.977952 105.441265) (end 77.003359 105.457229) (width 0.109) (layer "In2.Cu") (net 207))
  (segment (start 80.227657 125.372345) (end 80.657622 125.802311) (width 0.109) (layer "In2.Cu") (net 207))
  (segment (start 83.710431 127.77078) (end 83.745366 127.805715) (width 0.109) (layer "In2.Cu") (net 207))
  (segment (start 82.392537 128.519036) (end 83.140789 127.77078) (width 0.109) (layer "In2.Cu") (net 207))
  (segment (start 77.270255 105.546359) (end 77.280166 105.574682) (width 0.109) (layer "In2.Cu") (net 207))
  (segment (start 80.013992 125.105432) (end 80.035824 125.100449) (width 0.109) (layer "In2.Cu") (net 207))
  (segment (start 80.091015 125.062811) (end 80.11119 125.053095) (width 0.109) (layer "In2.Cu") (net 207))
  (segment (start 84.709334 128.984159) (end 84.689262 129.072094) (width 0.109) (layer "In2.Cu") (net 207))
  (segment (start 82.104555 126.179186) (end 82.143691 126.260452) (width 0.109) (layer "In2.Cu") (net 207))
  (segment (start 82.163762 126.348389) (end 82.163762 126.438587) (width 0.109) (layer "In2.Cu") (net 207))
  (segment (start 84.689263 128.806024) (end 84.709334 128.893961) (width 0.109) (layer "In2.Cu") (net 207))
  (segment (start 77.280166 105.574682) (end 77.283526 105.6045) (width 0.109) (layer "In2.Cu") (net 207))
  (segment (start 77.207666 105.725229) (end 77.179343 105.73514) (width 0.109) (layer "In2.Cu") (net 207))
  (segment (start 80.630487 126.862831) (end 80.665289 126.846072) (width 0.109) (layer "In2.Cu") (net 207))
  (segment (start 80.427454 126.791787) (end 80.451538 126.821988) (width 0.109) (layer "In2.Cu") (net 207))
  (segment (start 81.479011 127.711355) (end 81.513813 127.694596) (width 0.109) (layer "In2.Cu") (net 207))
  (segment (start 83.989313 128.619304) (end 84.059834 128.563068) (width 0.109) (layer "In2.Cu") (net 207))
  (segment (start 80.256317 125.171408) (end 80.251334 125.19324) (width 0.109) (layer "In2.Cu") (net 207))
  (segment (start 84.319233 128.50386) (end 84.40717 128.523931) (width 0.109) (layer "In2.Cu") (net 207))
  (segment (start 86.263171 131.103685) (end 86.248597 131.133948) (width 0.109) (layer "In2.Cu") (net 207))
  (segment (start 80.657622 125.802311) (end 80.713859 125.87283) (width 0.109) (layer "In2.Cu") (net 207))
  (segment (start 79.932085 125.076771) (end 79.949593 125.090733) (width 0.109) (layer "In2.Cu") (net 207))
  (segment (start 86.041784 130.927134) (end 86.072047 130.91256) (width 0.109) (layer "In2.Cu") (net 207))
  (segment (start 80.203979 125.334662) (end 80.213695 125.354837) (width 0.109) (layer "In2.Cu") (net 207))
  (segment (start 86.248597 130.974339) (end 86.263171 131.004602) (width 0.109) (layer "In2.Cu") (net 207))
  (segment (start 80.592827 126.871427) (end 80.630487 126.862831) (width 0.109) (layer "In2.Cu") (net 207))
  (segment (start 82.148586 128.519036) (end 82.178786 128.54312) (width 0.109) (layer "In2.Cu") (net 207))
  (segment (start 83.639912 127.714543) (end 83.710431 127.77078) (width 0.109) (layer "In2.Cu") (net 207))
  (segment (start 83.210861 129.391644) (end 83.241061 129.36756) (width 0.109) (layer "In2.Cu") (net 207))
  (segment (start 83.176059 129.408403) (end 83.210861 129.391644) (width 0.109) (layer "In2.Cu") (net 207))
  (segment (start 77.003359 105.75177) (end 76.977952 105.767734) (width 0.109) (layer "In2.Cu") (net 207))
  (segment (start 82.099147 128.377746) (end 82.099147 128.416374) (width 0.109) (layer "In2.Cu") (net 207))
  (segment (start 85.829651 130.969019) (end 85.859914 130.983593) (width 0.109) (layer "In2.Cu") (net 207))
  (segment (start 84.558955 128.619304) (end 84.59389 128.654239) (width 0.109) (layer "In2.Cu") (net 207))
  (segment (start 80.752995 125.954096) (end 80.773066 126.042033) (width 0.109) (layer "In2.Cu") (net 207))
  (segment (start 82.048318 126.678309) (end 82.030851 126.695776) (width 0.109) (layer "In2.Cu") (net 207))
  (segment (start 77.179343 105.473859) (end 77.207666 105.48377) (width 0.109) (layer "In2.Cu") (net 207))
  (segment (start 83.012286 127.196913) (end 83.012286 127.287111) (width 0.109) (layer "In2.Cu") (net 207))
  (segment (start 77.233073 105.709265) (end 77.207666 105.725229) (width 0.109) (layer "In2.Cu") (net 207))
  (segment (start 86.192138 131.315818) (end 86.206712 131.346081) (width 0.109) (layer "In2.Cu") (net 207))
  (segment (start 77.003359 105.457229) (end 77.031682 105.46714) (width 0.109) (layer "In2.Cu") (net 207))
  (segment (start 86.227655 130.948077) (end 86.248597 130.974339) (width 0.109) (layer "In2.Cu") (net 207))
  (segment (start 82.444052 126.826884) (end 82.531987 126.806812) (width 0.109) (layer "In2.Cu") (net 207))
  (segment (start 76.9275 110.827814) (end 76.9275 116.397186) (width 0.109) (layer "In2.Cu") (net 207))
  (segment (start 78.35 104.694532) (end 78.1795 104.524032) (width 0.109) (layer "In2.Cu") (net 207))
  (segment (start 82.148586 128.275084) (end 82.124502 128.305285) (width 0.109) (layer "In2.Cu") (net 207))
  (segment (start 82.99711 129.36756) (end 83.02731 129.391644) (width 0.109) (layer "In2.Cu") (net 207))
  (segment (start 80.133021 125.048112) (end 80.155414 125.048112) (width 0.109) (layer "In2.Cu") (net 207))
  (segment (start 82.947671 129.264898) (end 82.956266 129.302557) (width 0.109) (layer "In2.Cu") (net 207))
  (segment (start 80.938999 104.189) (end 80.999999 104.25) (width 0.182) (layer "B.Cu") (net 207))
  (segment (start 80.999999 104.25) (end 81.9 104.25) (width 0.182) (layer "B.Cu") (net 207))
  (segment (start 80.381756 104.585532) (end 80.778288 104.189) (width 0.182) (layer "B.Cu") (net 207))
  (segment (start 80.381756 104.585532) (end 78.459 104.585532) (width 0.182) (layer "B.Cu") (net 207))
  (segment (start 78.35 104.694532) (end 78.35 104.694533) (width 0.182) (layer "B.Cu") (net 207))
  (segment (start 78.459 104.585532) (end 78.35 104.694532) (width 0.182) (layer "B.Cu") (net 207))
  (segment (start 80.778288 104.189) (end 80.938999 104.189) (width 0.182) (layer "B.Cu") (net 207))
  (segment (start 89.4415 130.949) (end 89.8265 130.639) (width 0.182) (layer "F.Cu") (net 208))
  (via (at 78.55 105.505467) (size 0.45) (drill 0.1) (layers "F.Cu" "B.Cu") (net 208))
  (via (at 89.4415 130.949) (size 0.45) (drill 0.1) (layers "F.Cu" "B.Cu") (net 208))
  (segment (start 80.893175 123.664427) (end 80.8975 123.702812) (width 0.109) (layer "In2.Cu") (net 208))
  (segment (start 79.750201 118.244558) (end 79.84328 118.265802) (width 0.109) (layer "In2.Cu") (net 208))
  (segment (start 80.106418 119.527514) (end 80.116516 119.617145) (width 0.109) (layer "In2.Cu") (net 208))
  (segment (start 81.590927 119.947394) (end 81.623634 119.967946) (width 0.109) (layer "In2.Cu") (net 208))
  (segment (start 80.106418 119.478109) (end 80.106418 119.527514) (width 0.109) (layer "In2.Cu") (net 208))
  (segment (start 80.116516 122.988478) (end 80.106418 123.078109) (width 0.109) (layer "In2.Cu") (net 208))
  (segment (start 79.273259 117.224373) (end 79.636316 116.861315) (width 0.109) (layer "In2.Cu") (net 208))
  (segment (start 81.554467 121.470987) (end 81.516082 121.475312) (width 0.109) (layer "In2.Cu") (net 208))
  (segment (start 81.590927 118.747394) (end 81.623634 118.767946) (width 0.109) (layer "In2.Cu") (net 208))
  (segment (start 80.334448 121.090422) (end 80.419584 121.120213) (width 0.109) (layer "In2.Cu") (net 208))
  (segment (start 81.688582 120.102812) (end 81.684258 120.141196) (width 0.109) (layer "In2.Cu") (net 208))
  (segment (start 81.600948 122.610363) (end 81.573634 122.637677) (width 0.109) (layer "In2.Cu") (net 208))
  (segment (start 80.146307 119.702281) (end 80.194295 119.778654) (width 0.109) (layer "In2.Cu") (net 208))
  (segment (start 80.509215 122.330312) (end 81.466082 122.330312) (width 0.109) (layer "In2.Cu") (net 208))
  (segment (start 80.509215 121.475312) (end 80.419584 121.48541) (width 0.109) (layer "In2.Cu") (net 208))
  (segment (start 79.266532 115.550747) (end 79.306379 115.569937) (width 0.109) (layer "In2.Cu") (net 208))
  (segment (start 80.509215 122.675312) (end 80.419584 122.68541) (width 0.109) (layer "In2.Cu") (net 208))
  (segment (start 79.387719 115.802395) (end 79.368529 115.84224) (width 0.109) (layer "In2.Cu") (net 208))
  (segment (start 78.354025 116.30514) (end 78.717082 115.942082) (width 0.109) (layer "In2.Cu") (net 208))
  (segment (start 79.84328 118.265802) (end 79.938753 118.265802) (width 0.109) (layer "In2.Cu") (net 208))
  (segment (start 81.623634 121.167946) (end 81.650948 121.19526) (width 0.109) (layer "In2.Cu") (net 208))
  (segment (start 81.688582 121.302812) (end 81.684258 121.341196) (width 0.109) (layer "In2.Cu") (net 208))
  (segment (start 81.516082 121.130312) (end 81.554467 121.134636) (width 0.109) (layer "In2.Cu") (net 208))
  (segment (start 80.194295 121.626969) (end 80.146307 121.703342) (width 0.109) (layer "In2.Cu") (net 208))
  (segment (start 80.194295 123.378654) (end 80.258075 123.442434) (width 0.109) (layer "In2.Cu") (net 208))
  (segment (start 80.880417 123.627967) (end 80.893175 123.664427) (width 0.109) (layer "In2.Cu") (net 208))
  (segment (start 80.146307 120.503342) (end 80.116516 120.588478) (width 0.109) (layer "In2.Cu") (net 208))
  (segment (start 80.116516 120.817145) (end 80.146307 120.902281) (width 0.109) (layer "In2.Cu") (net 208))
  (segment (start 81.516082 120.275312) (end 80.509215 120.275312) (width 0.109) (layer "In2.Cu") (net 208))
  (segment (start 79.061648 115.597511) (end 79.096225 115.569936) (width 0.109) (layer "In2.Cu") (net 208))
  (segment (start 77.874917 115.287232) (end 77.894106 115.327078) (width 0.109) (layer "In2.Cu") (net 208))
  (segment (start 81.650948 121.19526) (end 81.6715 121.227967) (width 0.109) (layer "In2.Cu") (net 208))
  (segment (start 80.015459 116.48917) (end 80.055306 116.469982) (width 0.109) (layer "In2.Cu") (net 208))
  (segment (start 79.198616 117.283899) (end 79.273259 117.224373) (width 0.109) (layer "In2.Cu") (net 208))
  (segment (start 81.623634 119.967946) (end 81.650948 119.99526) (width 0.109) (layer "In2.Cu") (net 208))
  (segment (start 79.980882 116.516745) (end 80.015459 116.48917) (width 0.109) (layer "In2.Cu") (net 208))
  (segment (start 79.39756 115.759278) (end 79.387719 115.802395) (width 0.109) (layer "In2.Cu") (net 208))
  (segment (start 78.279382 116.364666) (end 78.354025 116.30514) (width 0.109) (layer "In2.Cu") (net 208))
  (segment (start 81.650948 119.99526) (end 81.6715 120.027967) (width 0.109) (layer "In2.Cu") (net 208))
  (segment (start 81.516082 118.730312) (end 81.554467 118.734636) (width 0.109) (layer "In2.Cu") (net 208))
  (segment (start 79.664183 118.203133) (end 79.750201 118.244558) (width 0.109) (layer "In2.Cu") (net 208))
  (segment (start 80.258075 122.763189) (end 80.194295 122.826969) (width 0.109) (layer "In2.Cu") (net 208))
  (segment (start 80.419584 119.08541) (end 80.334448 119.115201) (width 0.109) (layer "In2.Cu") (net 208))
  (segment (start 80.419584 121.48541) (end 80.334448 121.515201) (width 0.109) (layer "In2.Cu") (net 208))
  (segment (start 77.911733 116.406091) (end 78.004812 116.427335) (width 0.109) (layer "In2.Cu") (net 208))
  (segment (start 80.487507 117.953754) (end 80.530624 117.963596) (width 0.109) (layer "In2.Cu") (net 208))
  (segment (start 79.39756 115.715052) (end 79.39756 115.759278) (width 0.109) (layer "In2.Cu") (net 208))
  (segment (start 80.142649 116.460141) (end 80.185766 116.469981) (width 0.109) (layer "In2.Cu") (net 208))
  (segment (start 77.9475 107.777814) (end 77.9475 110.622186) (width 0.109) (layer "In2.Cu") (net 208))
  (segment (start 79.019519 117.346568) (end 79.112598 117.325324) (width 0.109) (layer "In2.Cu") (net 208))
  (segment (start 77.3725 106.147186) (end 77.3725 107.202814) (width 0.109) (layer "In2.Cu") (net 208))
  (segment (start 78.100285 116.427335) (end 78.193364 116.406091) (width 0.109) (layer "In2.Cu") (net 208))
  (segment (start 80.57047 117.982785) (end 80.605047 118.010359) (width 0.109) (layer "In2.Cu") (net 208))
  (segment (start 89.2515 130.759) (end 89.4415 130.949) (width 0.109) (layer "In2.Cu") (net 208))
  (segment (start 81.600948 122.39526) (end 81.6215 122.427967) (width 0.109) (layer "In2.Cu") (net 208))
  (segment (start 80.419584 123.520213) (end 80.509215 123.530312) (width 0.109) (layer "In2.Cu") (net 208))
  (segment (start 81.650948 118.79526) (end 81.6715 118.827967) (width 0.109) (layer "In2.Cu") (net 208))
  (segment (start 80.258075 121.042434) (end 80.334448 121.090422) (width 0.109) (layer "In2.Cu") (net 208))
  (segment (start 77.613144 116.107501) (end 77.654568 116.193519) (width 0.109) (layer "In2.Cu") (net 208))
  (segment (start 80.098423 116.460141) (end 80.142649 116.460141) (width 0.109) (layer "In2.Cu") (net 208))
  (segment (start 80.031832 118.244558) (end 80.11785 118.203133) (width 0.109) (layer "In2.Cu") (net 208))
  (segment (start 80.258075 122.242434) (end 80.334448 122.290422) (width 0.109) (layer "In2.Cu") (net 208))
  (segment (start 80.605047 118.010359) (end 80.8975 118.302812) (width 0.109) (layer "In2.Cu") (net 208))
  (segment (start 80.194295 119.226969) (end 80.146307 119.303342) (width 0.109) (layer "In2.Cu") (net 208))
  (segment (start 79.493036 117.57832) (end 79.451612 117.664338) (width 0.109) (layer "In2.Cu") (net 208))
  (segment (start 80.258075 120.363189) (end 80.194295 120.426969) (width 0.109) (layer "In2.Cu") (net 208))
  (segment (start 80.8975 118.302812) (end 80.8975 118.327514) (width 0.109) (layer "In2.Cu") (net 208))
  (segment (start 79.451612 117.664338) (end 79.430368 117.757417) (width 0.109) (layer "In2.Cu") (net 208))
  (segment (start 78.717082 115.942082) (end 78.717082 115.942079) (width 0.109) (layer "In2.Cu") (net 208))
  (segment (start 77.591899 115.918949) (end 77.591899 116.014422) (width 0.109) (layer "In2.Cu") (net 208))
  (segment (start 79.938753 118.265802) (end 80.031832 118.244558) (width 0.109) (layer "In2.Cu") (net 208))
  (segment (start 80.32574 118.010359) (end 80.360317 117.982785) (width 0.109) (layer "In2.Cu") (net 208))
  (segment (start 81.125531 118.690422) (end 81.210667 118.720213) (width 0.109) (layer "In2.Cu") (net 208))
  (segment (start 81.684258 118.941196) (end 81.6715 118.977656) (width 0.109) (layer "In2.Cu") (net 208))
  (segment (start 80.334448 120.315201) (end 80.258075 120.363189) (width 0.109) (layer "In2.Cu") (net 208))
  (segment (start 81.6715 121.227967) (end 81.684258 121.264427) (width 0.109) (layer "In2.Cu") (net 208))
  (segment (start 80.146307 122.903342) (end 80.116516 122.988478) (width 0.109) (layer "In2.Cu") (net 208))
  (segment (start 80.799844 123.547394) (end 80.832551 123.567946) (width 0.109) (layer "In2.Cu") (net 208))
  (segment (start 78.511134 116.838183) (end 78.511134 116.933656) (width 0.109) (layer "In2.Cu") (net 208))
  (segment (start 81.590927 119.058229) (end 81.554467 119.070987) (width 0.109) (layer "In2.Cu") (net 208))
  (segment (start 80.146307 121.703342) (end 80.116516 121.788478) (width 0.109) (layer "In2.Cu") (net 208))
  (segment (start 80.530624 117.963596) (end 80.57047 117.982785) (width 0.109) (layer "In2.Cu") (net 208))
  (segment (start 80.146307 123.302281) (end 80.194295 123.378654) (width 0.109) (layer "In2.Cu") (net 208))
  (segment (start 80.106418 121.927514) (end 80.116516 122.017145) (width 0.109) (layer "In2.Cu") (net 208))
  (segment (start 78.670305 117.224373) (end 78.744949 117.283899) (width 0.109) (layer "In2.Cu") (net 208))
  (segment (start 77.825715 116.364666) (end 77.911733 116.406091) (width 0.109) (layer "In2.Cu") (net 208))
  (segment (start 78.830967 117.325324) (end 78.924046 117.346568) (width 0.109) (layer "In2.Cu") (net 208))
  (segment (start 79.340956 115.597512) (end 79.368529 115.632088) (width 0.109) (layer "In2.Cu") (net 208))
  (segment (start 80.334448 119.115201) (end 80.258075 119.163189) (width 0.109) (layer "In2.Cu") (net 208))
  (segment (start 81.504467 122.670987) (end 81.466082 122.675312) (width 0.109) (layer "In2.Cu") (net 208))
  (segment (start 81.623634 121.437677) (end 81.590927 121.458229) (width 0.109) (layer "In2.Cu") (net 208))
  (segment (start 80.419584 121.120213) (end 80.509215 121.130312) (width 0.109) (layer "In2.Cu") (net 208))
  (segment (start 81.623634 118.767946) (end 81.650948 118.79526) (width 0.109) (layer "In2.Cu") (net 208))
  (segment (start 80.725 123.530312) (end 80.763384 123.534636) (width 0.109) (layer "In2.Cu") (net 208))
  (segment (start 77.591899 116.014422) (end 77.613144 116.107501) (width 0.109) (layer "In2.Cu") (net 208))
  (segment (start 79.387719 115.671935) (end 79.39756 115.715052) (width 0.109) (layer "In2.Cu") (net 208))
  (segment (start 80.185766 116.469981) (end 80.225613 116.489171) (width 0.109) (layer "In2.Cu") (net 208))
  (segment (start 87.078686 130.759) (end 89.2515 130.759) (width 0.109) (layer "In2.Cu") (net 208))
  (segment (start 81.6715 121.377656) (end 81.650948 121.410363) (width 0.109) (layer "In2.Cu") (net 208))
  (segment (start 80.443281 117.953754) (end 80.487507 117.953754) (width 0.109) (layer "In2.Cu") (net 208))
  (segment (start 79.636316 116.861313) (end 79.980882 116.516745) (width 0.109) (layer "In2.Cu") (net 208))
  (segment (start 79.430368 117.757417) (end 79.430368 117.85289) (width 0.109) (layer "In2.Cu") (net 208))
  (segment (start 81.466082 122.675312) (end 80.509215 122.675312) (width 0.109) (layer "In2.Cu") (net 208))
  (segment (start 79.112598 117.325324) (end 79.198616 117.283899) (width 0.109) (layer "In2.Cu") (net 208))
  (segment (start 81.554467 119.070987) (end 81.516082 119.075312) (width 0.109) (layer "In2.Cu") (net 208))
  (segment (start 78.532378 116.745104) (end 78.511134 116.838183) (width 0.109) (layer "In2.Cu") (net 208))
  (segment (start 77.9475 110.622186) (end 77.4725 111.097186) (width 0.109) (layer "In2.Cu") (net 208))
  (segment (start 80.316794 116.678512) (end 80.306953 116.721629) (width 0.109) (layer "In2.Cu") (net 208))
  (segment (start 77.903947 115.414421) (end 77.894106 115.457538) (width 0.109) (layer "In2.Cu") (net 208))
  (segment (start 81.300298 118.730312) (end 81.516082 118.730312) (width 0.109) (layer "In2.Cu") (net 208))
  (segment (start 81.540927 122.658229) (end 81.504467 122.670987) (width 0.109) (layer "In2.Cu") (net 208))
  (segment (start 77.654568 116.193519) (end 77.714094 116.268163) (width 0.109) (layer "In2.Cu") (net 208))
  (segment (start 80.859865 123.59526) (end 80.880417 123.627967) (width 0.109) (layer "In2.Cu") (net 208))
  (segment (start 80.258075 121.563189) (end 80.194295 121.626969) (width 0.109) (layer "In2.Cu") (net 208))
  (segment (start 80.194295 120.426969) (end 80.146307 120.503342) (width 0.109) (layer "In2.Cu") (net 208))
  (segment (start 81.210667 118.720213) (end 81.300298 118.730312) (width 0.109) (layer "In2.Cu") (net 208))
  (segment (start 78.004812 116.427335) (end 78.100285 116.427335) (width 0.109) (layer "In2.Cu") (net 208))
  (segment (start 79.368529 115.84224) (end 79.340955 115.876819) (width 0.109) (layer "In2.Cu") (net 208))
  (segment (start 80.832551 123.567946) (end 80.859865 123.59526) (width 0.109) (layer "In2.Cu") (net 208))
  (segment (start 81.684258 120.141196) (end 81.6715 120.177656) (width 0.109) (layer "In2.Cu") (net 208))
  (segment (start 81.504467 122.334636) (end 81.540927 122.347394) (width 0.109) (layer "In2.Cu") (net 208))
  (segment (start 77.847342 115.531962) (end 77.714094 115.665209) (width 0.109) (layer "In2.Cu") (net 208))
  (segment (start 80.106418 120.678109) (end 80.106418 120.727514) (width 0.109) (layer "In2.Cu") (net 208))
  (segment (start 81.516082 119.075312) (end 80.509215 119.075312) (width 0.109) (layer "In2.Cu") (net 208))
  (segment (start 77.3725 107.202814) (end 77.9475 107.777814) (width 0.109) (layer "In2.Cu") (net 208))
  (segment (start 78.511134 116.933656) (end 78.532378 117.026735) (width 0.109) (layer "In2.Cu") (net 208))
  (segment (start 81.650948 121.410363) (end 81.623634 121.437677) (width 0.109) (layer "In2.Cu") (net 208))
  (segment (start 80.194295 120.978654) (end 80.258075 121.042434) (width 0.109) (layer "In2.Cu") (net 208))
  (segment (start 80.509215 120.275312) (end 80.419584 120.28541) (width 0.109) (layer "In2.Cu") (net 208))
  (segment (start 81.590927 121.458229) (end 81.554467 121.470987) (width 0.109) (layer "In2.Cu") (net 208))
  (segment (start 78.633329 116.584442) (end 78.573802 116.659086) (width 0.109) (layer "In2.Cu") (net 208))
  (segment (start 80.26019 116.516746) (end 80.287763 116.551322) (width 0.109) (layer "In2.Cu") (net 208))
  (segment (start 80.360317 117.982785) (end 80.400163 117.963596) (width 0.109) (layer "In2.Cu") (net 208))
  (segment (start 79.306379 115.569937) (end 79.340956 115.597512) (width 0.109) (layer "In2.Cu") (net 208))
  (segment (start 80.334448 123.490422) (end 80.419584 123.520213) (width 0.109) (layer "In2.Cu") (net 208))
  (segment (start 81.6715 120.177656) (end 81.650948 120.210363) (width 0.109) (layer "In2.Cu") (net 208))
  (segment (start 79.179189 115.540907) (end 79.223415 115.540907) (width 0.109) (layer "In2.Cu") (net 208))
  (segment (start 80.334448 122.715201) (end 80.258075 122.763189) (width 0.109) (layer "In2.Cu") (net 208))
  (segment (start 79.223415 115.540907) (end 79.266532 115.550747) (width 0.109) (layer "In2.Cu") (net 208))
  (segment (start 80.306953 116.721629) (end 80.287763 116.761474) (width 0.109) (layer "In2.Cu") (net 208))
  (segment (start 81.623634 119.037677) (end 81.590927 119.058229) (width 0.109) (layer "In2.Cu") (net 208))
  (segment (start 81.6215 122.577656) (end 81.600948 122.610363) (width 0.109) (layer "In2.Cu") (net 208))
  (segment (start 81.573634 122.637677) (end 81.540927 122.658229) (width 0.109) (layer "In2.Cu") (net 208))
  (segment (start 79.636316 116.861315) (end 79.636316 116.861313) (width 0.109) (layer "In2.Cu") (net 208))
  (segment (start 80.419584 119.920213) (end 80.509215 119.930312) (width 0.109) (layer "In2.Cu") (net 208))
  (segment (start 80.260189 116.796053) (end 79.552563 117.503676) (width 0.109) (layer "In2.Cu") (net 208))
  (segment (start 81.684258 120.064427) (end 81.688582 120.102812) (width 0.109) (layer "In2.Cu") (net 208))
  (segment (start 80.106418 120.727514) (end 80.116516 120.817145) (width 0.109) (layer "In2.Cu") (net 208))
  (segment (start 77.613144 115.82587) (end 77.591899 115.918949) (width 0.109) (layer "In2.Cu") (net 208))
  (segment (start 80.055306 116.469982) (end 80.098423 116.460141) (width 0.109) (layer "In2.Cu") (net 208))
  (segment (start 78.193364 116.406091) (end 78.279382 116.364666) (width 0.109) (layer "In2.Cu") (net 208))
  (segment (start 78.55 105.505467) (end 78.3795 105.675967) (width 0.109) (layer "In2.Cu") (net 208))
  (segment (start 81.554467 121.134636) (end 81.590927 121.147394) (width 0.109) (layer "In2.Cu") (net 208))
  (segment (start 80.116516 120.588478) (end 80.106418 120.678109) (width 0.109) (layer "In2.Cu") (net 208))
  (segment (start 80.106418 121.878109) (end 80.106418 121.927514) (width 0.109) (layer "In2.Cu") (net 208))
  (segment (start 80.225613 116.489171) (end 80.26019 116.516746) (width 0.109) (layer "In2.Cu") (net 208))
  (segment (start 81.590927 121.147394) (end 81.623634 121.167946) (width 0.109) (layer "In2.Cu") (net 208))
  (segment (start 77.714094 115.665209) (end 77.654568 115.739852) (width 0.109) (layer "In2.Cu") (net 208))
  (segment (start 78.573802 116.659086) (end 78.532378 116.745104) (width 0.109) (layer "In2.Cu") (net 208))
  (segment (start 81.049158 118.642434) (end 81.125531 118.690422) (width 0.109) (layer "In2.Cu") (net 208))
  (segment (start 80.400163 117.963596) (end 80.443281 117.953754) (width 0.109) (layer "In2.Cu") (net 208))
  (segment (start 78.744949 117.283899) (end 78.830967 117.325324) (width 0.109) (layer "In2.Cu") (net 208))
  (segment (start 79.368529 115.632088) (end 79.387719 115.671935) (width 0.109) (layer "In2.Cu") (net 208))
  (segment (start 80.146307 120.902281) (end 80.194295 120.978654) (width 0.109) (layer "In2.Cu") (net 208))
  (segment (start 81.540927 122.347394) (end 81.573634 122.367946) (width 0.109) (layer "In2.Cu") (net 208))
  (segment (start 80.146307 122.102281) (end 80.194295 122.178654) (width 0.109) (layer "In2.Cu") (net 208))
  (segment (start 80.93739 118.502281) (end 80.985378 118.578654) (width 0.109) (layer "In2.Cu") (net 208))
  (segment (start 80.116516 119.388478) (end 80.106418 119.478109) (width 0.109) (layer "In2.Cu") (net 208))
  (segment (start 81.554467 119.934636) (end 81.590927 119.947394) (width 0.109) (layer "In2.Cu") (net 208))
  (segment (start 80.194295 122.826969) (end 80.146307 122.903342) (width 0.109) (layer "In2.Cu") (net 208))
  (segment (start 80.116516 119.617145) (end 80.146307 119.702281) (width 0.109) (layer "In2.Cu") (net 208))
  (segment (start 77.714094 116.268163) (end 77.751071 116.30514) (width 0.109) (layer "In2.Cu") (net 208))
  (segment (start 79.589539 118.143607) (end 79.664183 118.203133) (width 0.109) (layer "In2.Cu") (net 208))
  (segment (start 80.334448 122.290422) (end 80.419584 122.320213) (width 0.109) (layer "In2.Cu") (net 208))
  (segment (start 81.684258 118.864427) (end 81.688582 118.902812) (width 0.109) (layer "In2.Cu") (net 208))
  (segment (start 80.106418 123.127514) (end 80.116516 123.217145) (width 0.109) (layer "In2.Cu") (net 208))
  (segment (start 81.554467 120.270987) (end 81.516082 120.275312) (width 0.109) (layer "In2.Cu") (net 208))
  (segment (start 80.146307 119.303342) (end 80.116516 119.388478) (width 0.109) (layer "In2.Cu") (net 208))
  (segment (start 77.903947 115.370195) (end 77.903947 115.414421) (width 0.109) (layer "In2.Cu") (net 208))
  (segment (start 80.106418 123.078109) (end 80.106418 123.127514) (width 0.109) (layer "In2.Cu") (net 208))
  (segment (start 78.633329 117.187397) (end 78.670305 117.224373) (width 0.109) (layer "In2.Cu") (net 208))
  (segment (start 80.194295 122.178654) (end 80.258075 122.242434) (width 0.109) (layer "In2.Cu") (net 208))
  (segment (start 80.985378 118.578654) (end 81.049158 118.642434) (width 0.109) (layer "In2.Cu") (net 208))
  (segment (start 78.717082 115.942079) (end 79.061648 115.597511) (width 0.109) (layer "In2.Cu") (net 208))
  (segment (start 80.116516 122.017145) (end 80.146307 122.102281) (width 0.109) (layer "In2.Cu") (net 208))
  (segment (start 78.3795 105.675967) (end 77.843719 105.675967) (width 0.109) (layer "In2.Cu") (net 208))
  (segment (start 81.634258 122.541196) (end 81.6215 122.577656) (width 0.109) (layer "In2.Cu") (net 208))
  (segment (start 81.6715 118.977656) (end 81.650948 119.010363) (width 0.109) (layer "In2.Cu") (net 208))
  (segment (start 79.552563 118.106631) (end 79.589539 118.143607) (width 0.109) (layer "In2.Cu") (net 208))
  (segment (start 81.638582 122.502812) (end 81.634258 122.541196) (width 0.109) (layer "In2.Cu") (net 208))
  (segment (start 81.684258 121.264427) (end 81.688582 121.302812) (width 0.109) (layer "In2.Cu") (net 208))
  (segment (start 81.516082 119.930312) (end 81.554467 119.934636) (width 0.109) (layer "In2.Cu") (net 208))
  (segment (start 79.493036 118.031987) (end 79.552563 118.106631) (width 0.109) (layer "In2.Cu") (net 208))
  (segment (start 78.924046 117.346568) (end 79.019519 117.346568) (width 0.109) (layer "In2.Cu") (net 208))
  (segment (start 77.4725 114.877813) (end 77.847342 115.252655) (width 0.109) (layer "In2.Cu") (net 208))
  (segment (start 81.684258 121.341196) (end 81.6715 121.377656) (width 0.109) (layer "In2.Cu") (net 208))
  (segment (start 81.650948 119.010363) (end 81.623634 119.037677) (width 0.109) (layer "In2.Cu") (net 208))
  (segment (start 80.258075 119.163189) (end 80.194295 119.226969) (width 0.109) (layer "In2.Cu") (net 208))
  (segment (start 80.306953 116.591169) (end 80.316794 116.634286) (width 0.109) (layer "In2.Cu") (net 208))
  (segment (start 81.6715 118.827967) (end 81.684258 118.864427) (width 0.109) (layer "In2.Cu") (net 208))
  (segment (start 80.419584 120.28541) (end 80.334448 120.315201) (width 0.109) (layer "In2.Cu") (net 208))
  (segment (start 79.340955 115.876819) (end 78.633329 116.584442) (width 0.109) (layer "In2.Cu") (net 208))
  (segment (start 77.894106 115.457538) (end 77.874917 115.497385) (width 0.109) (layer "In2.Cu") (net 208))
  (segment (start 81.466082 122.330312) (end 81.504467 122.334636) (width 0.109) (layer "In2.Cu") (net 208))
  (segment (start 80.316794 116.634286) (end 80.316794 116.678512) (width 0.109) (layer "In2.Cu") (net 208))
  (segment (start 80.194295 119.778654) (end 80.258075 119.842434) (width 0.109) (layer "In2.Cu") (net 208))
  (segment (start 80.287763 116.761474) (end 80.260189 116.796053) (width 0.109) (layer "In2.Cu") (net 208))
  (segment (start 80.509215 119.930312) (end 81.516082 119.930312) (width 0.109) (layer "In2.Cu") (net 208))
  (segment (start 80.907599 118.417145) (end 80.93739 118.502281) (width 0.109) (layer "In2.Cu") (net 208))
  (segment (start 80.509215 119.075312) (end 80.419584 119.08541) (width 0.109) (layer "In2.Cu") (net 208))
  (segment (start 80.258075 123.442434) (end 80.334448 123.490422) (width 0.109) (layer "In2.Cu") (net 208))
  (segment (start 77.874917 115.497385) (end 77.847342 115.531962) (width 0.109) (layer "In2.Cu") (net 208))
  (segment (start 79.552563 117.503676) (end 79.493036 117.57832) (width 0.109) (layer "In2.Cu") (net 208))
  (segment (start 80.287763 116.551322) (end 80.306953 116.591169) (width 0.109) (layer "In2.Cu") (net 208))
  (segment (start 77.4725 111.097186) (end 77.4725 114.877813) (width 0.109) (layer "In2.Cu") (net 208))
  (segment (start 77.843719 105.675967) (end 77.3725 106.147186) (width 0.109) (layer "In2.Cu") (net 208))
  (segment (start 81.688582 118.902812) (end 81.684258 118.941196) (width 0.109) (layer "In2.Cu") (net 208))
  (segment (start 80.11785 118.203133) (end 80.192493 118.143607) (width 0.109) (layer "In2.Cu") (net 208))
  (segment (start 81.623634 120.237677) (end 81.590927 120.258229) (width 0.109) (layer "In2.Cu") (net 208))
  (segment (start 81.573634 122.367946) (end 81.600948 122.39526) (width 0.109) (layer "In2.Cu") (net 208))
  (segment (start 80.8975 118.327514) (end 80.907599 118.417145) (width 0.109) (layer "In2.Cu") (net 208))
  (segment (start 80.509215 121.130312) (end 81.516082 121.130312) (width 0.109) (layer "In2.Cu") (net 208))
  (segment (start 78.573802 117.112753) (end 78.633329 117.187397) (width 0.109) (layer "In2.Cu") (net 208))
  (segment (start 77.847342 115.252655) (end 77.874917 115.287232) (width 0.109) (layer "In2.Cu") (net 208))
  (segment (start 78.532378 117.026735) (end 78.573802 117.112753) (width 0.109) (layer "In2.Cu") (net 208))
  (segment (start 81.554467 118.734636) (end 81.590927 118.747394) (width 0.109) (layer "In2.Cu") (net 208))
  (segment (start 79.430368 117.85289) (end 79.451612 117.945969) (width 0.109) (layer "In2.Cu") (net 208))
  (segment (start 81.634258 122.464427) (end 81.638582 122.502812) (width 0.109) (layer "In2.Cu") (net 208))
  (segment (start 77.654568 115.739852) (end 77.613144 115.82587) (width 0.109) (layer "In2.Cu") (net 208))
  (segment (start 80.334448 121.515201) (end 80.258075 121.563189) (width 0.109) (layer "In2.Cu") (net 208))
  (segment (start 80.8975 123.702812) (end 80.8975 124.577813) (width 0.109) (layer "In2.Cu") (net 208))
  (segment (start 79.451612 117.945969) (end 79.493036 118.031987) (width 0.109) (layer "In2.Cu") (net 208))
  (segment (start 80.116516 123.217145) (end 80.146307 123.302281) (width 0.109) (layer "In2.Cu") (net 208))
  (segment (start 81.590927 120.258229) (end 81.554467 120.270987) (width 0.109) (layer "In2.Cu") (net 208))
  (segment (start 79.096225 115.569936) (end 79.136072 115.550748) (width 0.109) (layer "In2.Cu") (net 208))
  (segment (start 79.136072 115.550748) (end 79.179189 115.540907) (width 0.109) (layer "In2.Cu") (net 208))
  (segment (start 77.894106 115.327078) (end 77.903947 115.370195) (width 0.109) (layer "In2.Cu") (net 208))
  (segment (start 81.6715 120.027967) (end 81.684258 120.064427) (width 0.109) (layer "In2.Cu") (net 208))
  (segment (start 81.650948 120.210363) (end 81.623634 120.237677) (width 0.109) (layer "In2.Cu") (net 208))
  (segment (start 80.334448 119.890422) (end 80.419584 119.920213) (width 0.109) (layer "In2.Cu") (net 208))
  (segment (start 81.6215 122.427967) (end 81.634258 122.464427) (width 0.109) (layer "In2.Cu") (net 208))
  (segment (start 80.509215 123.530312) (end 80.725 123.530312) (width 0.109) (layer "In2.Cu") (net 208))
  (segment (start 80.419584 122.320213) (end 80.509215 122.330312) (width 0.109) (layer "In2.Cu") (net 208))
  (segment (start 77.751071 116.30514) (end 77.825715 116.364666) (width 0.109) (layer "In2.Cu") (net 208))
  (segment (start 80.192493 118.143607) (end 80.32574 118.010359) (width 0.109) (layer "In2.Cu") (net 208))
  (segment (start 80.8975 124.577813) (end 87.078686 130.759) (width 0.109) (layer "In2.Cu") (net 208))
  (segment (start 80.116516 121.788478) (end 80.106418 121.878109) (width 0.109) (layer "In2.Cu") (net 208))
  (segment (start 80.419584 122.68541) (end 80.334448 122.715201) (width 0.109) (layer "In2.Cu") (net 208))
  (segment (start 80.258075 119.842434) (end 80.334448 119.890422) (width 0.109) (layer "In2.Cu") (net 208))
  (segment (start 81.516082 121.475312) (end 80.509215 121.475312) (width 0.109) (layer "In2.Cu") (net 208))
  (segment (start 80.763384 123.534636) (end 80.799844 123.547394) (width 0.109) (layer "In2.Cu") (net 208))
  (segment (start 81.45 104.75) (end 81.389 104.811) (width 0.182) (layer "B.Cu") (net 208))
  (segment (start 80.218245 105.614467) (end 78.659 105.614467) (width 0.182) (layer "B.Cu") (net 208))
  (segment (start 81.9 104.75) (end 81.45 104.75) (width 0.182) (layer "B.Cu") (net 208))
  (segment (start 81.021712 104.811) (end 80.218245 105.614467) (width 0.182) (layer "B.Cu") (net 208))
  (segment (start 78.659 105.614467) (end 78.55 105.505467) (width 0.182) (layer "B.Cu") (net 208))
  (segment (start 81.389 104.811) (end 81.021712 104.811) (width 0.182) (layer "B.Cu") (net 208))
  (segment (start 89.4415 130.314) (end 89.8265 130.004) (width 0.182) (layer "F.Cu") (net 209))
  (via (at 78.55 106.101468) (size 0.45) (drill 0.1) (layers "F.Cu" "B.Cu") (net 209))
  (via (at 89.4415 130.314) (size 0.45) (drill 0.1) (layers "F.Cu" "B.Cu") (net 209))
  (segment (start 81.327046 124.608167) (end 81.355036 124.608168) (width 0.109) (layer "In2.Cu") (net 209))
  (segment (start 80.459073 120.858229) (end 80.495533 120.870987) (width 0.109) (layer "In2.Cu") (net 209))
  (segment (start 81.855705 121.578654) (end 81.791925 121.642434) (width 0.109) (layer "In2.Cu") (net 209))
  (segment (start 80.365742 123.141196) (end 80.3785 123.177656) (width 0.109) (layer "In2.Cu") (net 209))
  (segment (start 79.060488 115.297761) (end 79.153568 115.276518) (width 0.109) (layer "In2.Cu") (net 209))
  (segment (start 86.824084 129.97088) (end 86.844258 129.961163) (width 0.109) (layer "In2.Cu") (net 209))
  (segment (start 80.495533 120.870987) (end 80.533918 120.875312) (width 0.109) (layer "In2.Cu") (net 209))
  (segment (start 78.066646 107.166649) (end 78.081865 107.185733) (width 0.109) (layer "In2.Cu") (net 209))
  (segment (start 80.924469 123.315201) (end 81.000842 123.363189) (width 0.109) (layer "In2.Cu") (net 209))
  (segment (start 81.791925 118.563189) (end 81.855705 118.626969) (width 0.109) (layer "In2.Cu") (net 209))
  (segment (start 86.946762 130.156497) (end 86.937047 130.176673) (width 0.109) (layer "In2.Cu") (net 209))
  (segment (start 81.715552 118.515201) (end 81.791925 118.563189) (width 0.109) (layer "In2.Cu") (net 209))
  (segment (start 80.533918 120.875312) (end 81.540785 120.875312) (width 0.109) (layer "In2.Cu") (net 209))
  (segment (start 86.937047 130.242729) (end 86.946762 130.262903) (width 0.109) (layer "In2.Cu") (net 209))
  (segment (start 81.64853 124.632172) (end 81.654759 124.65946) (width 0.109) (layer "In2.Cu") (net 209))
  (segment (start 81.715552 120.490422) (end 81.630416 120.520213) (width 0.109) (layer "In2.Cu") (net 209))
  (segment (start 86.747062 130.013501) (end 86.768893 130.008518) (width 0.109) (layer "In2.Cu") (net 209))
  (segment (start 78.804555 116.780843) (end 78.785366 116.820689) (width 0.109) (layer "In2.Cu") (net 209))
  (segment (start 81.540785 119.330312) (end 80.533918 119.330312) (width 0.109) (layer "In2.Cu") (net 209))
  (segment (start 81.580416 122.08541) (end 81.665552 122.115201) (width 0.109) (layer "In2.Cu") (net 209))
  (segment (start 79.640707 115.596349) (end 79.66195 115.689427) (width 0.109) (layer "In2.Cu") (net 209))
  (segment (start 86.932064 130.220898) (end 86.937047 130.242729) (width 0.109) (layer "In2.Cu") (net 209))
  (segment (start 86.702837 130.008518) (end 86.72467 130.013502) (width 0.109) (layer "In2.Cu") (net 209))
  (segment (start 80.3785 119.577656) (end 80.399052 119.610363) (width 0.109) (layer "In2.Cu") (net 209))
  (segment (start 79.694759 117.78304) (end 79.694759 117.827266) (width 0.109) (layer "In2.Cu") (net 209))
  (segment (start 78.010144 107.464565) (end 78.020735 107.486556) (width 0.109) (layer "In2.Cu") (net 209))
  (segment (start 81.580416 122.920213) (end 81.490785 122.930312) (width 0.109) (layer "In2.Cu") (net 209))
  (segment (start 77.840731 107.22315) (end 77.862723 107.212561) (width 0.109) (layer "In2.Cu") (net 209))
  (segment (start 78.804555 116.990996) (end 78.83213 117.025573) (width 0.109) (layer "In2.Cu") (net 209))
  (segment (start 80.399052 120.59526) (end 80.3785 120.627967) (width 0.109) (layer "In2.Cu") (net 209))
  (segment (start 86.768893 130.008518) (end 86.789069 129.998803) (width 0.109) (layer "In2.Cu") (net 209))
  (segment (start 81.903693 121.103342) (end 81.933484 121.188478) (width 0.109) (layer "In2.Cu") (net 209))
  (segment (start 80.365742 121.864427) (end 80.361418 121.902812) (width 0.109) (layer "In2.Cu") (net 209))
  (segment (start 81.943582 118.927514) (end 81.933484 119.017145) (width 0.109) (layer "In2.Cu") (net 209))
  (segment (start 77.866133 116.031916) (end 77.885322 116.071762) (width 0.109) (layer "In2.Cu") (net 209))
  (segment (start 79.868904 118.001411) (end 79.91313 118.001411) (width 0.109) (layer "In2.Cu") (net 209))
  (segment (start 80.361418 121.902812) (end 80.365742 121.941196) (width 0.109) (layer "In2.Cu") (net 209))
  (segment (start 80.399052 119.39526) (end 80.3785 119.427967) (width 0.109) (layer "In2.Cu") (net 209))
  (segment (start 81.805705 122.778654) (end 81.741925 122.842434) (width 0.109) (layer "In2.Cu") (net 209))
  (segment (start 81.855705 119.178654) (end 81.791925 119.242434) (width 0.109) (layer "In2.Cu") (net 209))
  (segment (start 78.3795 105.930967) (end 77.949347 105.930967) (width 0.109) (layer "In2.Cu") (net 209))
  (segment (start 80.495533 122.934636) (end 80.459073 122.947394) (width 0.109) (layer "In2.Cu") (net 209))
  (segment (start 78.046143 115.090831) (end 78.10567 115.165475) (width 0.109) (layer "In2.Cu") (net 209))
  (segment (start 80.426366 120.837677) (end 80.459073 120.858229) (width 0.109) (layer "In2.Cu") (net 209))
  (segment (start 81.490785 122.075312) (end 81.580416 122.08541) (width 0.109) (layer "In2.Cu") (net 209))
  (segment (start 81.217449 118.437677) (end 81.250156 118.458229) (width 0.109) (layer "In2.Cu") (net 209))
  (segment (start 86.844258 129.961163) (end 86.866091 129.956181) (width 0.109) (layer "In2.Cu") (net 209))
  (segment (start 80.426366 120.567946) (end 80.399052 120.59526) (width 0.109) (layer "In2.Cu") (net 209))
  (segment (start 86.932063 130.198504) (end 86.932064 130.220898) (width 0.109) (layer "In2.Cu") (net 209))
  (segment (start 80.495533 123.270987) (end 80.533918 123.275312) (width 0.109) (layer "In2.Cu") (net 209))
  (segment (start 79.249038 115.276515) (end 79.342118 115.29776) (width 0.109) (layer "In2.Cu") (net 209))
  (segment (start 86.682663 129.998803) (end 86.702837 130.008518) (width 0.109) (layer "In2.Cu") (net 209))
  (segment (start 78.2025 110.727814) (end 77.7275 111.202814) (width 0.109) (layer "In2.Cu") (net 209))
  (segment (start 80.459073 122.947394) (end 80.426366 122.967946) (width 0.109) (layer "In2.Cu") (net 209))
  (segment (start 80.3785 119.427967) (end 80.365742 119.464427) (width 0.109) (layer "In2.Cu") (net 209))
  (segment (start 79.539757 116.03864) (end 78.83213 116.746266) (width 0.109) (layer "In2.Cu") (net 209))
  (segment (start 80.459073 120.547394) (end 80.426366 120.567946) (width 0.109) (layer "In2.Cu") (net 209))
  (segment (start 77.6275 106.252814) (end 77.6275 107.097186) (width 0.109) (layer "In2.Cu") (net 209))
  (segment (start 78.2025 107.672186) (end 78.2025 110.727814) (width 0.109) (layer "In2.Cu") (net 209))
  (segment (start 80.533918 119.675312) (end 81.540785 119.675312) (width 0.109) (layer "In2.Cu") (net 209))
  (segment (start 77.93158 107.151431) (end 77.953571 107.14084) (width 0.109) (layer "In2.Cu") (net 209))
  (segment (start 81.190135 118.410363) (end 81.217449 118.437677) (width 0.109) (layer "In2.Cu") (net 209))
  (segment (start 81.252655 124.572343) (end 81.274537 124.589795) (width 0.109) (layer "In2.Cu") (net 209))
  (segment (start 78.157625 116.133913) (end 78.192203 116.106338) (width 0.109) (layer "In2.Cu") (net 209))
  (segment (start 80.361418 120.702812) (end 80.365742 120.741196) (width 0.109) (layer "In2.Cu") (net 209))
  (segment (start 81.630416 119.68541) (end 81.715552 119.715201) (width 0.109) (layer "In2.Cu") (net 209))
  (segment (start 86.960725 129.997569) (end 86.974687 130.015077) (width 0.109) (layer "In2.Cu") (net 209))
  (segment (start 77.862723 107.212561) (end 77.881805 107.197342) (width 0.109) (layer "In2.Cu") (net 209))
  (segment (start 81.584323 124.554889) (end 81.606207 124.572341) (width 0.109) (layer "In2.Cu") (net 209))
  (segment (start 81.791925 121.642434) (end 81.715552 121.690422) (width 0.109) (layer "In2.Cu") (net 209))
  (segment (start 80.426366 122.037677) (end 80.459073 122.058229) (width 0.109) (layer "In2.Cu") (net 209))
  (segment (start 80.426366 119.637677) (end 80.459073 119.658229) (width 0.109) (layer "In2.Cu") (net 209))
  (segment (start 80.581184 116.608661) (end 80.581185 116.704135) (width 0.109) (layer "In2.Cu") (net 209))
  (segment (start 81.601481 124.783728) (end 81.589336 124.808947) (width 0.109) (layer "In2.Cu") (net 209))
  (segment (start 86.888483 129.95618) (end 86.910314 129.961163) (width 0.109) (layer "In2.Cu") (net 209))
  (segment (start 80.3785 121.977656) (end 80.399052 122.010363) (width 0.109) (layer "In2.Cu") (net 209))
  (segment (start 86.937047 130.176673) (end 86.932063 130.198504) (width 0.109) (layer "In2.Cu") (net 209))
  (segment (start 81.000842 123.363189) (end 81.064622 123.426969) (width 0.109) (layer "In2.Cu") (net 209))
  (segment (start 81.618933 124.938621) (end 86.665156 129.984842) (width 0.109) (layer "In2.Cu") (net 209))
  (segment (start 80.365742 120.741196) (end 80.3785 120.777656) (width 0.109) (layer "In2.Cu") (net 209))
  (segment (start 81.531814 124.536516) (end 81.559104 124.542744) (width 0.109) (layer "In2.Cu") (net 209))
  (segment (start 81.630416 120.520213) (end 81.540785 120.530312) (width 0.109) (layer "In2.Cu") (net 209))
  (segment (start 86.866091 129.956181) (end 86.888483 129.95618) (width 0.109) (layer "In2.Cu") (net 209))
  (segment (start 78.168338 115.344572) (end 78.168338 115.440045) (width 0.109) (layer "In2.Cu") (net 209))
  (segment (start 86.947998 129.984842) (end 86.960725 129.997569) (width 0.109) (layer "In2.Cu") (net 209))
  (segment (start 86.910314 129.961163) (end 86.93049 129.97088) (width 0.109) (layer "In2.Cu") (net 209))
  (segment (start 80.458989 116.35492) (end 80.518515 116.429564) (width 0.109) (layer "In2.Cu") (net 209))
  (segment (start 79.502779 115.39871) (end 79.539755 115.435686) (width 0.109) (layer "In2.Cu") (net 209))
  (segment (start 81.1525 123.678109) (end 81.1525 124.472187) (width 0.109) (layer "In2.Cu") (net 209))
  (segment (start 81.903693 121.502281) (end 81.855705 121.578654) (width 0.109) (layer "In2.Cu") (net 209))
  (segment (start 77.6275 107.097186) (end 77.727657 107.197343) (width 0.109) (layer "In2.Cu") (net 209))
  (segment (start 80.163918 117.811558) (end 80.238561 117.752032) (width 0.109) (layer "In2.Cu") (net 209))
  (segment (start 78.004714 107.44077) (end 78.010144 107.464565) (width 0.109) (layer "In2.Cu") (net 209))
  (segment (start 81.943582 121.278109) (end 81.943582 121.327514) (width 0.109) (layer "In2.Cu") (net 209))
  (segment (start 80.459073 123.258229) (end 80.495533 123.270987) (width 0.109) (layer "In2.Cu") (net 209))
  (segment (start 80.458991 116.957874) (end 79.751364 117.6655) (width 0.109) (layer "In2.Cu") (net 209))
  (segment (start 80.34737 116.258418) (end 80.422013 116.317944) (width 0.109) (layer "In2.Cu") (net 209))
  (segment (start 80.030671 117.944806) (end 80.163918 117.811558) (width 0.109) (layer "In2.Cu") (net 209))
  (segment (start 81.601481 124.916736) (end 81.618933 124.938621) (width 0.109) (layer "In2.Cu") (net 209))
  (segment (start 78.030436 116.162943) (end 78.074662 116.162943) (width 0.109) (layer "In2.Cu") (net 209))
  (segment (start 79.661951 115.784901) (end 79.640708 115.877979) (width 0.109) (layer "In2.Cu") (net 209))
  (segment (start 81.933484 118.788478) (end 81.943582 118.878109) (width 0.109) (layer "In2.Cu") (net 209))
  (segment (start 86.989385 130.079476) (end 86.984402 130.101307) (width 0.109) (layer "In2.Cu") (net 209))
  (segment (start 78.097886 107.255928) (end 78.092455 107.279725) (width 0.109) (layer "In2.Cu") (net 209))
  (segment (start 78.117779 116.153102) (end 78.157625 116.133913) (width 0.109) (layer "In2.Cu") (net 209))
  (segment (start 81.883484 122.388478) (end 81.893582 122.478109) (width 0.109) (layer "In2.Cu") (net 209))
  (segment (start 80.399052 119.610363) (end 80.426366 119.637677) (width 0.109) (layer "In2.Cu") (net 209))
  (segment (start 80.533918 123.275312) (end 80.749702 123.275312) (width 0.109) (layer "In2.Cu") (net 209))
  (segment (start 77.856291 115.988799) (end 77.866133 116.031916) (width 0.109) (layer "In2.Cu") (net 209))
  (segment (start 81.893582 122.527514) (end 81.883484 122.617145) (width 0.109) (layer "In2.Cu") (net 209))
  (segment (start 80.533918 122.930312) (end 80.495533 122.934636) (width 0.109) (layer "In2.Cu") (net 209))
  (segment (start 80.518515 116.429564) (end 80.559941 116.515583) (width 0.109) (layer "In2.Cu") (net 209))
  (segment (start 77.953571 107.14084) (end 77.977368 107.135409) (width 0.109) (layer "In2.Cu") (net 209))
  (segment (start 80.533918 121.730312) (end 80.495533 121.734636) (width 0.109) (layer "In2.Cu") (net 209))
  (segment (start 81.476534 124.542744) (end 81.503822 124.536515) (width 0.109) (layer "In2.Cu") (net 209))
  (segment (start 78.899827 115.398713) (end 78.97447 115.339185) (width 0.109) (layer "In2.Cu") (net 209))
  (segment (start 78.081864 107.301715) (end 78.066647 107.320799) (width 0.109) (layer "In2.Cu") (net 209))
  (segment (start 81.325 118.475312) (end 81.540785 118.475312) (width 0.109) (layer "In2.Cu") (net 209))
  (segment (start 80.3785 123.027967) (end 80.365742 123.064427) (width 0.109) (layer "In2.Cu") (net 209))
  (segment (start 78.035953 107.35149) (end 78.020736 107.370574) (width 0.109) (layer "In2.Cu") (net 209))
  (segment (start 86.960724 130.280411) (end 87.184314 130.504) (width 0.109) (layer "In2.Cu") (net 209))
  (segment (start 81.853693 122.702281) (end 81.805705 122.778654) (width 0.109) (layer "In2.Cu") (net 209))
  (segment (start 78.906553 117.072336) (end 78.94967 117.082177) (width 0.109) (layer "In2.Cu") (net 209))
  (segment (start 80.518516 116.883232) (end 80.458991 116.957874) (width 0.109) (layer "In2.Cu") (net 209))
  (segment (start 77.912896 115.827032) (end 77.885322 115.861609) (width 0.109) (layer "In2.Cu") (net 209))
  (segment (start 79.66195 115.689427) (end 79.661951 115.784901) (width 0.109) (layer "In2.Cu") (net 209))
  (segment (start 80.324579 117.710608) (end 80.417658 117.689363) (width 0.109) (layer "In2.Cu") (net 209))
  (segment (start 79.599282 115.963998) (end 79.539757 116.03864) (width 0.109) (layer "In2.Cu") (net 209))
  (segment (start 80.238561 117.752032) (end 80.324579 117.710608) (width 0.109) (layer "In2.Cu") (net 209))
  (segment (start 81.715552 119.715201) (end 81.791925 119.763189) (width 0.109) (layer "In2.Cu") (net 209))
  (segment (start 79.893704 116.258419) (end 79.979722 116.216995) (width 0.109) (layer "In2.Cu") (net 209))
  (segment (start 86.984402 130.035251) (end 86.989386 130.057084) (width 0.109) (layer "In2.Cu") (net 209))
  (segment (start 78.785366 116.95115) (end 78.804555 116.990996) (width 0.109) (layer "In2.Cu") (net 209))
  (segment (start 78.074662 116.162943) (end 78.117779 116.153102) (width 0.109) (layer "In2.Cu") (net 209))
  (segment (start 81.540785 120.875312) (end 81.630416 120.88541) (width 0.109) (layer "In2.Cu") (net 209))
  (segment (start 79.723789 117.700077) (end 79.7046 117.739923) (width 0.109) (layer "In2.Cu") (net 209))
  (segment (start 81.855705 119.826969) (end 81.903693 119.903342) (width 0.109) (layer "In2.Cu") (net 209))
  (segment (start 78.027655 115.712274) (end 77.912896 115.827032) (width 0.109) (layer "In2.Cu") (net 209))
  (segment (start 81.855705 121.026969) (end 81.903693 121.103342) (width 0.109) (layer "In2.Cu") (net 209))
  (segment (start 80.559941 116.515583) (end 80.581184 116.608661) (width 0.109) (layer "In2.Cu") (net 209))
  (segment (start 81.903693 120.302281) (end 81.855705 120.378654) (width 0.109) (layer "In2.Cu") (net 209))
  (segment (start 80.365742 121.941196) (end 80.3785 121.977656) (width 0.109) (layer "In2.Cu") (net 209))
  (segment (start 79.819061 116.317947) (end 79.893704 116.258419) (width 0.109) (layer "In2.Cu") (net 209))
  (segment (start 80.495533 119.670987) (end 80.533918 119.675312) (width 0.109) (layer "In2.Cu") (net 209))
  (segment (start 79.539755 115.435686) (end 79.599281 115.51033) (width 0.109) (layer "In2.Cu") (net 209))
  (segment (start 78.97447 115.339185) (end 79.060488 115.297761) (width 0.109) (layer "In2.Cu") (net 209))
  (segment (start 78.775525 116.863806) (end 78.775525 116.908032) (width 0.109) (layer "In2.Cu") (net 209))
  (segment (start 79.785941 117.972381) (end 79.825787 117.99157) (width 0.109) (layer "In2.Cu") (net 209))
  (segment (start 79.996093 117.972381) (end 80.030671 117.944806) (width 0.109) (layer "In2.Cu") (net 209))
  (segment (start 80.168272 116.195749) (end 80.261352 116.216994) (width 0.109) (layer "In2.Cu") (net 209))
  (segment (start 81.741925 122.842434) (end 81.665552 122.890422) (width 0.109) (layer "In2.Cu") (net 209))
  (segment (start 86.946762 130.262903) (end 86.960724 130.280411) (width 0.109) (layer "In2.Cu") (net 209))
  (segment (start 79.751364 117.944807) (end 79.785941 117.972381) (width 0.109) (layer "In2.Cu") (net 209))
  (segment (start 80.581185 116.704135) (end 80.559942 116.797213) (width 0.109) (layer "In2.Cu") (net 209))
  (segment (start 79.428136 115.339184) (end 79.502779 115.39871) (width 0.109) (layer "In2.Cu") (net 209))
  (segment (start 78.192203 116.106338) (end 78.899827 115.398713) (width 0.109) (layer "In2.Cu") (net 209))
  (segment (start 78.092455 107.279725) (end 78.081864 107.301715) (width 0.109) (layer "In2.Cu") (net 209))
  (segment (start 80.072802 116.195752) (end 80.168272 116.195749) (width 0.109) (layer "In2.Cu") (net 209))
  (segment (start 81.299756 124.60194) (end 81.327046 124.608167) (width 0.109) (layer "In2.Cu") (net 209))
  (segment (start 79.342118 115.29776) (end 79.428136 115.339184) (width 0.109) (layer "In2.Cu") (net 209))
  (segment (start 79.7046 117.739923) (end 79.694759 117.78304) (width 0.109) (layer "In2.Cu") (net 209))
  (segment (start 81.903693 118.703342) (end 81.933484 118.788478) (width 0.109) (layer "In2.Cu") (net 209))
  (segment (start 78.775525 116.908032) (end 78.785366 116.95115) (width 0.109) (layer "In2.Cu") (net 209))
  (segment (start 79.723789 117.91023) (end 79.751364 117.944807) (width 0.109) (layer "In2.Cu") (net 209))
  (segment (start 77.949347 105.930967) (end 77.6275 106.252814) (width 0.109) (layer "In2.Cu") (net 209))
  (segment (start 80.365742 123.064427) (end 80.361418 123.102812) (width 0.109) (layer "In2.Cu") (net 209))
  (segment (start 80.459073 119.347394) (end 80.426366 119.367946) (width 0.109) (layer "In2.Cu") (net 209))
  (segment (start 77.885322 115.861609) (end 77.866133 115.901455) (width 0.109) (layer "In2.Cu") (net 209))
  (segment (start 80.839333 123.28541) (end 80.924469 123.315201) (width 0.109) (layer "In2.Cu") (net 209))
  (segment (start 78.004714 107.416362) (end 78.004714 107.44077) (width 0.109) (layer "In2.Cu") (net 209))
  (segment (start 80.361418 123.102812) (end 80.365742 123.141196) (width 0.109) (layer "In2.Cu") (net 209))
  (segment (start 81.064622 123.426969) (end 81.11261 123.503342) (width 0.109) (layer "In2.Cu") (net 209))
  (segment (start 81.286616 118.470987) (end 81.325 118.475312) (width 0.109) (layer "In2.Cu") (net 209))
  (segment (start 81.250156 118.458229) (end 81.286616 118.470987) (width 0.109) (layer "In2.Cu") (net 209))
  (segment (start 78.092454 107.207723) (end 78.097886 107.23152) (width 0.109) (layer "In2.Cu") (net 209))
  (segment (start 81.559104 124.542744) (end 81.584323 124.554889) (width 0.109) (layer "In2.Cu") (net 209))
  (segment (start 81.791925 120.442434) (end 81.715552 120.490422) (width 0.109) (layer "In2.Cu") (net 209))
  (segment (start 81.903693 119.903342) (end 81.933484 119.988478) (width 0.109) (layer "In2.Cu") (net 209))
  (segment (start 80.422013 116.317944) (end 80.458989 116.35492) (width 0.109) (layer "In2.Cu") (net 209))
  (segment (start 77.7275 114.772188) (end 78.046143 115.090831) (width 0.109) (layer "In2.Cu") (net 209))
  (segment (start 80.3785 120.627967) (end 80.365742 120.664427) (width 0.109) (layer "In2.Cu") (net 209))
  (segment (start 80.399052 122.010363) (end 80.426366 122.037677) (width 0.109) (layer "In2.Cu") (net 209))
  (segment (start 81.1525 118.302812) (end 81.156825 118.341196) (width 0.109) (layer "In2.Cu") (net 209))
  (segment (start 81.903693 119.102281) (end 81.855705 119.178654) (width 0.109) (layer "In2.Cu") (net 209))
  (segment (start 81.589336 124.891518) (end 81.601481 124.916736) (width 0.109) (layer "In2.Cu") (net 209))
  (segment (start 78.047564 107.151432) (end 78.066646 107.166649) (width 0.109) (layer "In2.Cu") (net 209))
  (segment (start 80.60621 117.710608) (end 80.692228 117.752032) (width 0.109) (layer "In2.Cu") (net 209))
  (segment (start 81.943582 118.878109) (end 81.943582 118.927514) (width 0.109) (layer "In2.Cu") (net 209))
  (segment (start 80.533918 119.330312) (end 80.495533 119.334636) (width 0.109) (layer "In2.Cu") (net 209))
  (segment (start 81.791925 119.763189) (end 81.855705 119.826969) (width 0.109) (layer "In2.Cu") (net 209))
  (segment (start 79.640708 115.877979) (end 79.599282 115.963998) (width 0.109) (layer "In2.Cu") (net 209))
  (segment (start 81.274537 124.589795) (end 81.299756 124.60194) (width 0.109) (layer "In2.Cu") (net 209))
  (segment (start 81.665552 122.115201) (end 81.741925 122.163189) (width 0.109) (layer "In2.Cu") (net 209))
  (segment (start 81.618932 124.585068) (end 81.636385 124.606953) (width 0.109) (layer "In2.Cu") (net 209))
  (segment (start 79.91313 118.001411) (end 79.956247 117.99157) (width 0.109) (layer "In2.Cu") (net 209))
  (segment (start 80.3785 123.177656) (end 80.399052 123.210363) (width 0.109) (layer "In2.Cu") (net 209))
  (segment (start 86.665156 129.984842) (end 86.682663 129.998803) (width 0.109) (layer "In2.Cu") (net 209))
  (segment (start 80.495533 120.534636) (end 80.459073 120.547394) (width 0.109) (layer "In2.Cu") (net 209))
  (segment (start 80.426366 123.237677) (end 80.459073 123.258229) (width 0.109) (layer "In2.Cu") (net 209))
  (segment (start 81.853693 122.303342) (end 81.883484 122.388478) (width 0.109) (layer "In2.Cu") (net 209))
  (segment (start 81.540785 119.675312) (end 81.630416 119.68541) (width 0.109) (layer "In2.Cu") (net 209))
  (segment (start 86.72467 130.013502) (end 86.747062 130.013501) (width 0.109) (layer "In2.Cu") (net 209))
  (segment (start 78.866707 117.053147) (end 78.906553 117.072336) (width 0.109) (layer "In2.Cu") (net 209))
  (segment (start 86.974687 130.121483) (end 86.960725 130.138991) (width 0.109) (layer "In2.Cu") (net 209))
  (segment (start 81.355036 124.608168) (end 81.382327 124.601938) (width 0.109) (layer "In2.Cu") (net 209))
  (segment (start 80.459073 122.058229) (end 80.495533 122.070987) (width 0.109) (layer "In2.Cu") (net 209))
  (segment (start 79.7046 117.870384) (end 79.723789 117.91023) (width 0.109) (layer "In2.Cu") (net 209))
  (segment (start 81.933484 120.217145) (end 81.903693 120.302281) (width 0.109) (layer "In2.Cu") (net 209))
  (segment (start 81.11261 123.503342) (end 81.142401 123.588478) (width 0.109) (layer "In2.Cu") (net 209))
  (segment (start 77.977368 107.135409) (end 78.001776 107.135409) (width 0.109) (layer "In2.Cu") (net 209))
  (segment (start 80.426366 121.767946) (end 80.399052 121.79526) (width 0.109) (layer "In2.Cu") (net 209))
  (segment (start 80.417658 117.689363) (end 80.513131 117.689363) (width 0.109) (layer "In2.Cu") (net 209))
  (segment (start 77.792526 107.228581) (end 77.816934 107.228581) (width 0.109) (layer "In2.Cu") (net 209))
  (segment (start 77.912498 107.16665) (end 77.93158 107.151431) (width 0.109) (layer "In2.Cu") (net 209))
  (segment (start 81.855705 118.626969) (end 81.903693 118.703342) (width 0.109) (layer "In2.Cu") (net 209))
  (segment (start 78.020736 107.370574) (end 78.010145 107.392565) (width 0.109) (layer "In2.Cu") (net 209))
  (segment (start 80.495533 121.734636) (end 80.459073 121.747394) (width 0.109) (layer "In2.Cu") (net 209))
  (segment (start 80.426366 119.367946) (end 80.399052 119.39526) (width 0.109) (layer "In2.Cu") (net 209))
  (segment (start 80.513131 117.689363) (end 80.60621 117.710608) (width 0.109) (layer "In2.Cu") (net 209))
  (segment (start 80.3785 120.777656) (end 80.399052 120.810363) (width 0.109) (layer "In2.Cu") (net 209))
  (segment (start 78.993896 117.082177) (end 79.037013 117.072336) (width 0.109) (layer "In2.Cu") (net 209))
  (segment (start 77.746739 107.21256) (end 77.768731 107.223151) (width 0.109) (layer "In2.Cu") (net 209))
  (segment (start 81.540785 121.730312) (end 80.533918 121.730312) (width 0.109) (layer "In2.Cu") (net 209))
  (segment (start 81.490785 122.930312) (end 80.533918 122.930312) (width 0.109) (layer "In2.Cu") (net 209))
  (segment (start 80.459073 121.747394) (end 80.426366 121.767946) (width 0.109) (layer "In2.Cu") (net 209))
  (segment (start 77.727657 107.197343) (end 77.746739 107.21256) (width 0.109) (layer "In2.Cu") (net 209))
  (segment (start 81.805705 122.226969) (end 81.853693 122.303342) (width 0.109) (layer "In2.Cu") (net 209))
  (segment (start 81.630416 120.88541) (end 81.715552 120.915201) (width 0.109) (layer "In2.Cu") (net 209))
  (segment (start 81.156825 118.341196) (end 81.169583 118.377656) (width 0.109) (layer "In2.Cu") (net 209))
  (segment (start 78.10567 115.619142) (end 78.046143 115.693785) (width 0.109) (layer "In2.Cu") (net 209))
  (segment (start 80.459073 119.658229) (end 80.495533 119.670987) (width 0.109) (layer "In2.Cu") (net 209))
  (segment (start 81.715552 119.290422) (end 81.630416 119.320213) (width 0.109) (layer "In2.Cu") (net 209))
  (segment (start 81.933484 121.188478) (end 81.943582 121.278109) (width 0.109) (layer "In2.Cu") (net 209))
  (segment (start 86.960725 130.138991) (end 86.946762 130.156497) (width 0.109) (layer "In2.Cu") (net 209))
  (segment (start 81.933484 121.417145) (end 81.903693 121.502281) (width 0.109) (layer "In2.Cu") (net 209))
  (segment (start 78.168338 115.440045) (end 78.147094 115.533124) (width 0.109) (layer "In2.Cu") (net 209))
  (segment (start 81.715552 120.915201) (end 81.791925 120.963189) (width 0.109) (layer "In2.Cu") (net 209))
  (segment (start 81.943582 121.327514) (end 81.933484 121.417145) (width 0.109) (layer "In2.Cu") (net 209))
  (segment (start 77.856291 115.944573) (end 77.856291 115.988799) (width 0.109) (layer "In2.Cu") (net 209))
  (segment (start 81.606207 124.572341) (end 81.618932 124.585068) (width 0.109) (layer "In2.Cu") (net 209))
  (segment (start 78.83213 117.025573) (end 78.866707 117.053147) (width 0.109) (layer "In2.Cu") (net 209))
  (segment (start 81.630416 121.720213) (end 81.540785 121.730312) (width 0.109) (layer "In2.Cu") (net 209))
  (segment (start 79.751364 117.6655) (end 79.723789 117.700077) (width 0.109) (layer "In2.Cu") (net 209))
  (segment (start 78.010145 107.392565) (end 78.004714 107.416362) (width 0.109) (layer "In2.Cu") (net 209))
  (segment (start 80.365742 119.541196) (end 80.3785 119.577656) (width 0.109) (layer "In2.Cu") (net 209))
  (segment (start 89.2515 130.504) (end 89.4415 130.314) (width 0.109) (layer "In2.Cu") (net 209))
  (segment (start 81.540785 120.530312) (end 80.533918 120.530312) (width 0.109) (layer "In2.Cu") (net 209))
  (segment (start 80.533918 122.075312) (end 81.490785 122.075312) (width 0.109) (layer "In2.Cu") (net 209))
  (segment (start 81.142401 123.588478) (end 81.1525 123.678109) (width 0.109) (layer "In2.Cu") (net 209))
  (segment (start 81.943582 120.127514) (end 81.933484 120.217145) (width 0.109) (layer "In2.Cu") (net 209))
  (segment (start 79.111437 117.025572) (end 79.819061 116.317947) (width 0.109) (layer "In2.Cu") (net 209))
  (segment (start 80.361418 119.502812) (end 80.365742 119.541196) (width 0.109) (layer "In2.Cu") (net 209))
  (segment (start 81.893582 122.478109) (end 81.893582 122.527514) (width 0.109) (layer "In2.Cu") (net 209))
  (segment (start 86.984402 130.101307) (end 86.974687 130.121483) (width 0.109) (layer "In2.Cu") (net 209))
  (segment (start 77.816934 107.228581) (end 77.840731 107.22315) (width 0.109) (layer "In2.Cu") (net 209))
  (segment (start 81.451315 124.554889) (end 81.476534 124.542744) (width 0.109) (layer "In2.Cu") (net 209))
  (segment (start 79.956247 117.99157) (end 79.996093 117.972381) (width 0.109) (layer "In2.Cu") (net 209))
  (segment (start 81.1525 124.472187) (end 81.252655 124.572343) (width 0.109) (layer "In2.Cu") (net 209))
  (segment (start 78.025573 107.140841) (end 78.047564 107.151432) (width 0.109) (layer "In2.Cu") (net 209))
  (segment (start 80.365742 119.464427) (end 80.361418 119.502812) (width 0.109) (layer "In2.Cu") (net 209))
  (segment (start 80.365742 120.664427) (end 80.361418 120.702812) (width 0.109) (layer "In2.Cu") (net 209))
  (segment (start 81.791925 120.963189) (end 81.855705 121.026969) (width 0.109) (layer "In2.Cu") (net 209))
  (segment (start 77.947473 116.133913) (end 77.987319 116.153102) (width 0.109) (layer "In2.Cu") (net 209))
  (segment (start 78.020735 107.486556) (end 78.035955 107.505641) (width 0.109) (layer "In2.Cu") (net 209))
  (segment (start 80.766872 117.811558) (end 81.1525 118.197187) (width 0.109) (layer "In2.Cu") (net 209))
  (segment (start 78.10567 115.165475) (end 78.147094 115.251493) (width 0.109) (layer "In2.Cu") (net 209))
  (segment (start 78.147094 115.533124) (end 78.10567 115.619142) (width 0.109) (layer "In2.Cu") (net 209))
  (segment (start 81.741925 122.163189) (end 81.805705 122.226969) (width 0.109) (layer "In2.Cu") (net 209))
  (segment (start 78.046143 115.693785) (end 78.027655 115.712274) (width 0.109) (layer "In2.Cu") (net 209))
  (segment (start 80.426366 122.967946) (end 80.399052 122.99526) (width 0.109) (layer "In2.Cu") (net 209))
  (segment (start 81.589336 124.808947) (end 81.583107 124.836237) (width 0.109) (layer "In2.Cu") (net 209))
  (segment (start 80.533918 120.530312) (end 80.495533 120.534636) (width 0.109) (layer "In2.Cu") (net 209))
  (segment (start 81.943582 120.078109) (end 81.943582 120.127514) (width 0.109) (layer "In2.Cu") (net 209))
  (segment (start 81.630416 118.48541) (end 81.715552 118.515201) (width 0.109) (layer "In2.Cu") (net 209))
  (segment (start 86.93049 129.97088) (end 86.947998 129.984842) (width 0.109) (layer "In2.Cu") (net 209))
  (segment (start 78.066647 107.320799) (end 78.035953 107.35149) (width 0.109) (layer "In2.Cu") (net 209))
  (segment (start 81.169583 118.377656) (end 81.190135 118.410363) (width 0.109) (layer "In2.Cu") (net 209))
  (segment (start 81.630416 119.320213) (end 81.540785 119.330312) (width 0.109) (layer "In2.Cu") (net 209))
  (segment (start 79.825787 117.99157) (end 79.868904 118.001411) (width 0.109) (layer "In2.Cu") (net 209))
  (segment (start 81.665552 122.890422) (end 81.580416 122.920213) (width 0.109) (layer "In2.Cu") (net 209))
  (segment (start 80.692228 117.752032) (end 80.766872 117.811558) (width 0.109) (layer "In2.Cu") (net 209))
  (segment (start 81.503822 124.536515) (end 81.531814 124.536516) (width 0.109) (layer "In2.Cu") (net 209))
  (segment (start 79.076859 117.053147) (end 79.111437 117.025572) (width 0.109) (layer "In2.Cu") (net 209))
  (segment (start 81.883484 122.617145) (end 81.853693 122.702281) (width 0.109) (layer "In2.Cu") (net 209))
  (segment (start 81.636385 124.739961) (end 81.601481 124.783728) (width 0.109) (layer "In2.Cu") (net 209))
  (segment (start 77.768731 107.223151) (end 77.792526 107.228581) (width 0.109) (layer "In2.Cu") (net 209))
  (segment (start 77.987319 116.153102) (end 78.030436 116.162943) (width 0.109) (layer "In2.Cu") (net 209))
  (segment (start 77.866133 115.901455) (end 77.856291 115.944573) (width 0.109) (layer "In2.Cu") (net 209))
  (segment (start 81.855705 120.378654) (end 81.791925 120.442434) (width 0.109) (layer "In2.Cu") (net 209))
  (segment (start 78.081865 107.185733) (end 78.092454 107.207723) (width 0.109) (layer "In2.Cu") (net 209))
  (segment (start 79.694759 117.827266) (end 79.7046 117.870384) (width 0.109) (layer "In2.Cu") (net 209))
  (segment (start 81.654759 124.65946) (end 81.654758 124.687452) (width 0.109) (layer "In2.Cu") (net 209))
  (segment (start 81.64853 124.714742) (end 81.636385 124.739961) (width 0.109) (layer "In2.Cu") (net 209))
  (segment (start 80.495533 119.334636) (end 80.459073 119.347394) (width 0.109) (layer "In2.Cu") (net 209))
  (segment (start 81.1525 118.197187) (end 81.1525 118.302812) (width 0.109) (layer "In2.Cu") (net 209))
  (segment (start 80.399052 122.99526) (end 80.3785 123.027967) (width 0.109) (layer "In2.Cu") (net 209))
  (segment (start 78.55 106.101467) (end 78.3795 105.930967) (width 0.109) (layer "In2.Cu") (net 209))
  (segment (start 81.636385 124.606953) (end 81.64853 124.632172) (width 0.109) (layer "In2.Cu") (net 209))
  (segment (start 86.789069 129.998803) (end 86.824084 129.97088) (width 0.109) (layer "In2.Cu") (net 209))
  (segment (start 78.035955 107.505641) (end 78.2025 107.672186) (width 0.109) (layer "In2.Cu") (net 209))
  (segment (start 81.382327 124.601938) (end 81.407545 124.589795) (width 0.109) (layer "In2.Cu") (net 209))
  (segment (start 78.55 106.101468) (end 78.55 106.101467) (width 0.109) (layer "In2.Cu") (net 209))
  (segment (start 77.912896 116.106339) (end 77.947473 116.133913) (width 0.109) (layer "In2.Cu") (net 209))
  (segment (start 81.407545 124.589795) (end 81.451315 124.554889) (width 0.109) (layer "In2.Cu") (net 209))
  (segment (start 81.583107 124.836237) (end 81.583108 124.864227) (width 0.109) (layer "In2.Cu") (net 209))
  (segment (start 81.933484 119.017145) (end 81.903693 119.102281) (width 0.109) (layer "In2.Cu") (net 209))
  (segment (start 78.785366 116.820689) (end 78.775525 116.863806) (width 0.109) (layer "In2.Cu") (net 209))
  (segment (start 81.791925 119.242434) (end 81.715552 119.290422) (width 0.109) (layer "In2.Cu") (net 209))
  (segment (start 86.989386 130.057084) (end 86.989385 130.079476) (width 0.109) (layer "In2.Cu") (net 209))
  (segment (start 80.495533 122.070987) (end 80.533918 122.075312) (width 0.109) (layer "In2.Cu") (net 209))
  (segment (start 78.83213 116.746266) (end 78.804555 116.780843) (width 0.109) (layer "In2.Cu") (net 209))
  (segment (start 78.001776 107.135409) (end 78.025573 107.140841) (width 0.109) (layer "In2.Cu") (net 209))
  (segment (start 79.979722 116.216995) (end 80.072802 116.195752) (width 0.109) (layer "In2.Cu") (net 209))
  (segment (start 81.933484 119.988478) (end 81.943582 120.078109) (width 0.109) (layer "In2.Cu") (net 209))
  (segment (start 77.881805 107.197342) (end 77.912498 107.16665) (width 0.109) (layer "In2.Cu") (net 209))
  (segment (start 87.184314 130.504) (end 89.2515 130.504) (width 0.109) (layer "In2.Cu") (net 209))
  (segment (start 79.037013 117.072336) (end 79.076859 117.053147) (width 0.109) (layer "In2.Cu") (net 209))
  (segment (start 80.3785 121.827967) (end 80.365742 121.864427) (width 0.109) (layer "In2.Cu") (net 209))
  (segment (start 78.097886 107.23152) (end 78.097886 107.255928) (width 0.109) (layer "In2.Cu") (net 209))
  (segment (start 81.583108 124.864227) (end 81.589336 124.891518) (width 0.109) (layer "In2.Cu") (net 209))
  (segment (start 77.885322 116.071762) (end 77.912896 116.106339) (width 0.109) (layer "In2.Cu") (net 209))
  (segment (start 78.94967 117.082177) (end 78.993896 117.082177) (width 0.109) (layer "In2.Cu") (net 209))
  (segment (start 80.399052 120.810363) (end 80.426366 120.837677) (width 0.109) (layer "In2.Cu") (net 209))
  (segment (start 80.559942 116.797213) (end 80.518516 116.883232) (width 0.109) (layer "In2.Cu") (net 209))
  (segment (start 78.147094 115.251493) (end 78.168338 115.344572) (width 0.109) (layer "In2.Cu") (net 209))
  (segment (start 77.7275 111.202814) (end 77.7275 114.772188) (width 0.109) (layer "In2.Cu") (net 209))
  (segment (start 86.974687 130.015077) (end 86.984402 130.035251) (width 0.109) (layer "In2.Cu") (net 209))
  (segment (start 80.399052 121.79526) (end 80.3785 121.827967) (width 0.109) (layer "In2.Cu") (net 209))
  (segment (start 80.261352 116.216994) (end 80.34737 116.258418) (width 0.109) (layer "In2.Cu") (net 209))
  (segment (start 79.599281 115.51033) (end 79.640707 115.596349) (width 0.109) (layer "In2.Cu") (net 209))
  (segment (start 80.399052 123.210363) (end 80.426366 123.237677) (width 0.109) (layer "In2.Cu") (net 209))
  (segment (start 81.654758 124.687452) (end 81.64853 124.714742) (width 0.109) (layer "In2.Cu") (net 209))
  (segment (start 80.749702 123.275312) (end 80.839333 123.28541) (width 0.109) (layer "In2.Cu") (net 209))
  (segment (start 79.153568 115.276518) (end 79.249038 115.276515) (width 0.109) (layer "In2.Cu") (net 209))
  (segment (start 81.540785 118.475312) (end 81.630416 118.48541) (width 0.109) (layer "In2.Cu") (net 209))
  (segment (start 81.715552 121.690422) (end 81.630416 121.720213) (width 0.109) (layer "In2.Cu") (net 209))
  (segment (start 78.659 105.992467) (end 78.55 106.101467) (width 0.182) (layer "B.Cu") (net 209))
  (segment (start 81.178288 105.189) (end 80.374821 105.992467) (width 0.182) (layer "B.Cu") (net 209))
  (segment (start 81.45 105.25) (end 81.389 105.189) (width 0.182) (layer "B.Cu") (net 209))
  (segment (start 81.389 105.189) (end 81.178288 105.189) (width 0.182) (layer "B.Cu") (net 209))
  (segment (start 80.374821 105.992467) (end 78.659 105.992467) (width 0.182) (layer "B.Cu") (net 209))
  (segment (start 81.9 105.25) (end 81.45 105.25) (width 0.182) (layer "B.Cu") (net 209))
  (segment (start 90.7865 135.084) (end 91.1715 134.774) (width 0.182) (layer "F.Cu") (net 210))
  (via (at 91.1715 134.774) (size 0.45) (drill 0.1) (layers "F.Cu" "B.Cu") (net 210))
  (via (at 79.275 107.572981) (size 0.45) (drill 0.1) (layers "F.Cu" "B.Cu") (net 210))
  (segment (start 75.696888 117.481833) (end 75.726679 117.566969) (width 0.109) (layer "In6.Cu") (net 210))
  (segment (start 77.141128 119.242344) (end 77.120576 119.275051) (width 0.109) (layer "In6.Cu") (net 210))
  (segment (start 75.999956 116.950098) (end 75.91482 116.979889) (width 0.109) (layer "In6.Cu") (net 210))
  (segment (start 79.275 107.572981) (end 79.1045 107.743481) (width 0.109) (layer "In6.Cu") (net 210))
  (segment (start 77.024095 117.799324) (end 77.060555 117.812082) (width 0.109) (layer "In6.Cu") (net 210))
  (segment (start 75.726679 119.966969) (end 75.774667 120.043342) (width 0.109) (layer "In6.Cu") (net 210))
  (segment (start 77.093262 120.232634) (end 77.120576 120.259948) (width 0.109) (layer "In6.Cu") (net 210))
  (segment (start 75.68679 116.142797) (end 75.68679 116.192202) (width 0.109) (layer "In6.Cu") (net 210))
  (segment (start 75.726679 117.16803) (end 75.696888 117.253166) (width 0.109) (layer "In6.Cu") (net 210))
  (segment (start 75.91482 116.55511) (end 75.999956 116.584901) (width 0.109) (layer "In6.Cu") (net 210))
  (segment (start 75.696888 118.681833) (end 75.726679 118.766969) (width 0.109) (layer "In6.Cu") (net 210))
  (segment (start 75.774667 115.891657) (end 75.726679 115.96803) (width 0.109) (layer "In6.Cu") (net 210))
  (segment (start 77.093262 120.502365) (end 77.060555 120.522917) (width 0.109) (layer "In6.Cu") (net 210))
  (segment (start 75.696888 120.853166) (end 75.68679 120.942797) (width 0.109) (layer "In6.Cu") (net 210))
  (segment (start 77.153886 117.929115) (end 77.15821 117.9675) (width 0.109) (layer "In6.Cu") (net 210))
  (segment (start 76.4225 121.5675) (end 76.4225 123.777814) (width 0.109) (layer "In6.Cu") (net 210))
  (segment (start 76.089587 115.74) (end 75.999956 115.750098) (width 0.109) (layer "In6.Cu") (net 210))
  (segment (start 75.838447 115.827877) (end 75.774667 115.891657) (width 0.109) (layer "In6.Cu") (net 210))
  (segment (start 77.120576 119.275051) (end 77.093262 119.302365) (width 0.109) (layer "In6.Cu") (net 210))
  (segment (start 77.024095 116.599324) (end 77.060555 116.612082) (width 0.109) (layer "In6.Cu") (net 210))
  (segment (start 75.68679 120.942797) (end 75.68679 120.992202) (width 0.109) (layer "In6.Cu") (net 210))
  (segment (start 75.999956 115.750098) (end 75.91482 115.779889) (width 0.109) (layer "In6.Cu") (net 210))
  (segment (start 75.68679 116.192202) (end 75.696888 116.281833) (width 0.109) (layer "In6.Cu") (net 210))
  (segment (start 77.141128 116.692655) (end 77.153886 116.729115) (width 0.109) (layer "In6.Cu") (net 210))
  (segment (start 75.91482 120.579889) (end 75.838447 120.627877) (width 0.109) (layer "In6.Cu") (net 210))
  (segment (start 77.120576 120.259948) (end 77.141128 120.292655) (width 0.109) (layer "In6.Cu") (net 210))
  (segment (start 75.838447 121.307122) (end 75.91482 121.35511) (width 0.109) (layer "In6.Cu") (net 210))
  (segment (start 75.838447 118.907122) (end 75.91482 118.95511) (width 0.109) (layer "In6.Cu") (net 210))
  (segment (start 75.68679 117.342797) (end 75.68679 117.392202) (width 0.109) (layer "In6.Cu") (net 210))
  (segment (start 75.838447 120.107122) (end 75.91482 120.15511) (width 0.109) (layer "In6.Cu") (net 210))
  (segment (start 75.91482 118.179889) (end 75.838447 118.227877) (width 0.109) (layer "In6.Cu") (net 210))
  (segment (start 75.696888 118.453166) (end 75.68679 118.542797) (width 0.109) (layer "In6.Cu") (net 210))
  (segment (start 77.060555 119.322917) (end 77.024095 119.335675) (width 0.109) (layer "In6.Cu") (net 210))
  (segment (start 76.98571 118.995) (end 77.024095 118.999324) (width 0.109) (layer "In6.Cu") (net 210))
  (segment (start 75.68679 120.992202) (end 75.696888 121.081833) (width 0.109) (layer "In6.Cu") (net 210))
  (segment (start 91.1715 134.8535) (end 91.1715 134.774) (width 0.109) (layer "In6.Cu") (net 210))
  (segment (start 76.98571 118.14) (end 76.089587 118.14) (width 0.109) (layer "In6.Cu") (net 210))
  (segment (start 77.153886 119.205884) (end 77.141128 119.242344) (width 0.109) (layer "In6.Cu") (net 210))
  (segment (start 75.91482 120.15511) (end 75.999956 120.184901) (width 0.109) (layer "In6.Cu") (net 210))
  (segment (start 76.384865 121.459948) (end 76.405417 121.492655) (width 0.109) (layer "In6.Cu") (net 210))
  (segment (start 77.093262 117.832634) (end 77.120576 117.859948) (width 0.109) (layer "In6.Cu") (net 210))
  (segment (start 77.060555 116.612082) (end 77.093262 116.632634) (width 0.109) (layer "In6.Cu") (net 210))
  (segment (start 77.153886 116.805884) (end 77.141128 116.842344) (width 0.109) (layer "In6.Cu") (net 210))
  (segment (start 75.91482 119.379889) (end 75.838447 119.427877) (width 0.109) (layer "In6.Cu") (net 210))
  (segment (start 77.093262 119.302365) (end 77.060555 119.322917) (width 0.109) (layer "In6.Cu") (net 210))
  (segment (start 75.726679 121.166969) (end 75.774667 121.243342) (width 0.109) (layer "In6.Cu") (net 210))
  (segment (start 76.4225 123.777814) (end 84.4475 131.802814) (width 0.109) (layer "In6.Cu") (net 210))
  (segment (start 75.726679 118.766969) (end 75.774667 118.843342) (width 0.109) (layer "In6.Cu") (net 210))
  (segment (start 76.357551 115.702365) (end 76.324844 115.722917) (width 0.109) (layer "In6.Cu") (net 210))
  (segment (start 76.089587 116.94) (end 75.999956 116.950098) (width 0.109) (layer "In6.Cu") (net 210))
  (segment (start 87.732186 135.4875) (end 90.7375 135.4875) (width 0.109) (layer "In6.Cu") (net 210))
  (segment (start 75.91482 115.779889) (end 75.838447 115.827877) (width 0.109) (layer "In6.Cu") (net 210))
  (segment (start 75.696888 121.081833) (end 75.726679 121.166969) (width 0.109) (layer "In6.Cu") (net 210))
  (segment (start 76.98571 117.795) (end 77.024095 117.799324) (width 0.109) (layer "In6.Cu") (net 210))
  (segment (start 75.774667 119.491657) (end 75.726679 119.56803) (width 0.109) (layer "In6.Cu") (net 210))
  (segment (start 76.089587 117.795) (end 76.98571 117.795) (width 0.109) (layer "In6.Cu") (net 210))
  (segment (start 77.153886 118.005884) (end 77.141128 118.042344) (width 0.109) (layer "In6.Cu") (net 210))
  (segment (start 76.405417 115.642344) (end 76.384865 115.675051) (width 0.109) (layer "In6.Cu") (net 210))
  (segment (start 77.141128 118.042344) (end 77.120576 118.075051) (width 0.109) (layer "In6.Cu") (net 210))
  (segment (start 77.141128 117.892655) (end 77.153886 117.929115) (width 0.109) (layer "In6.Cu") (net 210))
  (segment (start 77.060555 117.812082) (end 77.093262 117.832634) (width 0.109) (layer "In6.Cu") (net 210))
  (segment (start 75.774667 117.091657) (end 75.726679 117.16803) (width 0.109) (layer "In6.Cu") (net 210))
  (segment (start 75.696888 119.881833) (end 75.726679 119.966969) (width 0.109) (layer "In6.Cu") (net 210))
  (segment (start 75.999956 120.550098) (end 75.91482 120.579889) (width 0.109) (layer "In6.Cu") (net 210))
  (segment (start 75.838447 117.027877) (end 75.774667 117.091657) (width 0.109) (layer "In6.Cu") (net 210))
  (segment (start 75.774667 120.691657) (end 75.726679 120.76803) (width 0.109) (layer "In6.Cu") (net 210))
  (segment (start 75.91482 117.75511) (end 75.999956 117.784901) (width 0.109) (layer "In6.Cu") (net 210))
  (segment (start 75.726679 117.566969) (end 75.774667 117.643342) (width 0.109) (layer "In6.Cu") (net 210))
  (segment (start 77.060555 118.122917) (end 77.024095 118.135675) (width 0.109) (layer "In6.Cu") (net 210))
  (segment (start 75.774667 118.291657) (end 75.726679 118.36803) (width 0.109) (layer "In6.Cu") (net 210))
  (segment (start 77.153886 120.329115) (end 77.15821 120.3675) (width 0.109) (layer "In6.Cu") (net 210))
  (segment (start 76.089587 118.995) (end 76.98571 118.995) (width 0.109) (layer "In6.Cu") (net 210))
  (segment (start 75.68679 118.592202) (end 75.696888 118.681833) (width 0.109) (layer "In6.Cu") (net 210))
  (segment (start 76.089587 118.14) (end 75.999956 118.150098) (width 0.109) (layer "In6.Cu") (net 210))
  (segment (start 76.25 115.74) (end 76.089587 115.74) (width 0.109) (layer "In6.Cu") (net 210))
  (segment (start 77.093262 116.632634) (end 77.120576 116.659948) (width 0.109) (layer "In6.Cu") (net 210))
  (segment (start 76.98571 116.595) (end 77.024095 116.599324) (width 0.109) (layer "In6.Cu") (net 210))
  (segment (start 75.999956 117.784901) (end 76.089587 117.795) (width 0.109) (layer "In6.Cu") (net 210))
  (segment (start 75.999956 120.184901) (end 76.089587 120.195) (width 0.109) (layer "In6.Cu") (net 210))
  (segment (start 84.4475 131.802814) (end 84.4475 132.202814) (width 0.109) (layer "In6.Cu") (net 210))
  (segment (start 75.999956 119.350098) (end 75.91482 119.379889) (width 0.109) (layer "In6.Cu") (net 210))
  (segment (start 76.98571 120.54) (end 76.089587 120.54) (width 0.109) (layer "In6.Cu") (net 210))
  (segment (start 77.060555 120.212082) (end 77.093262 120.232634) (width 0.109) (layer "In6.Cu") (net 210))
  (segment (start 75.726679 116.366969) (end 75.774667 116.443342) (width 0.109) (layer "In6.Cu") (net 210))
  (segment (start 75.999956 118.150098) (end 75.91482 118.179889) (width 0.109) (layer "In6.Cu") (net 210))
  (segment (start 77.060555 120.522917) (end 77.024095 120.535675) (width 0.109) (layer "In6.Cu") (net 210))
  (segment (start 77.060555 119.012082) (end 77.093262 119.032634) (width 0.109) (layer "In6.Cu") (net 210))
  (segment (start 76.089587 119.34) (end 75.999956 119.350098) (width 0.109) (layer "In6.Cu") (net 210))
  (segment (start 77.153886 120.405884) (end 77.141128 120.442344) (width 0.109) (layer "In6.Cu") (net 210))
  (segment (start 75.838447 117.707122) (end 75.91482 117.75511) (width 0.109) (layer "In6.Cu") (net 210))
  (segment (start 75.726679 118.36803) (end 75.696888 118.453166) (width 0.109) (layer "In6.Cu") (net 210))
  (segment (start 76.089587 120.195) (end 76.98571 120.195) (width 0.109) (layer "In6.Cu") (net 210))
  (segment (start 75.91482 116.979889) (end 75.838447 117.027877) (width 0.109) (layer "In6.Cu") (net 210))
  (segment (start 77.141128 119.092655) (end 77.153886 119.129115) (width 0.109) (layer "In6.Cu") (net 210))
  (segment (start 75.68679 118.542797) (end 75.68679 118.592202) (width 0.109) (layer "In6.Cu") (net 210))
  (segment (start 77.153886 119.129115) (end 77.15821 119.1675) (width 0.109) (layer "In6.Cu") (net 210))
  (segment (start 76.288384 115.735675) (end 76.25 115.74) (width 0.109) (layer "In6.Cu") (net 210))
  (segment (start 75.726679 120.76803) (end 75.696888 120.853166) (width 0.109) (layer "In6.Cu") (net 210))
  (segment (start 77.060555 116.922917) (end 77.024095 116.935675) (width 0.109) (layer "In6.Cu") (net 210))
  (segment (start 77.093262 119.032634) (end 77.120576 119.059948) (width 0.109) (layer "In6.Cu") (net 210))
  (segment (start 75.68679 119.792202) (end 75.696888 119.881833) (width 0.109) (layer "In6.Cu") (net 210))
  (segment (start 75.726679 115.96803) (end 75.696888 116.053166) (width 0.109) (layer "In6.Cu") (net 210))
  (segment (start 77.15821 120.3675) (end 77.153886 120.405884) (width 0.109) (layer "In6.Cu") (net 210))
  (segment (start 77.153886 116.729115) (end 77.15821 116.7675) (width 0.109) (layer "In6.Cu") (net 210))
  (segment (start 77.024095 120.199324) (end 77.060555 120.212082) (width 0.109) (layer "In6.Cu") (net 210))
  (segment (start 76.089587 121.395) (end 76.25 121.395) (width 0.109) (layer "In6.Cu") (net 210))
  (segment (start 90.7375 135.4875) (end 91.05 135.175) (width 0.109) (layer "In6.Cu") (net 210))
  (segment (start 77.024095 118.999324) (end 77.060555 119.012082) (width 0.109) (layer "In6.Cu") (net 210))
  (segment (start 76.98571 116.94) (end 76.089587 116.94) (width 0.109) (layer "In6.Cu") (net 210))
  (segment (start 76.418175 115.605884) (end 76.405417 115.642344) (width 0.109) (layer "In6.Cu") (net 210))
  (segment (start 77.093262 118.102365) (end 77.060555 118.122917) (width 0.109) (layer "In6.Cu") (net 210))
  (segment (start 75.999956 121.384901) (end 76.089587 121.395) (width 0.109) (layer "In6.Cu") (net 210))
  (segment (start 77.093262 116.902365) (end 77.060555 116.922917) (width 0.109) (layer "In6.Cu") (net 210))
  (segment (start 77.120576 117.859948) (end 77.141128 117.892655) (width 0.109) (layer "In6.Cu") (net 210))
  (segment (start 76.98571 120.195) (end 77.024095 120.199324) (width 0.109) (layer "In6.Cu") (net 210))
  (segment (start 76.089587 120.54) (end 75.999956 120.550098) (width 0.109) (layer "In6.Cu") (net 210))
  (segment (start 77.336205 107.743481) (end 76.1025 108.977186) (width 0.109) (layer "In6.Cu") (net 210))
  (segment (start 84.4475 132.202814) (end 87.732186 135.4875) (width 0.109) (layer "In6.Cu") (net 210))
  (segment (start 75.774667 120.043342) (end 75.838447 120.107122) (width 0.109) (layer "In6.Cu") (net 210))
  (segment (start 77.141128 120.442344) (end 77.120576 120.475051) (width 0.109) (layer "In6.Cu") (net 210))
  (segment (start 75.838447 120.627877) (end 75.774667 120.691657) (width 0.109) (layer "In6.Cu") (net 210))
  (segment (start 77.15821 119.1675) (end 77.153886 119.205884) (width 0.109) (layer "In6.Cu") (net 210))
  (segment (start 79.1045 107.743481) (end 77.336205 107.743481) (width 0.109) (layer "In6.Cu") (net 210))
  (segment (start 76.4225 115.5675) (end 76.418175 115.605884) (width 0.109) (layer "In6.Cu") (net 210))
  (segment (start 77.120576 116.659948) (end 77.141128 116.692655) (width 0.109) (layer "In6.Cu") (net 210))
  (segment (start 75.838447 119.427877) (end 75.774667 119.491657) (width 0.109) (layer "In6.Cu") (net 210))
  (segment (start 77.024095 119.335675) (end 76.98571 119.34) (width 0.109) (layer "In6.Cu") (net 210))
  (segment (start 77.024095 118.135675) (end 76.98571 118.14) (width 0.109) (layer "In6.Cu") (net 210))
  (segment (start 77.15821 116.7675) (end 77.153886 116.805884) (width 0.109) (layer "In6.Cu") (net 210))
  (segment (start 75.774667 121.243342) (end 75.838447 121.307122) (width 0.109) (layer "In6.Cu") (net 210))
  (segment (start 75.91482 121.35511) (end 75.999956 121.384901) (width 0.109) (layer "In6.Cu") (net 210))
  (segment (start 77.120576 116.875051) (end 77.093262 116.902365) (width 0.109) (layer "In6.Cu") (net 210))
  (segment (start 76.324844 121.412082) (end 76.357551 121.432634) (width 0.109) (layer "In6.Cu") (net 210))
  (segment (start 76.384865 115.675051) (end 76.357551 115.702365) (width 0.109) (layer "In6.Cu") (net 210))
  (segment (start 77.15821 117.9675) (end 77.153886 118.005884) (width 0.109) (layer "In6.Cu") (net 210))
  (segment (start 77.141128 116.842344) (end 77.120576 116.875051) (width 0.109) (layer "In6.Cu") (net 210))
  (segment (start 77.024095 120.535675) (end 76.98571 120.54) (width 0.109) (layer "In6.Cu") (net 210))
  (segment (start 76.418175 121.529115) (end 76.4225 121.5675) (width 0.109) (layer "In6.Cu") (net 210))
  (segment (start 75.68679 119.742797) (end 75.68679 119.792202) (width 0.109) (layer "In6.Cu") (net 210))
  (segment (start 75.91482 118.95511) (end 75.999956 118.984901) (width 0.109) (layer "In6.Cu") (net 210))
  (segment (start 76.1025 114.707814) (end 76.4225 115.027814) (width 0.109) (layer "In6.Cu") (net 210))
  (segment (start 77.120576 120.475051) (end 77.093262 120.502365) (width 0.109) (layer "In6.Cu") (net 210))
  (segment (start 75.774667 118.843342) (end 75.838447 118.907122) (width 0.109) (layer "In6.Cu") (net 210))
  (segment (start 77.141128 120.292655) (end 77.153886 120.329115) (width 0.109) (layer "In6.Cu") (net 210))
  (segment (start 76.405417 121.492655) (end 76.418175 121.529115) (width 0.109) (layer "In6.Cu") (net 210))
  (segment (start 75.696888 119.653166) (end 75.68679 119.742797) (width 0.109) (layer "In6.Cu") (net 210))
  (segment (start 76.25 121.395) (end 76.288384 121.399324) (width 0.109) (layer "In6.Cu") (net 210))
  (segment (start 75.696888 116.281833) (end 75.726679 116.366969) (width 0.109) (layer "In6.Cu") (net 210))
  (segment (start 76.98571 119.34) (end 76.089587 119.34) (width 0.109) (layer "In6.Cu") (net 210))
  (segment (start 76.324844 115.722917) (end 76.288384 115.735675) (width 0.109) (layer "In6.Cu") (net 210))
  (segment (start 77.120576 118.075051) (end 77.093262 118.102365) (width 0.109) (layer "In6.Cu") (net 210))
  (segment (start 76.357551 121.432634) (end 76.384865 121.459948) (width 0.109) (layer "In6.Cu") (net 210))
  (segment (start 75.999956 116.584901) (end 76.089587 116.595) (width 0.109) (layer "In6.Cu") (net 210))
  (segment (start 75.696888 116.053166) (end 75.68679 116.142797) (width 0.109) (layer "In6.Cu") (net 210))
  (segment (start 76.089587 116.595) (end 76.98571 116.595) (width 0.109) (layer "In6.Cu") (net 210))
  (segment (start 76.288384 121.399324) (end 76.324844 121.412082) (width 0.109) (layer "In6.Cu") (net 210))
  (segment (start 76.1025 108.977186) (end 76.1025 114.707814) (width 0.109) (layer "In6.Cu") (net 210))
  (segment (start 77.024095 116.935675) (end 76.98571 116.94) (width 0.109) (layer "In6.Cu") (net 210))
  (segment (start 75.696888 117.253166) (end 75.68679 117.342797) (width 0.109) (layer "In6.Cu") (net 210))
  (segment (start 75.774667 116.443342) (end 75.838447 116.507122) (width 0.109) (layer "In6.Cu") (net 210))
  (segment (start 75.999956 118.984901) (end 76.089587 118.995) (width 0.109) (layer "In6.Cu") (net 210))
  (segment (start 75.774667 117.643342) (end 75.838447 117.707122) (width 0.109) (layer "In6.Cu") (net 210))
  (segment (start 75.68679 117.392202) (end 75.696888 117.481833) (width 0.109) (layer "In6.Cu") (net 210))
  (segment (start 75.838447 118.227877) (end 75.774667 118.291657) (width 0.109) (layer "In6.Cu") (net 210))
  (segment (start 77.120576 119.059948) (end 77.141128 119.092655) (width 0.109) (layer "In6.Cu") (net 210))
  (segment (start 75.726679 119.56803) (end 75.696888 119.653166) (width 0.109) (layer "In6.Cu") (net 210))
  (segment (start 91.05 135.175) (end 91.05 134.975) (width 0.109) (layer "In6.Cu") (net 210))
  (segment (start 91.05 134.975) (end 91.1715 134.8535) (width 0.109) (layer "In6.Cu") (net 210))
  (segment (start 76.4225 115.027814) (end 76.4225 115.5675) (width 0.109) (layer "In6.Cu") (net 210))
  (segment (start 75.838447 116.507122) (end 75.91482 116.55511) (width 0.109) (layer "In6.Cu") (net 210))
  (segment (start 81.389 109.311) (end 81.178288 109.311) (width 0.182) (layer "B.Cu") (net 210))
  (segment (start 80.814 108.946712) (end 80.814 108.296712) (width 0.182) (layer "B.Cu") (net 210))
  (segment (start 81.45 109.25) (end 81.389 109.311) (width 0.182) (layer "B.Cu") (net 210))
  (segment (start 79.384 107.681981) (end 79.275 107.572981) (width 0.182) (layer "B.Cu") (net 210))
  (segment (start 80.814 108.296712) (end 80.199269 107.681981) (width 0.182) (layer "B.Cu") (net 210))
  (segment (start 80.199269 107.681981) (end 79.384 107.681981) (width 0.182) (layer "B.Cu") (net 210))
  (segment (start 81.178288 109.311) (end 80.814 108.946712) (width 0.182) (layer "B.Cu") (net 210))
  (segment (start 81.9 109.25) (end 81.45 109.25) (width 0.182) (layer "B.Cu") (net 210))
  (segment (start 90.7865 134.449) (end 91.1715 134.138999) (width 0.182) (layer "F.Cu") (net 211))
  (via (at 91.1715 134.138999) (size 0.45) (drill 0.1) (layers "F.Cu" "B.Cu") (net 211))
  (via (at 79.275 108.168982) (size 0.45) (drill 0.1) (layers "F.Cu" "B.Cu") (net 211))
  (segment (start 77.373321 116.966969) (end 77.325333 117.043342) (width 0.109) (layer "In6.Cu") (net 211))
  (segment (start 75.958872 119.842344) (end 75.979424 119.875051) (width 0.109) (layer "In6.Cu") (net 211))
  (segment (start 75.979424 120.859948) (end 75.958872 120.892655) (width 0.109) (layer "In6.Cu") (net 211))
  (segment (start 77.18518 117.579889) (end 77.261553 117.627877) (width 0.109) (layer "In6.Cu") (net 211))
  (segment (start 75.958872 116.092655) (end 75.946114 116.129115) (width 0.109) (layer "In6.Cu") (net 211))
  (segment (start 76.63761 115.766969) (end 76.589622 115.843342) (width 0.109) (layer "In6.Cu") (net 211))
  (segment (start 75.946114 116.205884) (end 75.958872 116.242344) (width 0.109) (layer "In6.Cu") (net 211))
  (segment (start 77.010413 117.54) (end 77.100044 117.550098) (width 0.109) (layer "In6.Cu") (net 211))
  (segment (start 76.075905 118.399324) (end 76.039445 118.412082) (width 0.109) (layer "In6.Cu") (net 211))
  (segment (start 75.958872 121.042344) (end 75.979424 121.075051) (width 0.109) (layer "In6.Cu") (net 211))
  (segment (start 77.09628 108.444113) (end 77.06899 108.437886) (width 0.109) (layer "In6.Cu") (net 211))
  (segment (start 75.946114 120.929115) (end 75.94179 120.9675) (width 0.109) (layer "In6.Cu") (net 211))
  (segment (start 77.403112 119.053166) (end 77.41321 119.142797) (width 0.109) (layer "In6.Cu") (net 211))
  (segment (start 76.715151 123.494316) (end 76.699316 123.510151) (width 0.109) (layer "In6.Cu") (net 211))
  (segment (start 77.204296 108.51712) (end 77.179077 108.504975) (width 0.109) (layer "In6.Cu") (net 211))
  (segment (start 77.010413 118.74) (end 77.100044 118.750098) (width 0.109) (layer "In6.Cu") (net 211))
  (segment (start 77.373321 118.166969) (end 77.325333 118.243342) (width 0.109) (layer "In6.Cu") (net 211))
  (segment (start 77.284333 108.22254) (end 77.290561 108.24983) (width 0.109) (layer "In6.Cu") (net 211))
  (segment (start 76.525842 115.907122) (end 76.449469 115.95511) (width 0.109) (layer "In6.Cu") (net 211))
  (segment (start 76.11429 119.94) (end 77.010413 119.94) (width 0.109) (layer "In6.Cu") (net 211))
  (segment (start 75.979424 118.675051) (end 76.006738 118.702365) (width 0.109) (layer "In6.Cu") (net 211))
  (segment (start 76.6775 123.1545) (end 76.680007 123.176752) (width 0.109) (layer "In6.Cu") (net 211))
  (segment (start 76.820888 123.462596) (end 76.799752 123.469992) (width 0.109) (layer "In6.Cu") (net 211))
  (segment (start 75.946114 121.005884) (end 75.958872 121.042344) (width 0.109) (layer "In6.Cu") (net 211))
  (segment (start 76.006738 118.702365) (end 76.039445 118.722917) (width 0.109) (layer "In6.Cu") (net 211))
  (segment (start 77.403112 120.481833) (end 77.373321 120.566969) (width 0.109) (layer "In6.Cu") (net 211))
  (segment (start 75.958872 117.442344) (end 75.979424 117.475051) (width 0.109) (layer "In6.Cu") (net 211))
  (segment (start 77.403112 120.253166) (end 77.41321 120.342797) (width 0.109) (layer "In6.Cu") (net 211))
  (segment (start 76.075905 120.799324) (end 76.039445 120.812082) (width 0.109) (layer "In6.Cu") (net 211))
  (segment (start 76.867596 123.311111) (end 76.874992 123.332247) (width 0.109) (layer "In6.Cu") (net 211))
  (segment (start 76.039445 117.212082) (end 76.006738 117.232634) (width 0.109) (layer "In6.Cu") (net 211))
  (segment (start 75.979424 119.875051) (end 76.006738 119.902365) (width 0.109) (layer "In6.Cu") (net 211))
  (segment (start 77.441833 107.998481) (end 77.320157 108.120157) (width 0.109) (layer "In6.Cu") (net 211))
  (segment (start 76.6775 123.672188) (end 84.7025 131.697186) (width 0.109) (layer "In6.Cu") (net 211))
  (segment (start 76.680007 123.176752) (end 76.687403 123.197888) (width 0.109) (layer "In6.Cu") (net 211))
  (segment (start 77.302706 108.275049) (end 77.320158 108.296933) (width 0.109) (layer "In6.Cu") (net 211))
  (segment (start 79.1045 107.998481) (end 77.441833 107.998481) (width 0.109) (layer "In6.Cu") (net 211))
  (segment (start 76.6775 115.592202) (end 76.667401 115.681833) (width 0.109) (layer "In6.Cu") (net 211))
  (segment (start 77.373321 116.56803) (end 77.403112 116.653166) (width 0.109) (layer "In6.Cu") (net 211))
  (segment (start 76.039445 119.922917) (end 76.075905 119.935675) (width 0.109) (layer "In6.Cu") (net 211))
  (segment (start 77.33397 108.310745) (end 77.351422 108.332629) (width 0.109) (layer "In6.Cu") (net 211))
  (segment (start 76.006738 121.102365) (end 76.039445 121.122917) (width 0.109) (layer "In6.Cu") (net 211))
  (segment (start 76.006738 120.832634) (end 75.979424 120.859948) (width 0.109) (layer "In6.Cu") (net 211))
  (segment (start 76.449469 115.95511) (end 76.364333 115.984901) (width 0.109) (layer "In6.Cu") (net 211))
  (segment (start 76.006738 117.232634) (end 75.979424 117.259948) (width 0.109) (layer "In6.Cu") (net 211))
  (segment (start 77.18518 120.75511) (end 77.100044 120.784901) (width 0.109) (layer "In6.Cu") (net 211))
  (segment (start 77.284332 108.19455) (end 77.284333 108.22254) (width 0.109) (layer "In6.Cu") (net 211))
  (segment (start 77.351422 108.465637) (end 77.33397 108.487521) (width 0.109) (layer "In6.Cu") (net 211))
  (segment (start 77.325333 117.043342) (end 77.261553 117.107122) (width 0.109) (layer "In6.Cu") (net 211))
  (segment (start 76.11429 117.195) (end 76.075905 117.199324) (width 0.109) (layer "In6.Cu") (net 211))
  (segment (start 76.006738 119.632634) (end 75.979424 119.659948) (width 0.109) (layer "In6.Cu") (net 211))
  (segment (start 76.039445 119.612082) (end 76.006738 119.632634) (width 0.109) (layer "In6.Cu") (net 211))
  (segment (start 76.3575 109.082814) (end 76.3575 114.602186) (width 0.109) (layer "In6.Cu") (net 211))
  (segment (start 77.373321 119.366969) (end 77.325333 119.443342) (width 0.109) (layer "In6.Cu") (net 211))
  (segment (start 77.403112 117.853166) (end 77.41321 117.942797) (width 0.109) (layer "In6.Cu") (net 211))
  (segment (start 79.275 108.168981) (end 79.1045 107.998481) (width 0.109) (layer "In6.Cu") (net 211))
  (segment (start 75.979424 118.459948) (end 75.958872 118.492655) (width 0.109) (layer "In6.Cu") (net 211))
  (segment (start 76.63761 121.36803) (end 76.667401 121.453166) (width 0.109) (layer "In6.Cu") (net 211))
  (segment (start 76.075905 121.135675) (end 76.11429 121.14) (width 0.109) (layer "In6.Cu") (net 211))
  (segment (start 76.11429 117.54) (end 77.010413 117.54) (width 0.109) (layer "In6.Cu") (net 211))
  (segment (start 77.290561 108.16726) (end 77.284332 108.19455) (width 0.109) (layer "In6.Cu") (net 211))
  (segment (start 77.325333 118.891657) (end 77.373321 118.96803) (width 0.109) (layer "In6.Cu") (net 211))
  (segment (start 90.5675 135.2325) (end 90.76525 135.03475) (width 0.109) (layer "In6.Cu") (net 211))
  (segment (start 77.325333 118.243342) (end 77.261553 118.307122) (width 0.109) (layer "In6.Cu") (net 211))
  (segment (start 77.261553 118.307122) (end 77.18518 118.35511) (width 0.109) (layer "In6.Cu") (net 211))
  (segment (start 76.274702 115.995) (end 76.11429 115.995) (width 0.109) (layer "In6.Cu") (net 211))
  (segment (start 77.286866 108.51712) (end 77.259578 108.523347) (width 0.109) (layer "In6.Cu") (net 211))
  (segment (start 77.100044 117.184901) (end 77.010413 117.195) (width 0.109) (layer "In6.Cu") (net 211))
  (segment (start 84.7025 132.097186) (end 87.837814 135.2325) (width 0.109) (layer "In6.Cu") (net 211))
  (segment (start 75.94179 118.5675) (end 75.946114 118.605884) (width 0.109) (layer "In6.Cu") (net 211))
  (segment (start 76.855683 123.292151) (end 76.867596 123.311111) (width 0.109) (layer "In6.Cu") (net 211))
  (segment (start 76.6775 121.542797) (end 76.6775 123.1545) (width 0.109) (layer "In6.Cu") (net 211))
  (segment (start 76.820888 123.264403) (end 76.839848 123.276316) (width 0.109) (layer "In6.Cu") (net 211))
  (segment (start 76.11429 116.34) (end 77.010413 116.34) (width 0.109) (layer "In6.Cu") (net 211))
  (segment (start 76.699316 123.216848) (end 76.715151 123.232683) (width 0.109) (layer "In6.Cu") (net 211))
  (segment (start 76.734111 123.482403) (end 76.715151 123.494316) (width 0.109) (layer "In6.Cu") (net 211))
  (segment (start 76.839848 123.450683) (end 76.820888 123.462596) (width 0.109) (layer "In6.Cu") (net 211))
  (segment (start 77.41321 117.942797) (end 77.41321 117.992202) (width 0.109) (layer "In6.Cu") (net 211))
  (segment (start 76.11429 120.795) (end 76.075905 120.799324) (width 0.109) (layer "In6.Cu") (net 211))
  (segment (start 77.33397 108.487521) (end 77.312085 108.504975) (width 0.109) (layer "In6.Cu") (net 211))
  (segment (start 77.040998 108.437886) (end 77.01371 108.444113) (width 0.109) (layer "In6.Cu") (net 211))
  (segment (start 87.837814 135.2325) (end 90.5675 135.2325) (width 0.109) (layer "In6.Cu") (net 211))
  (segment (start 77.302706 108.142041) (end 77.290561 108.16726) (width 0.109) (layer "In6.Cu") (net 211))
  (segment (start 75.94179 116.1675) (end 75.946114 116.205884) (width 0.109) (layer "In6.Cu") (net 211))
  (segment (start 77.259578 108.523347) (end 77.231586 108.523348) (width 0.109) (layer "In6.Cu") (net 211))
  (segment (start 76.699316 123.510151) (end 76.687403 123.529111) (width 0.109) (layer "In6.Cu") (net 211))
  (segment (start 76.006738 119.902365) (end 76.039445 119.922917) (width 0.109) (layer "In6.Cu") (net 211))
  (segment (start 77.100044 117.550098) (end 77.18518 117.579889) (width 0.109) (layer "In6.Cu") (net 211))
  (segment (start 77.100044 119.950098) (end 77.18518 119.979889) (width 0.109) (layer "In6.Cu") (net 211))
  (segment (start 77.369794 108.41313) (end 77.363567 108.440418) (width 0.109) (layer "In6.Cu") (net 211))
  (segment (start 77.403112 116.653166) (end 77.41321 116.742797) (width 0.109) (layer "In6.Cu") (net 211))
  (segment (start 77.010413 117.195) (end 76.11429 117.195) (width 0.109) (layer "In6.Cu") (net 211))
  (segment (start 76.006738 118.432634) (end 75.979424 118.459948) (width 0.109) (layer "In6.Cu") (net 211))
  (segment (start 77.261553 117.627877) (end 77.325333 117.691657) (width 0.109) (layer "In6.Cu") (net 211))
  (segment (start 77.325333 120.091657) (end 77.373321 120.16803) (width 0.109) (layer "In6.Cu") (net 211))
  (segment (start 77.325333 117.691657) (end 77.373321 117.76803) (width 0.109) (layer "In6.Cu") (net 211))
  (segment (start 77.06899 108.437886) (end 77.040998 108.437886) (width 0.109) (layer "In6.Cu") (net 211))
  (segment (start 77.41321 119.192202) (end 77.403112 119.281833) (width 0.109) (layer "In6.Cu") (net 211))
  (segment (start 77.18518 116.379889) (end 77.261553 116.427877) (width 0.109) (layer "In6.Cu") (net 211))
  (segment (start 76.839848 123.276316) (end 76.855683 123.292151) (width 0.109) (layer "In6.Cu") (net 211))
  (segment (start 77.231586 108.523348) (end 77.204296 108.51712) (width 0.109) (layer "In6.Cu") (net 211))
  (segment (start 76.6775 123.5725) (end 76.6775 123.672188) (width 0.109) (layer "In6.Cu") (net 211))
  (segment (start 75.94179 117.3675) (end 75.946114 117.405884) (width 0.109) (layer "In6.Cu") (net 211))
  (segment (start 77.18518 118.35511) (end 77.100044 118.384901) (width 0.109) (layer "In6.Cu") (net 211))
  (segment (start 75.979424 116.059948) (end 75.958872 116.092655) (width 0.109) (layer "In6.Cu") (net 211))
  (segment (start 77.010413 118.395) (end 76.11429 118.395) (width 0.109) (layer "In6.Cu") (net 211))
  (segment (start 77.100044 118.750098) (end 77.18518 118.779889) (width 0.109) (layer "In6.Cu") (net 211))
  (segment (start 76.274702 121.14) (end 76.364333 121.150098) (width 0.109) (layer "In6.Cu") (net 211))
  (segment (start 76.006738 116.032634) (end 75.979424 116.059948) (width 0.109) (layer "In6.Cu") (net 211))
  (segment (start 76.039445 116.012082) (end 76.006738 116.032634) (width 0.109) (layer "In6.Cu") (net 211))
  (segment (start 77.261553 120.707122) (end 77.18518 120.75511) (width 0.109) (layer "In6.Cu") (net 211))
  (segment (start 91.14625 134.138999) (end 91.1715 134.138999) (width 0.109) (layer "In6.Cu") (net 211))
  (segment (start 75.979424 119.659948) (end 75.958872 119.692655) (width 0.109) (layer "In6.Cu") (net 211))
  (segment (start 76.11429 118.74) (end 77.010413 118.74) (width 0.109) (layer "In6.Cu") (net 211))
  (segment (start 76.715151 123.232683) (end 76.734111 123.244596) (width 0.109) (layer "In6.Cu") (net 211))
  (segment (start 76.075905 115.999324) (end 76.039445 116.012082) (width 0.109) (layer "In6.Cu") (net 211))
  (segment (start 76.589622 121.291657) (end 76.63761 121.36803) (width 0.109) (layer "In6.Cu") (net 211))
  (segment (start 77.41321 116.792202) (end 77.403112 116.881833) (width 0.109) (layer "In6.Cu") (net 211))
  (segment (start 76.075905 119.599324) (end 76.039445 119.612082) (width 0.109) (layer "In6.Cu") (net 211))
  (segment (start 84.7025 131.697186) (end 84.7025 132.097186) (width 0.109) (layer "In6.Cu") (net 211))
  (segment (start 77.41321 119.142797) (end 77.41321 119.192202) (width 0.109) (layer "In6.Cu") (net 211))
  (segment (start 76.449469 121.179889) (end 76.525842 121.227877) (width 0.109) (layer "In6.Cu") (net 211))
  (segment (start 77.41321 117.992202) (end 77.403112 118.081833) (width 0.109) (layer "In6.Cu") (net 211))
  (segment (start 75.946114 117.405884) (end 75.958872 117.442344) (width 0.109) (layer "In6.Cu") (net 211))
  (segment (start 77.325333 120.643342) (end 77.261553 120.707122) (width 0.109) (layer "In6.Cu") (net 211))
  (segment (start 75.958872 117.292655) (end 75.946114 117.329115) (width 0.109) (layer "In6.Cu") (net 211))
  (segment (start 77.373321 120.16803) (end 77.403112 120.253166) (width 0.109) (layer "In6.Cu") (net 211))
  (segment (start 77.403112 118.081833) (end 77.373321 118.166969) (width 0.109) (layer "In6.Cu") (net 211))
  (segment (start 75.979424 117.475051) (end 76.006738 117.502365) (width 0.109) (layer "In6.Cu") (net 211))
  (segment (start 77.010413 116.34) (end 77.100044 116.350098) (width 0.109) (layer "In6.Cu") (net 211))
  (segment (start 76.687403 123.197888) (end 76.699316 123.216848) (width 0.109) (layer "In6.Cu") (net 211))
  (segment (start 76.039445 118.412082) (end 76.006738 118.432634) (width 0.109) (layer "In6.Cu") (net 211))
  (segment (start 77.261553 120.027877) (end 77.325333 120.091657) (width 0.109) (layer "In6.Cu") (net 211))
  (segment (start 77.100044 118.384901) (end 77.010413 118.395) (width 0.109) (layer "In6.Cu") (net 211))
  (segment (start 76.3575 109.082814) (end 76.966605 108.47371) (width 0.109) (layer "In6.Cu") (net 211))
  (segment (start 77.18518 119.979889) (end 77.261553 120.027877) (width 0.109) (layer "In6.Cu") (net 211))
  (segment (start 77.351422 108.332629) (end 77.363567 108.357848) (width 0.109) (layer "In6.Cu") (net 211))
  (segment (start 75.979424 121.075051) (end 76.006738 121.102365) (width 0.109) (layer "In6.Cu") (net 211))
  (segment (start 77.157194 108.487521) (end 77.143383 108.47371) (width 0.109) (layer "In6.Cu") (net 211))
  (segment (start 76.364333 121.150098) (end 76.449469 121.179889) (width 0.109) (layer "In6.Cu") (net 211))
  (segment (start 76.799752 123.257007) (end 76.820888 123.264403) (width 0.109) (layer "In6.Cu") (net 211))
  (segment (start 77.18518 117.15511) (end 77.100044 117.184901) (width 0.109) (layer "In6.Cu") (net 211))
  (segment (start 76.667401 115.681833) (end 76.63761 115.766969) (width 0.109) (layer "In6.Cu") (net 211))
  (segment (start 76.039445 116.322917) (end 76.075905 116.335675) (width 0.109) (layer "In6.Cu") (net 211))
  (segment (start 76.589622 115.843342) (end 76.525842 115.907122) (width 0.109) (layer "In6.Cu") (net 211))
  (segment (start 77.010413 119.595) (end 76.11429 119.595) (width 0.109) (layer "In6.Cu") (net 211))
  (segment (start 77.369794 108.385138) (end 77.369794 108.41313) (width 0.109) (layer "In6.Cu") (net 211))
  (segment (start 76.006738 117.502365) (end 76.039445 117.522917) (width 0.109) (layer "In6.Cu") (net 211))
  (segment (start 77.18518 119.55511) (end 77.100044 119.584901) (width 0.109) (layer "In6.Cu") (net 211))
  (segment (start 77.403112 119.281833) (end 77.373321 119.366969) (width 0.109) (layer "In6.Cu") (net 211))
  (segment (start 76.11429 119.595) (end 76.075905 119.599324) (width 0.109) (layer "In6.Cu") (net 211))
  (segment (start 77.100044 116.350098) (end 77.18518 116.379889) (width 0.109) (layer "In6.Cu") (net 211))
  (segment (start 77.010413 120.795) (end 76.11429 120.795) (width 0.109) (layer "In6.Cu") (net 211))
  (segment (start 77.41321 120.342797) (end 77.41321 120.392202) (width 0.109) (layer "In6.Cu") (net 211))
  (segment (start 76.6775 114.922186) (end 76.6775 115.592202) (width 0.109) (layer "In6.Cu") (net 211))
  (segment (start 77.373321 118.96803) (end 77.403112 119.053166) (width 0.109) (layer "In6.Cu") (net 211))
  (segment (start 77.261553 117.107122) (end 77.18518 117.15511) (width 0.109) (layer "In6.Cu") (net 211))
  (segment (start 76.755247 123.475007) (end 76.734111 123.482403) (width 0.109) (layer "In6.Cu") (net 211))
  (segment (start 77.100044 120.784901) (end 77.010413 120.795) (width 0.109) (layer "In6.Cu") (net 211))
  (segment (start 77.373321 120.566969) (end 77.325333 120.643342) (width 0.109) (layer "In6.Cu") (net 211))
  (segment (start 77.01371 108.444113) (end 76.988491 108.456258) (width 0.109) (layer "In6.Cu") (net 211))
  (segment (start 75.94179 119.7675) (end 75.946114 119.805884) (width 0.109) (layer "In6.Cu") (net 211))
  (segment (start 77.261553 119.507122) (end 77.18518 119.55511) (width 0.109) (layer "In6.Cu") (net 211))
  (segment (start 76.039445 121.122917) (end 76.075905 121.135675) (width 0.109) (layer "In6.Cu") (net 211))
  (segment (start 77.121499 108.456258) (end 77.09628 108.444113) (width 0.109) (layer "In6.Cu") (net 211))
  (segment (start 75.958872 119.692655) (end 75.946114 119.729115) (width 0.109) (layer "In6.Cu") (net 211))
  (segment (start 77.312085 108.504975) (end 77.286866 108.51712) (width 0.109) (layer "In6.Cu") (net 211))
  (segment (start 75.94179 120.9675) (end 75.946114 121.005884) (width 0.109) (layer "In6.Cu") (net 211))
  (segment (start 77.320157 108.120157) (end 77.302706 108.142041) (width 0.109) (layer "In6.Cu") (net 211))
  (segment (start 77.100044 119.584901) (end 77.010413 119.595) (width 0.109) (layer "In6.Cu") (net 211))
  (segment (start 75.946114 118.529115) (end 75.94179 118.5675) (width 0.109) (layer "In6.Cu") (net 211))
  (segment (start 76.11429 118.395) (end 76.075905 118.399324) (width 0.109) (layer "In6.Cu") (net 211))
  (segment (start 76.11429 121.14) (end 76.274702 121.14) (width 0.109) (layer "In6.Cu") (net 211))
  (segment (start 75.946114 119.805884) (end 75.958872 119.842344) (width 0.109) (layer "In6.Cu") (net 211))
  (segment (start 77.290561 108.24983) (end 77.302706 108.275049) (width 0.109) (layer "In6.Cu") (net 211))
  (segment (start 77.261553 118.827877) (end 77.325333 118.891657) (width 0.109) (layer "In6.Cu") (net 211))
  (segment (start 76.039445 118.722917) (end 76.075905 118.735675) (width 0.109) (layer "In6.Cu") (net 211))
  (segment (start 75.946114 119.729115) (end 75.94179 119.7675) (width 0.109) (layer "In6.Cu") (net 211))
  (segment (start 76.734111 123.244596) (end 76.755247 123.251992) (width 0.109) (layer "In6.Cu") (net 211))
  (segment (start 77.18518 118.779889) (end 77.261553 118.827877) (width 0.109) (layer "In6.Cu") (net 211))
  (segment (start 77.41321 116.742797) (end 77.41321 116.792202) (width 0.109) (layer "In6.Cu") (net 211))
  (segment (start 76.075905 117.535675) (end 76.11429 117.54) (width 0.109) (layer "In6.Cu") (net 211))
  (segment (start 79.275 108.168982) (end 79.275 108.168981) (width 0.109) (layer "In6.Cu") (net 211))
  (segment (start 76.855683 123.434848) (end 76.839848 123.450683) (width 0.109) (layer "In6.Cu") (net 211))
  (segment (start 77.363567 108.357848) (end 77.369794 108.385138) (width 0.109) (layer "In6.Cu") (net 211))
  (segment (start 76.755247 123.251992) (end 76.799752 123.257007) (width 0.109) (layer "In6.Cu") (net 211))
  (segment (start 75.946114 118.605884) (end 75.958872 118.642344) (width 0.109) (layer "In6.Cu") (net 211))
  (segment (start 75.958872 118.642344) (end 75.979424 118.675051) (width 0.109) (layer "In6.Cu") (net 211))
  (segment (start 75.946114 117.329115) (end 75.94179 117.3675) (width 0.109) (layer "In6.Cu") (net 211))
  (segment (start 75.946114 116.129115) (end 75.94179 116.1675) (width 0.109) (layer "In6.Cu") (net 211))
  (segment (start 77.373321 117.76803) (end 77.403112 117.853166) (width 0.109) (layer "In6.Cu") (net 211))
  (segment (start 77.363567 108.440418) (end 77.351422 108.465637) (width 0.109) (layer "In6.Cu") (net 211))
  (segment (start 76.680007 123.550247) (end 76.6775 123.5725) (width 0.109) (layer "In6.Cu") (net 211))
  (segment (start 90.76525 135.03475) (end 90.76525 134.519999) (width 0.109) (layer "In6.Cu") (net 211))
  (segment (start 75.958872 118.492655) (end 75.946114 118.529115) (width 0.109) (layer "In6.Cu") (net 211))
  (segment (start 76.075905 117.199324) (end 76.039445 117.212082) (width 0.109) (layer "In6.Cu") (net 211))
  (segment (start 76.039445 117.522917) (end 76.075905 117.535675) (width 0.109) (layer "In6.Cu") (net 211))
  (segment (start 75.979424 117.259948) (end 75.958872 117.292655) (width 0.109) (layer "In6.Cu") (net 211))
  (segment (start 75.958872 120.892655) (end 75.946114 120.929115) (width 0.109) (layer "In6.Cu") (net 211))
  (segment (start 77.261553 116.427877) (end 77.325333 116.491657) (width 0.109) (layer "In6.Cu") (net 211))
  (segment (start 76.874992 123.394752) (end 76.867596 123.415888) (width 0.109) (layer "In6.Cu") (net 211))
  (segment (start 76.075905 119.935675) (end 76.11429 119.94) (width 0.109) (layer "In6.Cu") (net 211))
  (segment (start 77.010413 119.94) (end 77.100044 119.950098) (width 0.109) (layer "In6.Cu") (net 211))
  (segment (start 77.320158 108.296933) (end 77.33397 108.310745) (width 0.109) (layer "In6.Cu") (net 211))
  (segment (start 76.006738 116.302365) (end 76.039445 116.322917) (width 0.109) (layer "In6.Cu") (net 211))
  (segment (start 76.075905 118.735675) (end 76.11429 118.74) (width 0.109) (layer "In6.Cu") (net 211))
  (segment (start 76.039445 120.812082) (end 76.006738 120.832634) (width 0.109) (layer "In6.Cu") (net 211))
  (segment (start 76.799752 123.469992) (end 76.755247 123.475007) (width 0.109) (layer "In6.Cu") (net 211))
  (segment (start 76.525842 121.227877) (end 76.589622 121.291657) (width 0.109) (layer "In6.Cu") (net 211))
  (segment (start 76.075905 116.335675) (end 76.11429 116.34) (width 0.109) (layer "In6.Cu") (net 211))
  (segment (start 77.325333 116.491657) (end 77.373321 116.56803) (width 0.109) (layer "In6.Cu") (net 211))
  (segment (start 77.403112 116.881833) (end 77.373321 116.966969) (width 0.109) (layer "In6.Cu") (net 211))
  (segment (start 76.874992 123.332247) (end 76.8775 123.3545) (width 0.109) (layer "In6.Cu") (net 211))
  (segment (start 77.325333 119.443342) (end 77.261553 119.507122) (width 0.109) (layer "In6.Cu") (net 211))
  (segment (start 75.979424 116.275051) (end 76.006738 116.302365) (width 0.109) (layer "In6.Cu") (net 211))
  (segment (start 77.179077 108.504975) (end 77.157194 108.487521) (width 0.109) (layer "In6.Cu") (net 211))
  (segment (start 76.988491 108.456258) (end 76.966605 108.47371) (width 0.109) (layer "In6.Cu") (net 211))
  (segment (start 76.11429 115.995) (end 76.075905 115.999324) (width 0.109) (layer "In6.Cu") (net 211))
  (segment (start 76.364333 115.984901) (end 76.274702 115.995) (width 0.109) (layer "In6.Cu") (net 211))
  (segment (start 76.867596 123.415888) (end 76.855683 123.434848) (width 0.109) (layer "In6.Cu") (net 211))
  (segment (start 76.687403 123.529111) (end 76.680007 123.550247) (width 0.109) (layer "In6.Cu") (net 211))
  (segment (start 76.667401 121.453166) (end 76.6775 121.542797) (width 0.109) (layer "In6.Cu") (net 211))
  (segment (start 77.143383 108.47371) (end 77.121499 108.456258) (width 0.109) (layer "In6.Cu") (net 211))
  (segment (start 76.8775 123.3725) (end 76.874992 123.394752) (width 0.109) (layer "In6.Cu") (net 211))
  (segment (start 75.958872 116.242344) (end 75.979424 116.275051) (width 0.109) (layer "In6.Cu") (net 211))
  (segment (start 76.8775 123.3545) (end 76.8775 123.3725) (width 0.109) (layer "In6.Cu") (net 211))
  (segment (start 77.41321 120.392202) (end 77.403112 120.481833) (width 0.109) (layer "In6.Cu") (net 211))
  (segment (start 90.76525 134.519999) (end 91.14625 134.138999) (width 0.109) (layer "In6.Cu") (net 211))
  (segment (start 76.3575 114.602186) (end 76.6775 114.922186) (width 0.109) (layer "In6.Cu") (net 211))
  (segment (start 80.436 109.103288) (end 80.436 108.453288) (width 0.182) (layer "B.Cu") (net 211))
  (segment (start 81.9 109.75) (end 81.45 109.75) (width 0.182) (layer "B.Cu") (net 211))
  (segment (start 81.45 109.75) (end 81.389 109.689) (width 0.182) (layer "B.Cu") (net 211))
  (segment (start 80.042693 108.059981) (end 79.384 108.059981) (width 0.182) (layer "B.Cu") (net 211))
  (segment (start 81.021712 109.689) (end 80.436 109.103288) (width 0.182) (layer "B.Cu") (net 211))
  (segment (start 79.275 108.168981) (end 79.275 108.168982) (width 0.182) (layer "B.Cu") (net 211))
  (segment (start 80.436 108.453288) (end 80.042693 108.059981) (width 0.182) (layer "B.Cu") (net 211))
  (segment (start 79.384 108.059981) (end 79.275 108.168981) (width 0.182) (layer "B.Cu") (net 211))
  (segment (start 81.389 109.689) (end 81.021712 109.689) (width 0.182) (layer "B.Cu") (net 211))
  (segment (start 89.4415 132.854) (end 89.8265 132.544) (width 0.182) (layer "F.Cu") (net 212))
  (via (at 79.125 108.998532) (size 0.45) (drill 0.1) (layers "F.Cu" "B.Cu") (net 212))
  (via (at 89.4415 132.854) (size 0.45) (drill 0.1) (layers "F.Cu" "B.Cu") (net 212))
  (segment (start 80.801242 130.340564) (end 80.88726 130.29914) (width 0.109) (layer "In4.Cu") (net 212))
  (segment (start 81.058767 128.855884) (end 81.031194 128.890462) (width 0.109) (layer "In4.Cu") (net 212))
  (segment (start 79.220298 126.807264) (end 79.239486 126.847109) (width 0.109) (layer "In4.Cu") (net 212))
  (segment (start 79.788928 129.442574) (end 79.882007 129.421329) (width 0.109) (layer "In4.Cu") (net 212))
  (segment (start 79.832652 127.691921) (end 79.867229 127.664346) (width 0.109) (layer "In4.Cu") (net 212))
  (segment (start 77.410857 125.051756) (end 77.410858 125.095982) (width 0.109) (layer "In4.Cu") (net 212))
  (segment (start 78.111723 125.796847) (end 78.155949 125.796847) (width 0.109) (layer "In4.Cu") (net 212))
  (segment (start 79.487287 128.037287) (end 79.832652 127.691921) (width 0.109) (layer "In4.Cu") (net 212))
  (segment (start 77.236714 124.877612) (end 77.279831 124.887453) (width 0.109) (layer "In4.Cu") (net 212))
  (segment (start 79.514357 129.379905) (end 79.600375 129.421329) (width 0.109) (layer "In4.Cu") (net 212))
  (segment (start 81.095949 130.105568) (end 81.130526 130.077994) (width 0.109) (layer "In4.Cu") (net 212))
  (segment (start 80.961904 130.239613) (end 80.980393 130.221125) (width 0.109) (layer "In4.Cu") (net 212))
  (segment (start 78.423975 128.289522) (end 78.483501 128.364166) (width 0.109) (layer "In4.Cu") (net 212))
  (segment (start 78.028759 125.825876) (end 78.068606 125.806688) (width 0.109) (layer "In4.Cu") (net 212))
  (segment (start 79.34321 128.755089) (end 79.301786 128.841107) (width 0.109) (layer "In4.Cu") (net 212))
  (segment (start 80.262445 130.127992) (end 80.321971 130.202636) (width 0.109) (layer "In4.Cu") (net 212))
  (segment (start 77.319676 124.906641) (end 77.354253 124.934216) (width 0.109) (layer "In4.Cu") (net 212))
  (segment (start 78.520478 128.401143) (end 78.595122 128.46067) (width 0.109) (layer "In4.Cu") (net 212))
  (segment (start 76.645031 125.92274) (end 77.354254 125.213522) (width 0.109) (layer "In4.Cu") (net 212))
  (segment (start 78.483501 127.76121) (end 79.192724 127.051992) (width 0.109) (layer "In4.Cu") (net 212))
  (segment (start 76.93575 126.684869) (end 77.031223 126.684869) (width 0.109) (layer "In4.Cu") (net 212))
  (segment (start 78.361306 128.110425) (end 78.382551 128.203504) (width 0.109) (layer "In4.Cu") (net 212))
  (segment (start 81.375254 130.105568) (end 83.933686 132.664) (width 0.109) (layer "In4.Cu") (net 212))
  (segment (start 78.913417 126.772686) (end 78.947994 126.745111) (width 0.109) (layer "In4.Cu") (net 212))
  (segment (start 75.3725 111.497186) (end 75.372501 124.102815) (width 0.109) (layer "In4.Cu") (net 212))
  (segment (start 78.483501 127.76121) (end 78.423975 127.835854) (width 0.109) (layer "In4.Cu") (net 212))
  (segment (start 80.826311 128.564393) (end 80.869428 128.554552) (width 0.109) (layer "In4.Cu") (net 212))
  (segment (start 81.213489 130.048964) (end 81.257714 130.048964) (width 0.109) (layer "In4.Cu") (net 212))
  (segment (start 77.564266 126.841975) (end 78.273489 126.132757) (width 0.109) (layer "In4.Cu") (net 212))
  (segment (start 78.962772 128.502094) (end 79.04879 128.46067) (width 0.109) (layer "In4.Cu") (net 212))
  (segment (start 76.365729 125.643438) (end 76.384218 125.62495) (width 0.109) (layer "In4.Cu") (net 212))
  (segment (start 76.645031 125.92274) (end 76.585505 125.997384) (width 0.109) (layer "In4.Cu") (net 212))
  (segment (start 77.303453 126.544185) (end 77.738973 126.10866) (width 0.109) (layer "In4.Cu") (net 212))
  (segment (start 80.996616 128.583581) (end 81.031193 128.611156) (width 0.109) (layer "In4.Cu") (net 212))
  (segment (start 78.361306 128.014952) (end 78.361306 128.110425) (width 0.109) (layer "In4.Cu") (net 212))
  (segment (start 80.168562 127.809461) (end 80.168563 127.853687) (width 0.109) (layer "In4.Cu") (net 212))
  (segment (start 78.068606 125.806688) (end 78.111723 125.796847) (width 0.109) (layer "In4.Cu") (net 212))
  (segment (start 89.2515 132.664) (end 89.4415 132.854) (width 0.109) (layer "In4.Cu") (net 212))
  (segment (start 79.192723 126.772686) (end 79.220298 126.807264) (width 0.109) (layer "In4.Cu") (net 212))
  (segment (start 80.077381 127.664346) (end 80.111958 127.691921) (width 0.109) (layer "In4.Cu") (net 212))
  (segment (start 78.330092 125.970991) (end 78.330093 126.015217) (width 0.109) (layer "In4.Cu") (net 212))
  (segment (start 81.257714 130.048964) (end 81.300831 130.058805) (width 0.109) (layer "In4.Cu") (net 212))
  (segment (start 77.50474 126.916619) (end 77.463316 127.002637) (width 0.109) (layer "In4.Cu") (net 212))
  (segment (start 77.738973 126.10866) (end 77.994182 125.853451) (width 0.109) (layer "In4.Cu") (net 212))
  (segment (start 77.994182 125.853451) (end 78.028759 125.825876) (width 0.109) (layer "In4.Cu") (net 212))
  (segment (start 80.061158 129.30189) (end 80.496678 128.866365) (width 0.109) (layer "In4.Cu") (net 212))
  (segment (start 80.168563 127.853687) (end 80.158722 127.896804) (width 0.109) (layer "In4.Cu") (net 212))
  (segment (start 79.600375 129.421329) (end 79.693455 129.442574) (width 0.109) (layer "In4.Cu") (net 212))
  (segment (start 76.756652 126.6222) (end 76.84267 126.663624) (width 0.109) (layer "In4.Cu") (net 212))
  (segment (start 78.9545 109.169032) (end 77.700654 109.169032) (width 0.109) (layer "In4.Cu") (net 212))
  (segment (start 78.222688 127.46342) (end 78.658208 127.027895) (width 0.109) (layer "In4.Cu") (net 212))
  (segment (start 75.603601 125.35272) (end 75.624846 125.445799) (width 0.109) (layer "In4.Cu") (net 212))
  (segment (start 80.158721 127.766344) (end 80.168562 127.809461) (width 0.109) (layer "In4.Cu") (net 212))
  (segment (start 77.031223 126.684869) (end 77.124302 126.663624) (width 0.109) (layer "In4.Cu") (net 212))
  (segment (start 79.882007 129.421329) (end 79.968025 129.379905) (width 0.109) (layer "In4.Cu") (net 212))
  (segment (start 79.249328 126.934452) (end 79.239487 126.977569) (width 0.109) (layer "In4.Cu") (net 212))
  (segment (start 78.043537 127.582859) (end 78.129555 127.541435) (width 0.109) (layer "In4.Cu") (net 212))
  (segment (start 75.66627 125.078149) (end 75.624846 125.164167) (width 0.109) (layer "In4.Cu") (net 212))
  (segment (start 77.074947 124.934216) (end 77.109524 124.906641) (width 0.109) (layer "In4.Cu") (net 212))
  (segment (start 81.130526 130.077994) (end 81.170372 130.058805) (width 0.109) (layer "In4.Cu") (net 212))
  (segment (start 76.544081 126.083402) (end 76.522836 126.176482) (width 0.109) (layer "In4.Cu") (net 212))
  (segment (start 77.21032 126.6222) (end 77.284964 126.562673) (width 0.109) (layer "In4.Cu") (net 212))
  (segment (start 78.987841 126.725923) (end 79.030958 126.716082) (width 0.109) (layer "In4.Cu") (net 212))
  (segment (start 79.950193 127.635317) (end 79.994419 127.635317) (width 0.109) (layer "In4.Cu") (net 212))
  (segment (start 78.77422 128.523339) (end 78.869693 128.523339) (width 0.109) (layer "In4.Cu") (net 212))
  (segment (start 75.923435 125.744389) (end 76.016515 125.765634) (width 0.109) (layer "In4.Cu") (net 212))
  (segment (start 79.402736 128.680445) (end 80.111959 127.971227) (width 0.109) (layer "In4.Cu") (net 212))
  (segment (start 81.340677 130.077994) (end 81.375254 130.105568) (width 0.109) (layer "In4.Cu") (net 212))
  (segment (start 81.300831 130.058805) (end 81.340677 130.077994) (width 0.109) (layer "In4.Cu") (net 212))
  (segment (start 79.030958 126.716082) (end 79.075184 126.716082) (width 0.109) (layer "In4.Cu") (net 212))
  (segment (start 75.906605 124.795038) (end 75.887416 124.834884) (width 0.109) (layer "In4.Cu") (net 212))
  (segment (start 77.463316 127.284269) (end 77.50474 127.370287) (width 0.109) (layer "In4.Cu") (net 212))
  (segment (start 78.129555 127.541435) (end 78.204199 127.481908) (width 0.109) (layer "In4.Cu") (net 212))
  (segment (start 81.087798 128.772922) (end 81.077957 128.816039) (width 0.109) (layer "In4.Cu") (net 212))
  (segment (start 76.522836 126.271955) (end 76.544081 126.365034) (width 0.109) (layer "In4.Cu") (net 212))
  (segment (start 83.933686 132.664) (end 89.2515 132.664) (width 0.109) (layer "In4.Cu") (net 212))
  (segment (start 78.869693 128.523339) (end 78.962772 128.502094) (width 0.109) (layer "In4.Cu") (net 212))
  (segment (start 75.859842 124.590155) (end 75.887416 124.624732) (width 0.109) (layer "In4.Cu") (net 212))
  (segment (start 77.675887 127.541435) (end 77.761905 127.582859) (width 0.109) (layer "In4.Cu") (net 212))
  (segment (start 78.658208 127.027895) (end 78.913417 126.772686) (width 0.109) (layer "In4.Cu") (net 212))
  (segment (start 77.354253 124.934216) (end 77.381828 124.968794) (width 0.109) (layer "In4.Cu") (net 212))
  (segment (start 75.916446 124.751921) (end 75.906605 124.795038) (width 0.109) (layer "In4.Cu") (net 212))
  (segment (start 76.291085 125.702965) (end 76.365729 125.643438) (width 0.109) (layer "In4.Cu") (net 212))
  (segment (start 75.624846 125.164167) (end 75.603601 125.257247) (width 0.109) (layer "In4.Cu") (net 212))
  (segment (start 79.402736 128.680445) (end 79.34321 128.755089) (width 0.109) (layer "In4.Cu") (net 212))
  (segment (start 75.859842 124.869461) (end 75.725797 125.003505) (width 0.109) (layer "In4.Cu") (net 212))
  (segment (start 81.077957 128.816039) (end 81.058767 128.855884) (width 0.109) (layer "In4.Cu") (net 212))
  (segment (start 77.124302 126.663624) (end 77.21032 126.6222) (width 0.109) (layer "In4.Cu") (net 212))
  (segment (start 78.595122 128.46067) (end 78.68114 128.502094) (width 0.109) (layer "In4.Cu") (net 212))
  (segment (start 80.61269 130.361809) (end 80.708163 130.361809) (width 0.109) (layer "In4.Cu") (net 212))
  (segment (start 80.980393 130.221125) (end 81.095949 130.105568) (width 0.109) (layer "In4.Cu") (net 212))
  (segment (start 80.956771 128.564393) (end 80.996616 128.583581) (width 0.109) (layer "In4.Cu") (net 212))
  (segment (start 75.725797 125.003505) (end 75.66627 125.078149) (width 0.109) (layer "In4.Cu") (net 212))
  (segment (start 75.66627 125.531817) (end 75.725797 125.606461) (width 0.109) (layer "In4.Cu") (net 212))
  (segment (start 81.077956 128.685579) (end 81.087797 128.728696) (width 0.109) (layer "In4.Cu") (net 212))
  (segment (start 75.372501 124.102815) (end 75.859842 124.590155) (width 0.109) (layer "In4.Cu") (net 212))
  (segment (start 80.321971 129.59968) (end 81.031194 128.890462) (width 0.109) (layer "In4.Cu") (net 212))
  (segment (start 77.564266 126.841975) (end 77.50474 126.916619) (width 0.109) (layer "In4.Cu") (net 212))
  (segment (start 77.149371 124.887453) (end 77.192488 124.877612) (width 0.109) (layer "In4.Cu") (net 212))
  (segment (start 80.321971 130.202636) (end 80.358948 130.239613) (width 0.109) (layer "In4.Cu") (net 212))
  (segment (start 75.837417 125.702965) (end 75.923435 125.744389) (width 0.109) (layer "In4.Cu") (net 212))
  (segment (start 80.751887 128.611156) (end 80.786464 128.583581) (width 0.109) (layer "In4.Cu") (net 212))
  (segment (start 77.761905 127.582859) (end 77.854985 127.604104) (width 0.109) (layer "In4.Cu") (net 212))
  (segment (start 81.031193 128.611156) (end 81.058768 128.645734) (width 0.109) (layer "In4.Cu") (net 212))
  (segment (start 80.111958 127.691921) (end 80.139533 127.726499) (width 0.109) (layer "In4.Cu") (net 212))
  (segment (start 78.483501 128.364166) (end 78.520478 128.401143) (width 0.109) (layer "In4.Cu") (net 212))
  (segment (start 80.496678 128.866365) (end 80.751887 128.611156) (width 0.109) (layer "In4.Cu") (net 212))
  (segment (start 80.199776 129.948895) (end 80.221021 130.041974) (width 0.109) (layer "In4.Cu") (net 212))
  (segment (start 77.601243 127.481908) (end 77.675887 127.541435) (width 0.109) (layer "In4.Cu") (net 212))
  (segment (start 80.042669 129.320378) (end 80.061158 129.30189) (width 0.109) (layer "In4.Cu") (net 212))
  (segment (start 78.330093 126.015217) (end 78.320252 126.058334) (width 0.109) (layer "In4.Cu") (net 212))
  (segment (start 80.913654 128.554552) (end 80.956771 128.564393) (width 0.109) (layer "In4.Cu") (net 212))
  (segment (start 78.204199 127.481908) (end 78.222688 127.46342) (width 0.109) (layer "In4.Cu") (net 212))
  (segment (start 75.887416 124.624732) (end 75.906605 124.664578) (width 0.109) (layer "In4.Cu") (net 212))
  (segment (start 76.205067 125.744389) (end 76.291085 125.702965) (width 0.109) (layer "In4.Cu") (net 212))
  (segment (start 79.907076 127.645158) (end 79.950193 127.635317) (width 0.109) (layer "In4.Cu") (net 212))
  (segment (start 79.141923 128.382655) (end 79.487287 128.037287) (width 0.109) (layer "In4.Cu") (net 212))
  (segment (start 77.284964 126.562673) (end 77.303453 126.544185) (width 0.109) (layer "In4.Cu") (net 212))
  (segment (start 77.381827 125.178944) (end 77.354254 125.213522) (width 0.109) (layer "In4.Cu") (net 212))
  (segment (start 75.762773 125.643438) (end 75.837417 125.702965) (width 0.109) (layer "In4.Cu") (net 212))
  (segment (start 77.109524 124.906641) (end 77.149371 124.887453) (width 0.109) (layer "In4.Cu") (net 212))
  (segment (start 76.544081 126.365034) (end 76.585505 126.451052) (width 0.109) (layer "In4.Cu") (net 212))
  (segment (start 78.155949 125.796847) (end 78.199066 125.806688) (width 0.109) (layer "In4.Cu") (net 212))
  (segment (start 76.84267 126.663624) (end 76.93575 126.684869) (width 0.109) (layer "In4.Cu") (net 212))
  (segment (start 79.301786 128.841107) (end 79.280541 128.934187) (width 0.109) (layer "In4.Cu") (net 212))
  (segment (start 80.433592 130.29914) (end 80.51961 130.340564) (width 0.109) (layer "In4.Cu") (net 212))
  (segment (start 78.301062 126.098179) (end 78.273489 126.132757) (width 0.109) (layer "In4.Cu") (net 212))
  (segment (start 79.04879 128.46067) (end 79.123434 128.401143) (width 0.109) (layer "In4.Cu") (net 212))
  (segment (start 79.280541 128.934187) (end 79.280541 129.02966) (width 0.109) (layer "In4.Cu") (net 212))
  (segment (start 79.123434 128.401143) (end 79.141923 128.382655) (width 0.109) (layer "In4.Cu") (net 212))
  (segment (start 80.139533 127.726499) (end 80.158721 127.766344) (width 0.109) (layer "In4.Cu") (net 212))
  (segment (start 75.887416 124.834884) (end 75.859842 124.869461) (width 0.109) (layer "In4.Cu") (net 212))
  (segment (start 77.442071 127.095717) (end 77.442071 127.19119) (width 0.109) (layer "In4.Cu") (net 212))
  (segment (start 77.463316 127.002637) (end 77.442071 127.095717) (width 0.109) (layer "In4.Cu") (net 212))
  (segment (start 78.301063 125.888029) (end 78.320251 125.927874) (width 0.109) (layer "In4.Cu") (net 212))
  (segment (start 77.279831 124.887453) (end 77.319676 124.906641) (width 0.109) (layer "In4.Cu") (net 212))
  (segment (start 78.199066 125.806688) (end 78.238911 125.825876) (width 0.109) (layer "In4.Cu") (net 212))
  (segment (start 78.68114 128.502094) (end 78.77422 128.523339) (width 0.109) (layer "In4.Cu") (net 212))
  (segment (start 80.158722 127.896804) (end 80.139532 127.936649) (width 0.109) (layer "In4.Cu") (net 212))
  (segment (start 79.34321 129.208757) (end 79.402736 129.283401) (width 0.109) (layer "In4.Cu") (net 212))
  (segment (start 78.382551 127.921872) (end 78.361306 128.014952) (width 0.109) (layer "In4.Cu") (net 212))
  (segment (start 78.273488 125.853451) (end 78.301063 125.888029) (width 0.109) (layer "In4.Cu") (net 212))
  (segment (start 80.199776 129.853422) (end 80.199776 129.948895) (width 0.109) (layer "In4.Cu") (net 212))
  (segment (start 79.239487 126.977569) (end 79.220297 127.017414) (width 0.109) (layer "In4.Cu") (net 212))
  (segment (start 77.192488 124.877612) (end 77.236714 124.877612) (width 0.109) (layer "In4.Cu") (net 212))
  (segment (start 77.564266 127.444931) (end 77.601243 127.481908) (width 0.109) (layer "In4.Cu") (net 212))
  (segment (start 80.88726 130.29914) (end 80.961904 130.239613) (width 0.109) (layer "In4.Cu") (net 212))
  (segment (start 81.087797 128.728696) (end 81.087798 128.772922) (width 0.109) (layer "In4.Cu") (net 212))
  (segment (start 78.423975 127.835854) (end 78.382551 127.921872) (width 0.109) (layer "In4.Cu") (net 212))
  (segment (start 78.320252 126.058334) (end 78.301062 126.098179) (width 0.109) (layer "In4.Cu") (net 212))
  (segment (start 75.725797 125.606461) (end 75.762773 125.643438) (width 0.109) (layer "In4.Cu") (net 212))
  (segment (start 76.016515 125.765634) (end 76.111988 125.765634) (width 0.109) (layer "In4.Cu") (net 212))
  (segment (start 79.220297 127.017414) (end 79.192724 127.051992) (width 0.109) (layer "In4.Cu") (net 212))
  (segment (start 79.968025 129.379905) (end 80.042669 129.320378) (width 0.109) (layer "In4.Cu") (net 212))
  (segment (start 78.238911 125.825876) (end 78.273488 125.853451) (width 0.109) (layer "In4.Cu") (net 212))
  (segment (start 80.869428 128.554552) (end 80.913654 128.554552) (width 0.109) (layer "In4.Cu") (net 212))
  (segment (start 77.950458 127.604104) (end 78.043537 127.582859) (width 0.109) (layer "In4.Cu") (net 212))
  (segment (start 77.700654 109.169032) (end 75.3725 111.497186) (width 0.109) (layer "In4.Cu") (net 212))
  (segment (start 80.221021 129.760342) (end 80.199776 129.853422) (width 0.109) (layer "In4.Cu") (net 212))
  (segment (start 80.262445 129.674324) (end 80.221021 129.760342) (width 0.109) (layer "In4.Cu") (net 212))
  (segment (start 79.994419 127.635317) (end 80.037536 127.645158) (width 0.109) (layer "In4.Cu") (net 212))
  (segment (start 78.382551 128.203504) (end 78.423975 128.289522) (width 0.109) (layer "In4.Cu") (net 212))
  (segment (start 80.037536 127.645158) (end 80.077381 127.664346) (width 0.109) (layer "In4.Cu") (net 212))
  (segment (start 76.384218 125.62495) (end 77.074947 124.934216) (width 0.109) (layer "In4.Cu") (net 212))
  (segment (start 79.249327 126.890226) (end 79.249328 126.934452) (width 0.109) (layer "In4.Cu") (net 212))
  (segment (start 75.916446 124.707695) (end 75.916446 124.751921) (width 0.109) (layer "In4.Cu") (net 212))
  (segment (start 79.301786 129.122739) (end 79.34321 129.208757) (width 0.109) (layer "In4.Cu") (net 212))
  (segment (start 76.522836 126.176482) (end 76.522836 126.271955) (width 0.109) (layer "In4.Cu") (net 212))
  (segment (start 76.645031 126.525696) (end 76.682008 126.562673) (width 0.109) (layer "In4.Cu") (net 212))
  (segment (start 81.058768 128.645734) (end 81.077956 128.685579) (width 0.109) (layer "In4.Cu") (net 212))
  (segment (start 76.682008 126.562673) (end 76.756652 126.6222) (width 0.109) (layer "In4.Cu") (net 212))
  (segment (start 79.867229 127.664346) (end 79.907076 127.645158) (width 0.109) (layer "In4.Cu") (net 212))
  (segment (start 77.401017 125.139099) (end 77.381827 125.178944) (width 0.109) (layer "In4.Cu") (net 212))
  (segment (start 79.125 108.998532) (end 78.9545 109.169032) (width 0.109) (layer "In4.Cu") (net 212))
  (segment (start 75.603601 125.257247) (end 75.603601 125.35272) (width 0.109) (layer "In4.Cu") (net 212))
  (segment (start 80.358948 130.239613) (end 80.433592 130.29914) (width 0.109) (layer "In4.Cu") (net 212))
  (segment (start 80.708163 130.361809) (end 80.801242 130.340564) (width 0.109) (layer "In4.Cu") (net 212))
  (segment (start 79.158146 126.745111) (end 79.192723 126.772686) (width 0.109) (layer "In4.Cu") (net 212))
  (segment (start 79.075184 126.716082) (end 79.118301 126.725923) (width 0.109) (layer "In4.Cu") (net 212))
  (segment (start 78.947994 126.745111) (end 78.987841 126.725923) (width 0.109) (layer "In4.Cu") (net 212))
  (segment (start 80.321971 129.59968) (end 80.262445 129.674324) (width 0.109) (layer "In4.Cu") (net 212))
  (segment (start 76.585505 125.997384) (end 76.544081 126.083402) (width 0.109) (layer "In4.Cu") (net 212))
  (segment (start 77.50474 127.370287) (end 77.564266 127.444931) (width 0.109) (layer "In4.Cu") (net 212))
  (segment (start 78.320251 125.927874) (end 78.330092 125.970991) (width 0.109) (layer "In4.Cu") (net 212))
  (segment (start 77.410858 125.095982) (end 77.401017 125.139099) (width 0.109) (layer "In4.Cu") (net 212))
  (segment (start 80.139532 127.936649) (end 80.111959 127.971227) (width 0.109) (layer "In4.Cu") (net 212))
  (segment (start 76.585505 126.451052) (end 76.645031 126.525696) (width 0.109) (layer "In4.Cu") (net 212))
  (segment (start 79.280541 129.02966) (end 79.301786 129.122739) (width 0.109) (layer "In4.Cu") (net 212))
  (segment (start 81.170372 130.058805) (end 81.213489 130.048964) (width 0.109) (layer "In4.Cu") (net 212))
  (segment (start 79.693455 129.442574) (end 79.788928 129.442574) (width 0.109) (layer "In4.Cu") (net 212))
  (segment (start 77.381828 124.968794) (end 77.401016 125.008639) (width 0.109) (layer "In4.Cu") (net 212))
  (segment (start 75.906605 124.664578) (end 75.916446 124.707695) (width 0.109) (layer "In4.Cu") (net 212))
  (segment (start 80.221021 130.041974) (end 80.262445 130.127992) (width 0.109) (layer "In4.Cu") (net 212))
  (segment (start 75.624846 125.445799) (end 75.66627 125.531817) (width 0.109) (layer "In4.Cu") (net 212))
  (segment (start 77.442071 127.19119) (end 77.463316 127.284269) (width 0.109) (layer "In4.Cu") (net 212))
  (segment (start 79.239486 126.847109) (end 79.249327 126.890226) (width 0.109) (layer "In4.Cu") (net 212))
  (segment (start 79.439713 129.320378) (end 79.514357 129.379905) (width 0.109) (layer "In4.Cu") (net 212))
  (segment (start 79.402736 129.283401) (end 79.439713 129.320378) (width 0.109) (layer "In4.Cu") (net 212))
  (segment (start 77.854985 127.604104) (end 77.950458 127.604104) (width 0.109) (layer "In4.Cu") (net 212))
  (segment (start 80.51961 130.340564) (end 80.61269 130.361809) (width 0.109) (layer "In4.Cu") (net 212))
  (segment (start 76.111988 125.765634) (end 76.205067 125.744389) (width 0.109) (layer "In4.Cu") (net 212))
  (segment (start 77.401016 125.008639) (end 77.410857 125.051756) (width 0.109) (layer "In4.Cu") (net 212))
  (segment (start 80.786464 128.583581) (end 80.826311 128.564393) (width 0.109) (layer "In4.Cu") (net 212))
  (segment (start 79.118301 126.725923) (end 79.158146 126.745111) (width 0.109) (layer "In4.Cu") (net 212))
  (segment (start 81.228288 110.811) (end 81.389 110.811) (width 0.182) (layer "B.Cu") (net 212))
  (segment (start 79.84982 109.107532) (end 80.864 110.121712) (width 0.182) (layer "B.Cu") (net 212))
  (segment (start 79.84982 109.107532) (end 79.234 109.107532) (width 0.182) (layer "B.Cu") (net 212))
  (segment (start 81.389 110.811) (end 81.45 110.75) (width 0.182) (layer "B.Cu") (net 212))
  (segment (start 81.45 110.75) (end 81.9 110.75) (width 0.182) (layer "B.Cu") (net 212))
  (segment (start 80.864 110.446712) (end 81.228288 110.811) (width 0.182) (layer "B.Cu") (net 212))
  (segment (start 80.864 110.121712) (end 80.864 110.446712) (width 0.182) (layer "B.Cu") (net 212))
  (segment (start 79.234 109.107532) (end 79.125 108.998532) (width 0.182) (layer "B.Cu") (net 212))
  (segment (start 89.4415 132.219) (end 89.8265 131.909) (width 0.182) (layer "F.Cu") (net 213))
  (via (at 79.125 109.594533) (size 0.45) (drill 0.1) (layers "F.Cu" "B.Cu") (net 213))
  (via (at 89.4415 132.219) (size 0.45) (drill 0.1) (layers "F.Cu" "B.Cu") (net 213))
  (segment (start 77.706464 127.12134) (end 77.706464 127.165566) (width 0.109) (layer "In4.Cu") (net 213))
  (segment (start 78.887186 128.249104) (end 78.927032 128.229915) (width 0.109) (layer "In4.Cu") (net 213))
  (segment (start 77.612583 124.847035) (end 77.654007 124.933053) (width 0.109) (layer "In4.Cu") (net 213))
  (segment (start 77.408756 109.901431) (end 77.375166 109.901431) (width 0.109) (layer "In4.Cu") (net 213))
  (segment (start 76.913124 124.735415) (end 76.987768 124.675889) (width 0.109) (layer "In4.Cu") (net 213))
  (segment (start 75.897024 125.410059) (end 75.924598 125.444636) (width 0.109) (layer "In4.Cu") (net 213))
  (segment (start 78.573242 125.852288) (end 78.594486 125.945367) (width 0.109) (layer "In4.Cu") (net 213))
  (segment (start 75.8327 123.48862) (end 75.825016 123.510581) (width 0.109) (layer "In4.Cu") (net 213))
  (segment (start 77.088562 126.391445) (end 77.123139 126.363871) (width 0.109) (layer "In4.Cu") (net 213))
  (segment (start 80.493199 129.796082) (end 80.47401 129.835928) (width 0.109) (layer "In4.Cu") (net 213))
  (segment (start 77.837492 127.329869) (end 77.880609 127.33971) (width 0.109) (layer "In4.Cu") (net 213))
  (segment (start 77.735494 127.038377) (end 77.716305 127.078223) (width 0.109) (layer "In4.Cu") (net 213))
  (segment (start 77.516078 124.735413) (end 77.553055 124.77239) (width 0.109) (layer "In4.Cu") (net 213))
  (segment (start 78.716881 128.229915) (end 78.756727 128.249104) (width 0.109) (layer "In4.Cu") (net 213))
  (segment (start 76.12948 125.491399) (end 76.169326 125.47221) (width 0.109) (layer "In4.Cu") (net 213))
  (segment (start 77.76041 109.803549) (end 77.767885 109.836296) (width 0.109) (layer "In4.Cu") (net 213))
  (segment (start 79.573964 128.876847) (end 79.554775 128.916693) (width 0.109) (layer "In4.Cu") (net 213))
  (segment (start 79.513722 126.960076) (end 79.492477 127.053155) (width 0.109) (layer "In4.Cu") (net 213))
  (segment (start 84.604747 132.406493) (end 84.627 132.409) (width 0.109) (layer "In4.Cu") (net 213))
  (segment (start 76.180839 124.682072) (end 76.180839 124.777545) (width 0.109) (layer "In4.Cu") (net 213))
  (segment (start 77.806282 109.424032) (end 77.710157 109.520157) (width 0.109) (layer "In4.Cu") (net 213))
  (segment (start 78.0861 125.532454) (end 78.181572 125.532453) (width 0.109) (layer "In4.Cu") (net 213))
  (segment (start 77.498027 109.944422) (end 77.471766 109.923479) (width 0.109) (layer "In4.Cu") (net 213))
  (segment (start 80.765502 130.068385) (end 80.800079 130.040811) (width 0.109) (layer "In4.Cu") (net 213))
  (segment (start 81.537079 129.906766) (end 81.555568 129.925254) (width 0.109) (layer "In4.Cu") (net 213))
  (segment (start 80.555351 130.068385) (end 80.595197 130.087574) (width 0.109) (layer "In4.Cu") (net 213))
  (segment (start 75.8327 123.432183) (end 75.835305 123.455304) (width 0.109) (layer "In4.Cu") (net 213))
  (segment (start 80.292273 128.151541) (end 79.856748 128.587061) (width 0.109) (layer "In4.Cu") (net 213))
  (segment (start 78.594487 126.040841) (end 78.573242 126.13392) (width 0.109) (layer "In4.Cu") (net 213))
  (segment (start 84.583611 132.399097) (end 84.604747 132.406493) (width 0.109) (layer "In4.Cu") (net 213))
  (segment (start 80.411712 127.97239) (end 80.370288 128.058408) (width 0.109) (layer "In4.Cu") (net 213))
  (segment (start 78.625699 128.040575) (end 78.625699 128.084801) (width 0.109) (layer "In4.Cu") (net 213))
  (segment (start 77.993021 125.5537) (end 78.0861 125.532454) (width 0.109) (layer "In4.Cu") (net 213))
  (segment (start 77.710157 109.520157) (end 77.689215 109.546419) (width 0.109) (layer "In4.Cu") (net 213))
  (segment (start 75.63779 123.628222) (end 75.630106 123.650183) (width 0.109) (layer "In4.Cu") (net 213))
  (segment (start 79.856748 128.587061) (end 79.601539 128.84227) (width 0.109) (layer "In4.Cu") (net 213))
  (segment (start 78.042374 127.283106) (end 78.751594 126.573885) (width 0.109) (layer "In4.Cu") (net 213))
  (segment (start 80.31076 128.133051) (end 80.292273 128.151541) (width 0.109) (layer "In4.Cu") (net 213))
  (segment (start 77.635623 110.002148) (end 77.602033 110.002149) (width 0.109) (layer "In4.Cu") (net 213))
  (segment (start 75.708282 123.348796) (end 75.754524 123.354007) (width 0.109) (layer "In4.Cu") (net 213))
  (segment (start 84.318903 132.265612) (end 84.330816 132.246652) (width 0.109) (layer "In4.Cu") (net 213))
  (segment (start 81.462435 129.847239) (end 81.537079 129.906766) (width 0.109) (layer "In4.Cu") (net 213))
  (segment (start 77.048716 126.410634) (end 77.088562 126.391445) (width 0.109) (layer "In4.Cu") (net 213))
  (segment (start 76.058644 125.031286) (end 75.924598 125.165331) (width 0.109) (layer "In4.Cu") (net 213))
  (segment (start 75.686321 123.341112) (end 75.708282 123.348796) (width 0.109) (layer "In4.Cu") (net 213))
  (segment (start 76.787229 126.202105) (end 76.787229 126.246331) (width 0.109) (layer "In4.Cu") (net 213))
  (segment (start 79.005335 126.451689) (end 79.100807 126.451688) (width 0.109) (layer "In4.Cu") (net 213))
  (segment (start 77.907003 125.595124) (end 77.993021 125.5537) (width 0.109) (layer "In4.Cu") (net 213))
  (segment (start 75.630106 123.650183) (end 75.6275 123.673304) (width 0.109) (layer "In4.Cu") (net 213))
  (segment (start 84.365611 132.218904) (end 84.386747 132.211508) (width 0.109) (layer "In4.Cu") (net 213))
  (segment (start 81.094785 129.805815) (end 81.187865 129.78457) (width 0.109) (layer "In4.Cu") (net 213))
  (segment (start 78.682304 127.923035) (end 78.654729 127.957612) (width 0.109) (layer "In4.Cu") (net 213))
  (segment (start 79.373038 127.232306) (end 78.937513 127.667826) (width 0.109) (layer "In4.Cu") (net 213))
  (segment (start 78.47229 126.294581) (end 78.453803 126.313071) (width 0.109) (layer "In4.Cu") (net 213))
  (segment (start 84.564651 132.387184) (end 84.583611 132.399097) (width 0.109) (layer "In4.Cu") (net 213))
  (segment (start 76.843834 126.084565) (end 76.816259 126.119142) (width 0.109) (layer "In4.Cu") (net 213))
  (segment (start 81.032356 128.311403) (end 81.118374 128.352827) (width 0.109) (layer "In4.Cu") (net 213))
  (segment (start 79.554775 129.047153) (end 79.573964 129.086999) (width 0.109) (layer "In4.Cu") (net 213))
  (segment (start 77.667168 109.643017) (end 77.674641 109.675765) (width 0.109) (layer "In4.Cu") (net 213))
  (segment (start 80.750726 128.311405) (end 80.843805 128.290159) (width 0.109) (layer "In4.Cu") (net 213))
  (segment (start 80.682539 130.097415) (end 80.725656 130.087574) (width 0.109) (layer "In4.Cu") (net 213))
  (segment (start 84.287183 132.371349) (end 84.299096 132.352389) (width 0.109) (layer "In4.Cu") (net 213))
  (segment (start 79.763304 129.17818) (end 79.806421 129.168339) (width 0.109) (layer "In4.Cu") (net 213))
  (segment (start 79.806421 129.168339) (end 79.846267 129.14915) (width 0.109) (layer "In4.Cu") (net 213))
  (segment (start 79.573964 129.086999) (end 79.601539 129.121576) (width 0.109) (layer "In4.Cu") (net 213))
  (segment (start 75.835305 123.4655) (end 75.8327 123.48862) (width 0.109) (layer "In4.Cu") (net 213))
  (segment (start 77.967951 127.329869) (end 78.007797 127.31068) (width 0.109) (layer "In4.Cu") (net 213))
  (segment (start 79.880844 129.121576) (end 80.590064 128.412355) (width 0.109) (layer "In4.Cu") (net 213))
  (segment (start 75.999021 125.491399) (end 76.042138 125.50124) (width 0.109) (layer "In4.Cu") (net 213))
  (segment (start 78.573242 126.13392) (end 78.531818 126.219938) (width 0.109) (layer "In4.Cu") (net 213))
  (segment (start 81.008767 129.847239) (end 81.094785 129.805815) (width 0.109) (layer "In4.Cu") (net 213))
  (segment (start 79.601539 128.84227) (end 79.573964 128.876847) (width 0.109) (layer "In4.Cu") (net 213))
  (segment (start 79.391525 126.61086) (end 79.451053 126.685505) (width 0.109) (layer "In4.Cu") (net 213))
  (segment (start 76.11817 124.502974) (end 76.159595 124.588992) (width 0.109) (layer "In4.Cu") (net 213))
  (segment (start 75.959175 125.47221) (end 75.999021 125.491399) (width 0.109) (layer "In4.Cu") (net 213))
  (segment (start 84.252388 132.399097) (end 84.271348 132.387184) (width 0.109) (layer "In4.Cu") (net 213))
  (segment (start 89.2515 132.409) (end 89.4415 132.219) (width 0.109) (layer "In4.Cu") (net 213))
  (segment (start 81.352192 128.798546) (end 81.330947 128.891625) (width 0.109) (layer "In4.Cu") (net 213))
  (segment (start 75.666621 123.59207) (end 75.650169 123.608522) (width 0.109) (layer "In4.Cu") (net 213))
  (segment (start 80.520774 129.761505) (end 80.493199 129.796082) (width 0.109) (layer "In4.Cu") (net 213))
  (segment (start 76.787229 126.246331) (end 76.79707 126.289448) (width 0.109) (layer "In4.Cu") (net 213))
  (segment (start 76.086363 125.50124) (end 76.12948 125.491399) (width 0.109) (layer "In4.Cu") (net 213))
  (segment (start 76.203903 125.444636) (end 76.913124 124.735415) (width 0.109) (layer "In4.Cu") (net 213))
  (segment (start 77.539023 109.980101) (end 77.512762 109.959157) (width 0.109) (layer "In4.Cu") (net 213))
  (segment (start 75.924598 125.444636) (end 75.959175 125.47221) (width 0.109) (layer "In4.Cu") (net 213))
  (segment (start 77.602033 110.002149) (end 77.569287 109.994674) (width 0.109) (layer "In4.Cu") (net 213))
  (segment (start 77.832359 125.65465) (end 77.907003 125.595124) (width 0.109) (layer "In4.Cu") (net 213))
  (segment (start 77.342419 109.908906) (end 77.312156 109.923479) (width 0.109) (layer "In4.Cu") (net 213))
  (segment (start 77.285894 109.944421) (end 75.6275 111.602814) (width 0.109) (layer "In4.Cu") (net 213))
  (segment (start 75.796185 123.37407) (end 75.812637 123.390522) (width 0.109) (layer "In4.Cu") (net 213))
  (segment (start 81.229995 128.44933) (end 81.289523 128.523975) (width 0.109) (layer "In4.Cu") (net 213))
  (segment (start 81.187865 129.78457) (end 81.283338 129.78457) (width 0.109) (layer "In4.Cu") (net 213))
  (segment (start 78.937513 127.667826) (end 78.682304 127.923035) (width 0.109) (layer "In4.Cu") (net 213))
  (segment (start 84.346651 132.230817) (end 84.365611 132.218904) (width 0.109) (layer "In4.Cu") (net 213))
  (segment (start 77.099043 125.829356) (end 76.843834 126.084565) (width 0.109) (layer "In4.Cu") (net 213))
  (segment (start 77.553055 124.77239) (end 77.612583 124.847035) (width 0.109) (layer "In4.Cu") (net 213))
  (segment (start 77.654007 125.214685) (end 77.612583 125.300703) (width 0.109) (layer "In4.Cu") (net 213))
  (segment (start 80.31076 127.530095) (end 80.370288 127.60474) (width 0.109) (layer "In4.Cu") (net 213))
  (segment (start 79.193886 126.472933) (end 79.279904 126.514357) (width 0.109) (layer "In4.Cu") (net 213))
  (segment (start 76.878411 126.391445) (end 76.918257 126.410634) (width 0.109) (layer "In4.Cu") (net 213))
  (segment (start 78.654729 128.167764) (end 78.682304 128.202341) (width 0.109) (layer "In4.Cu") (net 213))
  (segment (start 80.113121 127.392168) (end 80.199139 127.433592) (width 0.109) (layer "In4.Cu") (net 213))
  (segment (start 77.724894 109.747025) (end 77.745837 109.773286) (width 0.109) (layer "In4.Cu") (net 213))
  (segment (start 84.548816 132.371349) (end 84.564651 132.387184) (width 0.109) (layer "In4.Cu") (net 213))
  (segment (start 75.6275 111.602814) (end 75.6275 123.2475) (width 0.109) (layer "In4.Cu") (net 213))
  (segment (start 76.058644 124.42833) (end 76.11817 124.502974) (width 0.109) (layer "In4.Cu") (net 213))
  (segment (start 79.492477 127.053155) (end 79.451053 127.139173) (width 0.109) (layer "In4.Cu") (net 213))
  (segment (start 77.880609 127.33971) (end 77.924834 127.33971) (width 0.109) (layer "In4.Cu") (net 213))
  (segment (start 84.231252 132.406493) (end 84.252388 132.399097) (width 0.109) (layer "In4.Cu") (net 213))
  (segment (start 79.719079 129.17818) (end 79.763304 129.17818) (width 0.109) (layer "In4.Cu") (net 213))
  (segment (start 84.627 132.409) (end 89.2515 132.409) (width 0.109) (layer "In4.Cu") (net 213))
  (segment (start 77.924834 127.33971) (end 77.967951 127.329869) (width 0.109) (layer "In4.Cu") (net 213))
  (segment (start 76.79707 126.158988) (end 76.787229 126.202105) (width 0.109) (layer "In4.Cu") (net 213))
  (segment (start 78.682304 128.202341) (end 78.716881 128.229915) (width 0.109) (layer "In4.Cu") (net 213))
  (segment (start 77.553055 125.375346) (end 77.534568 125.393836) (width 0.109) (layer "In4.Cu") (net 213))
  (segment (start 75.686321 123.579691) (end 75.666621 123.59207) (width 0.109) (layer "In4.Cu") (net 213))
  (segment (start 80.843805 128.290159) (end 80.939277 128.290158) (width 0.109) (layer "In4.Cu") (net 213))
  (segment (start 81.193018 128.412353) (end 81.229995 128.44933) (width 0.109) (layer "In4.Cu") (net 213))
  (segment (start 78.625699 128.084801) (end 78.63554 128.127918) (width 0.109) (layer "In4.Cu") (net 213))
  (segment (start 77.667167 109.609429) (end 77.667168 109.643017) (width 0.109) (layer "In4.Cu") (net 213))
  (segment (start 80.520774 129.761505) (end 81.211508 129.070776) (width 0.109) (layer "In4.Cu") (net 213))
  (segment (start 78.912256 126.472935) (end 79.005335 126.451689) (width 0.109) (layer "In4.Cu") (net 213))
  (segment (start 75.812637 123.530281) (end 75.796185 123.546733) (width 0.109) (layer "In4.Cu") (net 213))
  (segment (start 84.306492 132.331253) (end 84.311507 132.286748) (width 0.109) (layer "In4.Cu") (net 213))
  (segment (start 78.751594 126.573885) (end 78.826238 126.514359) (width 0.109) (layer "In4.Cu") (net 213))
  (segment (start 76.816259 126.329294) (end 76.843834 126.363871) (width 0.109) (layer "In4.Cu") (net 213))
  (segment (start 77.698633 109.9801) (end 77.668369 109.994675) (width 0.109) (layer "In4.Cu") (net 213))
  (segment (start 77.76041 109.902633) (end 77.745837 109.932896) (width 0.109) (layer "In4.Cu") (net 213))
  (segment (start 77.706464 127.165566) (end 77.716305 127.208683) (width 0.109) (layer "In4.Cu") (net 213))
  (segment (start 78.360669 125.595122) (end 78.435313 125.654648) (width 0.109) (layer "In4.Cu") (net 213))
  (segment (start 77.689215 109.546419) (end 77.674642 109.576681) (width 0.109) (layer "In4.Cu") (net 213))
  (segment (start 84.529507 132.331253) (end 84.536903 132.352389) (width 0.109) (layer "In4.Cu") (net 213))
  (segment (start 79.92457 127.370924) (end 80.020042 127.370923) (width 0.109) (layer "In4.Cu") (net 213))
  (segment (start 75.825016 123.510581) (end 75.812637 123.530281) (width 0.109) (layer "In4.Cu") (net 213))
  (segment (start 81.352191 128.703072) (end 81.352192 128.798546) (width 0.109) (layer "In4.Cu") (net 213))
  (segment (start 80.590064 128.412355) (end 80.664708 128.352829) (width 0.109) (layer "In4.Cu") (net 213))
  (segment (start 79.125 109.594533) (end 79.125 109.594532) (width 0.109) (layer "In4.Cu") (net 213))
  (segment (start 79.354548 126.573883) (end 79.391525 126.61086) (width 0.109) (layer "In4.Cu") (net 213))
  (segment (start 77.675251 125.026132) (end 77.675252 125.121606) (width 0.109) (layer "In4.Cu") (net 213))
  (segment (start 78.9545 109.424032) (end 77.806282 109.424032) (width 0.109) (layer "In4.Cu") (net 213))
  (segment (start 80.725656 130.087574) (end 80.765502 130.068385) (width 0.109) (layer "In4.Cu") (net 213))
  (segment (start 76.843834 126.363871) (end 76.878411 126.391445) (width 0.109) (layer "In4.Cu") (net 213))
  (segment (start 77.745837 109.932896) (end 77.724894 109.959157) (width 0.109) (layer "In4.Cu") (net 213))
  (segment (start 79.391525 127.213816) (end 79.373038 127.232306) (width 0.109) (layer "In4.Cu") (net 213))
  (segment (start 75.6275 123.2475) (end 75.630106 123.27062) (width 0.109) (layer "In4.Cu") (net 213))
  (segment (start 77.073786 124.634465) (end 77.166865 124.613219) (width 0.109) (layer "In4.Cu") (net 213))
  (segment (start 84.449252 132.211508) (end 84.470388 132.218904) (width 0.109) (layer "In4.Cu") (net 213))
  (segment (start 77.471766 109.923479) (end 77.441503 109.908906) (width 0.109) (layer "In4.Cu") (net 213))
  (segment (start 75.708282 123.572007) (end 75.686321 123.579691) (width 0.109) (layer "In4.Cu") (net 213))
  (segment (start 81.289523 128.977643) (end 81.229995 129.052286) (width 0.109) (layer "In4.Cu") (net 213))
  (segment (start 80.493199 130.006234) (end 80.520774 130.040811) (width 0.109) (layer "In4.Cu") (net 213))
  (segment (start 77.441434 124.675887) (end 77.516078 124.735413) (width 0.109) (layer "In4.Cu") (net 213))
  (segment (start 76.918257 126.410634) (end 76.961374 126.420475) (width 0.109) (layer "In4.Cu") (net 213))
  (segment (start 75.666621 123.328733) (end 75.686321 123.341112) (width 0.109) (layer "In4.Cu") (net 213))
  (segment (start 78.47229 125.691625) (end 78.531818 125.76627) (width 0.109) (layer "In4.Cu") (net 213))
  (segment (start 80.411712 127.690758) (end 80.432956 127.783837) (width 0.109) (layer "In4.Cu") (net 213))
  (segment (start 79.100807 126.451688) (end 79.193886 126.472933) (width 0.109) (layer "In4.Cu") (net 213))
  (segment (start 77.745837 109.773286) (end 77.76041 109.803549) (width 0.109) (layer "In4.Cu") (net 213))
  (segment (start 75.796185 123.546733) (end 75.776485 123.559112) (width 0.109) (layer "In4.Cu") (net 213))
  (segment (start 76.79707 126.289448) (end 76.816259 126.329294) (width 0.109) (layer "In4.Cu") (net 213))
  (segment (start 84.409 132.209) (end 84.427 132.209) (width 0.109) (layer "In4.Cu") (net 213))
  (segment (start 75.754524 123.354007) (end 75.776485 123.361691) (width 0.109) (layer "In4.Cu") (net 213))
  (segment (start 84.536903 132.352389) (end 84.548816 132.371349) (width 0.109) (layer "In4.Cu") (net 213))
  (segment (start 77.716305 127.078223) (end 77.706464 127.12134) (width 0.109) (layer "In4.Cu") (net 213))
  (segment (start 76.961374 126.420475) (end 77.005599 126.420475) (width 0.109) (layer "In4.Cu") (net 213))
  (segment (start 77.569287 109.994674) (end 77.539023 109.980101) (width 0.109) (layer "In4.Cu") (net 213))
  (segment (start 79.675962 129.168339) (end 79.719079 129.17818) (width 0.109) (layer "In4.Cu") (net 213))
  (segment (start 84.505183 132.246652) (end 84.517096 132.265612) (width 0.109) (layer "In4.Cu") (net 213))
  (segment (start 80.800079 130.040811) (end 80.934123 129.906766) (width 0.109) (layer "In4.Cu") (net 213))
  (segment (start 80.432957 127.879311) (end 80.411712 127.97239) (width 0.109) (layer "In4.Cu") (net 213))
  (segment (start 77.441503 109.908906) (end 77.408756 109.901431) (width 0.109) (layer "In4.Cu") (net 213))
  (segment (start 77.612583 125.300703) (end 77.553055 125.375346) (width 0.109) (layer "In4.Cu") (net 213))
  (segment (start 75.6275 123.997187) (end 76.058644 124.42833) (width 0.109) (layer "In4.Cu") (net 213))
  (segment (start 77.355416 124.634463) (end 77.441434 124.675887) (width 0.109) (layer "In4.Cu") (net 213))
  (segment (start 75.877835 125.370213) (end 75.897024 125.410059) (width 0.109) (layer "In4.Cu") (net 213))
  (segment (start 79.831491 127.39217) (end 79.92457 127.370924) (width 0.109) (layer "In4.Cu") (net 213))
  (segment (start 78.018278 126.748591) (end 77.763069 127.0038) (width 0.109) (layer "In4.Cu") (net 213))
  (segment (start 81.330947 128.609993) (end 81.352191 128.703072) (width 0.109) (layer "In4.Cu") (net 213))
  (segment (start 77.763069 127.283106) (end 77.797646 127.31068) (width 0.109) (layer "In4.Cu") (net 213))
  (segment (start 78.654729 127.957612) (end 78.63554 127.997458) (width 0.109) (layer "In4.Cu") (net 213))
  (segment (start 78.799844 128.258945) (end 78.844069 128.258945) (width 0.109) (layer "In4.Cu") (net 213))
  (segment (start 80.47401 129.966388) (end 80.493199 130.006234) (width 0.109) (layer "In4.Cu") (net 213))
  (segment (start 77.005599 126.420475) (end 77.048716 126.410634) (width 0.109) (layer "In4.Cu") (net 213))
  (segment (start 79.492477 126.771523) (end 79.513721 126.864602) (width 0.109) (layer "In4.Cu") (net 213))
  (segment (start 80.432956 127.783837) (end 80.432957 127.879311) (width 0.109) (layer "In4.Cu") (net 213))
  (segment (start 80.939277 128.290158) (end 81.032356 128.311403) (width 0.109) (layer "In4.Cu") (net 213))
  (segment (start 78.274651 125.553698) (end 78.360669 125.595122) (width 0.109) (layer "In4.Cu") (net 213))
  (segment (start 77.123139 126.363871) (end 77.832359 125.65465) (width 0.109) (layer "In4.Cu") (net 213))
  (segment (start 81.229995 129.052286) (end 81.211508 129.070776) (width 0.109) (layer "In4.Cu") (net 213))
  (segment (start 77.166865 124.613219) (end 77.262337 124.613218) (width 0.109) (layer "In4.Cu") (net 213))
  (segment (start 80.020042 127.370923) (end 80.113121 127.392168) (width 0.109) (layer "In4.Cu") (net 213))
  (segment (start 75.650169 123.608522) (end 75.63779 123.628222) (width 0.109) (layer "In4.Cu") (net 213))
  (segment (start 77.716305 127.208683) (end 77.735494 127.248529) (width 0.109) (layer "In4.Cu") (net 213))
  (segment (start 81.376417 129.805815) (end 81.462435 129.847239) (width 0.109) (layer "In4.Cu") (net 213))
  (segment (start 79.513721 126.864602) (end 79.513722 126.960076) (width 0.109) (layer "In4.Cu") (net 213))
  (segment (start 80.595197 130.087574) (end 80.638314 130.097415) (width 0.109) (layer "In4.Cu") (net 213))
  (segment (start 77.797646 127.31068) (end 77.837492 127.329869) (width 0.109) (layer "In4.Cu") (net 213))
  (segment (start 75.776485 123.559112) (end 75.754524 123.566796) (width 0.109) (layer "In4.Cu") (net 213))
  (segment (start 79.451053 127.139173) (end 79.391525 127.213816) (width 0.109) (layer "In4.Cu") (net 213))
  (segment (start 76.11817 124.956642) (end 76.058644 125.031286) (width 0.109) (layer "In4.Cu") (net 213))
  (segment (start 78.63554 127.997458) (end 78.625699 128.040575) (width 0.109) (layer "In4.Cu") (net 213))
  (segment (start 77.767885 109.869886) (end 77.76041 109.902633) (width 0.109) (layer "In4.Cu") (net 213))
  (segment (start 78.63554 128.127918) (end 78.654729 128.167764) (width 0.109) (layer "In4.Cu") (net 213))
  (segment (start 77.512762 109.959157) (end 77.498027 109.944422) (width 0.109) (layer "In4.Cu") (net 213))
  (segment (start 78.531818 125.76627) (end 78.573242 125.852288) (width 0.109) (layer "In4.Cu") (net 213))
  (segment (start 75.825016 123.410222) (end 75.8327 123.432183) (width 0.109) (layer "In4.Cu") (net 213))
  (segment (start 77.767885 109.836296) (end 77.767885 109.869886) (width 0.109) (layer "In4.Cu") (net 213))
  (segment (start 79.670829 127.49312) (end 79.745473 127.433594) (width 0.109) (layer "In4.Cu") (net 213))
  (segment (start 80.47401 129.835928) (end 80.464169 129.879045) (width 0.109) (layer "In4.Cu") (net 213))
  (segment (start 79.544934 129.004036) (end 79.554775 129.047153) (width 0.109) (layer "In4.Cu") (net 213))
  (segment (start 77.674642 109.576681) (end 77.667167 109.609429) (width 0.109) (layer "In4.Cu") (net 213))
  (segment (start 80.199139 127.433592) (end 80.273783 127.493118) (width 0.109) (layer "In4.Cu") (net 213))
  (segment (start 77.654007 124.933053) (end 77.675251 125.026132) (width 0.109) (layer "In4.Cu") (net 213))
  (segment (start 84.209 132.409) (end 84.231252 132.406493) (width 0.109) (layer "In4.Cu") (net 213))
  (segment (start 78.756727 128.249104) (end 78.799844 128.258945) (width 0.109) (layer "In4.Cu") (net 213))
  (segment (start 78.961609 128.202341) (end 79.670829 127.49312) (width 0.109) (layer "In4.Cu") (net 213))
  (segment (start 84.524492 132.286748) (end 84.529507 132.331253) (width 0.109) (layer "In4.Cu") (net 213))
  (segment (start 79.554775 128.916693) (end 79.544934 128.95981) (width 0.109) (layer "In4.Cu") (net 213))
  (segment (start 76.159595 124.870624) (end 76.11817 124.956642) (width 0.109) (layer "In4.Cu") (net 213))
  (segment (start 75.867994 125.327096) (end 75.877835 125.370213) (width 0.109) (layer "In4.Cu") (net 213))
  (segment (start 78.181572 125.532453) (end 78.274651 125.553698) (width 0.109) (layer "In4.Cu") (net 213))
  (segment (start 84.489348 132.230817) (end 84.505183 132.246652) (width 0.109) (layer "In4.Cu") (net 213))
  (segment (start 75.650169 123.312281) (end 75.666621 123.328733) (width 0.109) (layer "In4.Cu") (net 213))
  (segment (start 80.464169 129.879045) (end 80.464169 129.923271) (width 0.109) (layer "In4.Cu") (net 213))
  (segment (start 84.311507 132.286748) (end 84.318903 132.265612) (width 0.109) (layer "In4.Cu") (net 213))
  (segment (start 77.675252 125.121606) (end 77.654007 125.214685) (width 0.109) (layer "In4.Cu") (net 213))
  (segment (start 75.867994 125.282871) (end 75.867994 125.327096) (width 0.109) (layer "In4.Cu") (net 213))
  (segment (start 77.763069 127.0038) (end 77.735494 127.038377) (width 0.109) (layer "In4.Cu") (net 213))
  (segment (start 81.289523 128.523975) (end 81.330947 128.609993) (width 0.109) (layer "In4.Cu") (net 213))
  (segment (start 77.312156 109.923479) (end 77.285894 109.944421) (width 0.109) (layer "In4.Cu") (net 213))
  (segment (start 77.710158 109.732289) (end 77.724894 109.747025) (width 0.109) (layer "In4.Cu") (net 213))
  (segment (start 77.668369 109.994675) (end 77.635623 110.002148) (width 0.109) (layer "In4.Cu") (net 213))
  (segment (start 76.987768 124.675889) (end 77.073786 124.634465) (width 0.109) (layer "In4.Cu") (net 213))
  (segment (start 79.125 109.594532) (end 78.9545 109.424032) (width 0.109) (layer "In4.Cu") (net 213))
  (segment (start 80.664708 128.352829) (end 80.750726 128.311405) (width 0.109) (layer "In4.Cu") (net 213))
  (segment (start 81.330947 128.891625) (end 81.289523 128.977643) (width 0.109) (layer "In4.Cu") (net 213))
  (segment (start 77.534568 125.393836) (end 77.099043 125.829356) (width 0.109) (layer "In4.Cu") (net 213))
  (segment (start 81.283338 129.78457) (end 81.376417 129.805815) (width 0.109) (layer "In4.Cu") (net 213))
  (segment (start 75.812637 123.390522) (end 75.825016 123.410222) (width 0.109) (layer "In4.Cu") (net 213))
  (segment (start 80.934123 129.906766) (end 81.008767 129.847239) (width 0.109) (layer "In4.Cu") (net 213))
  (segment (start 79.451053 126.685505) (end 79.492477 126.771523) (width 0.109) (layer "In4.Cu") (net 213))
  (segment (start 78.453803 126.313071) (end 78.018278 126.748591) (width 0.109) (layer "In4.Cu") (net 213))
  (segment (start 76.042138 125.50124) (end 76.086363 125.50124) (width 0.109) (layer "In4.Cu") (net 213))
  (segment (start 75.924598 125.165331) (end 75.897024 125.199908) (width 0.109) (layer "In4.Cu") (net 213))
  (segment (start 75.877835 125.239754) (end 75.867994 125.282871) (width 0.109) (layer "In4.Cu") (net 213))
  (segment (start 80.370288 128.058408) (end 80.31076 128.133051) (width 0.109) (layer "In4.Cu") (net 213))
  (segment (start 77.724894 109.959157) (end 77.698633 109.9801) (width 0.109) (layer "In4.Cu") (net 213))
  (segment (start 76.169326 125.47221) (end 76.203903 125.444636) (width 0.109) (layer "In4.Cu") (net 213))
  (segment (start 76.159595 124.588992) (end 76.180839 124.682072) (width 0.109) (layer "In4.Cu") (net 213))
  (segment (start 79.279904 126.514357) (end 79.354548 126.573883) (width 0.109) (layer "In4.Cu") (net 213))
  (segment (start 78.844069 128.258945) (end 78.887186 128.249104) (width 0.109) (layer "In4.Cu") (net 213))
  (segment (start 78.435313 125.654648) (end 78.47229 125.691625) (width 0.109) (layer "In4.Cu") (net 213))
  (segment (start 81.555568 129.925254) (end 84.039314 132.409) (width 0.109) (layer "In4.Cu") (net 213))
  (segment (start 75.63779 123.292581) (end 75.650169 123.312281) (width 0.109) (layer "In4.Cu") (net 213))
  (segment (start 75.776485 123.361691) (end 75.796185 123.37407) (width 0.109) (layer "In4.Cu") (net 213))
  (segment (start 78.826238 126.514359) (end 78.912256 126.472935) (width 0.109) (layer "In4.Cu") (net 213))
  (segment (start 84.386747 132.211508) (end 84.409 132.209) (width 0.109) (layer "In4.Cu") (net 213))
  (segment (start 78.531818 126.219938) (end 78.47229 126.294581) (width 0.109) (layer "In4.Cu") (net 213))
  (segment (start 84.299096 132.352389) (end 84.306492 132.331253) (width 0.109) (layer "In4.Cu") (net 213))
  (segment (start 76.180839 124.777545) (end 76.159595 124.870624) (width 0.109) (layer "In4.Cu") (net 213))
  (segment (start 80.464169 129.923271) (end 80.47401 129.966388) (width 0.109) (layer "In4.Cu") (net 213))
  (segment (start 84.039314 132.409) (end 84.209 132.409) (width 0.109) (layer "In4.Cu") (net 213))
  (segment (start 79.846267 129.14915) (end 79.880844 129.121576) (width 0.109) (layer "In4.Cu") (net 213))
  (segment (start 75.754524 123.566796) (end 75.708282 123.572007) (width 0.109) (layer "In4.Cu") (net 213))
  (segment (start 78.927032 128.229915) (end 78.961609 128.202341) (width 0.109) (layer "In4.Cu") (net 213))
  (segment (start 84.330816 132.246652) (end 84.346651 132.230817) (width 0.109) (layer "In4.Cu") (net 213))
  (segment (start 79.544934 128.95981) (end 79.544934 129.004036) (width 0.109) (layer "In4.Cu") (net 213))
  (segment (start 77.674641 109.675765) (end 77.689216 109.706027) (width 0.109) (layer "In4.Cu") (net 213))
  (segment (start 84.427 132.209) (end 84.449252 132.211508) (width 0.109) (layer "In4.Cu") (net 213))
  (segment (start 80.273783 127.493118) (end 80.31076 127.530095) (width 0.109) (layer "In4.Cu") (net 213))
  (segment (start 77.735494 127.248529) (end 77.763069 127.283106) (width 0.109) (layer "In4.Cu") (net 213))
  (segment (start 75.897024 125.199908) (end 75.877835 125.239754) (width 0.109) (layer "In4.Cu") (net 213))
  (segment (start 78.594486 125.945367) (end 78.594487 126.040841) (width 0.109) (layer "In4.Cu") (net 213))
  (segment (start 77.262337 124.613218) (end 77.355416 124.634463) (width 0.109) (layer "In4.Cu") (net 213))
  (segment (start 84.470388 132.218904) (end 84.489348 132.230817) (width 0.109) (layer "In4.Cu") (net 213))
  (segment (start 79.745473 127.433594) (end 79.831491 127.39217) (width 0.109) (layer "In4.Cu") (net 213))
  (segment (start 76.816259 126.119142) (end 76.79707 126.158988) (width 0.109) (layer "In4.Cu") (net 213))
  (segment (start 78.007797 127.31068) (end 78.042374 127.283106) (width 0.109) (layer "In4.Cu") (net 213))
  (segment (start 80.520774 130.040811) (end 80.555351 130.068385) (width 0.109) (layer "In4.Cu") (net 213))
  (segment (start 75.835305 123.455304) (end 75.835305 123.4655) (width 0.109) (layer "In4.Cu") (net 213))
  (segment (start 81.118374 128.352827) (end 81.193018 128.412353) (width 0.109) (layer "In4.Cu") (net 213))
  (segment (start 84.271348 132.387184) (end 84.287183 132.371349) (width 0.109) (layer "In4.Cu") (net 213))
  (segment (start 75.630106 123.27062) (end 75.63779 123.292581) (width 0.109) (layer "In4.Cu") (net 213))
  (segment (start 84.517096 132.265612) (end 84.524492 132.286748) (width 0.109) (layer "In4.Cu") (net 213))
  (segment (start 79.601539 129.121576) (end 79.636116 129.14915) (width 0.109) (layer "In4.Cu") (net 213))
  (segment (start 75.6275 123.673304) (end 75.6275 123.997187) (width 0.109) (layer "In4.Cu") (net 213))
  (segment (start 77.689216 109.706027) (end 77.710158 109.732289) (width 0.109) (layer "In4.Cu") (net 213))
  (segment (start 80.638314 130.097415) (end 80.682539 130.097415) (width 0.109) (layer "In4.Cu") (net 213))
  (segment (start 77.375166 109.901431) (end 77.342419 109.908906) (width 0.109) (layer "In4.Cu") (net 213))
  (segment (start 79.636116 129.14915) (end 79.675962 129.168339) (width 0.109) (layer "In4.Cu") (net 213))
  (segment (start 80.370288 127.60474) (end 80.411712 127.690758) (width 0.109) (layer "In4.Cu") (net 213))
  (segment (start 80.486 110.603288) (end 81.071712 111.189) (width 0.182) (layer "B.Cu") (net 213))
  (segment (start 79.693244 109.485532) (end 80.486 110.278288) (width 0.182) (layer "B.Cu") (net 213))
  (segment (start 81.45 111.25) (end 81.9 111.25) (width 0.182) (layer "B.Cu") (net 213))
  (segment (start 81.071712 111.189) (end 81.389 111.189) (width 0.182) (layer "B.Cu") (net 213))
  (segment (start 79.234 109.485532) (end 79.125 109.594532) (width 0.182) (layer "B.Cu") (net 213))
  (segment (start 81.389 111.189) (end 81.45 111.25) (width 0.182) (layer "B.Cu") (net 213))
  (segment (start 80.486 110.278288) (end 80.486 110.603288) (width 0.182) (layer "B.Cu") (net 213))
  (segment (start 79.693244 109.485532) (end 79.234 109.485532) (width 0.182) (layer "B.Cu") (net 213))
  (segment (start 79.125 109.594532) (end 79.125 109.594533) (width 0.182) (layer "B.Cu") (net 213))
  (segment (start 89.4415 134.759) (end 89.8265 134.449) (width 0.182) (layer "F.Cu") (net 214))
  (via (at 89.4415 134.759) (size 0.45) (drill 0.1) (layers "F.Cu" "B.Cu") (net 214))
  (via (at 78.975 110.405467) (size 0.45) (drill 0.1) (layers "F.Cu" "B.Cu") (net 214))
  (segment (start 82.402434 128.743599) (end 82.309354 128.722354) (width 0.109) (layer "In6.Cu") (net 214))
  (segment (start 81.838866 125.884902) (end 81.799019 125.90409) (width 0.109) (layer "In6.Cu") (net 214))
  (segment (start 80.752516 126.883884) (end 80.659437 126.905129) (width 0.109) (layer "In6.Cu") (net 214))
  (segment (start 78.434775 124.304531) (end 78.639844 124.099463) (width 0.109) (layer "In6.Cu") (net 214))
  (segment (start 79.993943 125.863698) (end 79.919299 125.923225) (width 0.109) (layer "In6.Cu") (net 214))
  (segment (start 79.253059 125.666059) (end 79.231815 125.57298) (width 0.109) (layer "In6.Cu") (net 214))
  (segment (start 81.390119 127.803119) (end 81.304101 127.761695) (width 0.109) (layer "In6.Cu") (net 214))
  (segment (start 78.686607 124.02504) (end 78.696448 123.981923) (width 0.109) (layer "In6.Cu") (net 214))
  (segment (start 81.152088 125.257158) (end 81.171276 125.217311) (width 0.109) (layer "In6.Cu") (net 214))
  (segment (start 82.971423 129.429017) (end 82.929999 129.342999) (width 0.109) (layer "In6.Cu") (net 214))
  (segment (start 80.252042 124.167618) (end 80.232852 124.127771) (width 0.109) (layer "In6.Cu") (net 214))
  (segment (start 84.727031 128.642607) (end 84.683914 128.632766) (width 0.109) (layer "In6.Cu") (net 214))
  (segment (start 79.551649 125.964649) (end 79.465631 125.923225) (width 0.109) (layer "In6.Cu") (net 214))
  (segment (start 82.010764 128.423764) (end 81.98952 128.330685) (width 0.109) (layer "In6.Cu") (net 214))
  (segment (start 82.090512 126.006088) (end 82.071322 125.966241) (width 0.109) (layer "In6.Cu") (net 214))
  (segment (start 77.8225 115.312814) (end 77.2125 114.702814) (width 0.109) (layer "In6.Cu") (net 214))
  (segment (start 79.740202 125.985894) (end 79.644729 125.985894) (width 0.109) (layer "In6.Cu") (net 214))
  (segment (start 83.807796 127.723372) (end 83.764679 127.713531) (width 0.109) (layer "In6.Cu") (net 214))
  (segment (start 78.31258 124.653745) (end 78.31258 124.558272) (width 0.109) (layer "In6.Cu") (net 214))
  (segment (start 84.522148 128.68937) (end 83.670883 129.540638) (width 0.109) (layer "In6.Cu") (net 214))
  (segment (start 79.231815 125.57298) (end 79.231815 125.477507) (width 0.109) (layer "In6.Cu") (net 214))
  (segment (start 81.132953 127.590547) (end 81.091529 127.504529) (width 0.109) (layer "In6.Cu") (net 214))
  (segment (start 81.181117 125.174194) (end 81.181118 125.12997) (width 0.109) (layer "In6.Cu") (net 214))
  (segment (start 89.4415 134.759) (end 89.2565 134.574) (width 0.109) (layer "In6.Cu") (net 214))
  (segment (start 78.546396 125.00399) (end 78.471752 124.944463) (width 0.109) (layer "In6.Cu") (net 214))
  (segment (start 81.799019 125.90409) (end 81.764443 125.931665) (width 0.109) (layer "In6.Cu") (net 214))
  (segment (start 80.205278 124.372499) (end 80.232853 124.337923) (width 0.109) (layer "In6.Cu") (net 214))
  (segment (start 84.596384 129.776697) (end 84.536858 129.702053) (width 0.109) (layer "In6.Cu") (net 214))
  (segment (start 81.070285 127.315977) (end 81.091529 127.222897) (width 0.109) (layer "In6.Cu") (net 214))
  (segment (start 79.465631 125.923225) (end 79.390987 125.863698) (width 0.109) (layer "In6.Cu") (net 214))
  (segment (start 78.667418 124.064886) (end 78.686607 124.02504) (width 0.109) (layer "In6.Cu") (net 214))
  (segment (start 80.879784 124.984855) (end 80.845208 125.01243) (width 0.109) (layer "In6.Cu") (net 214))
  (segment (start 82.043748 126.210969) (end 82.071323 126.176393) (width 0.109) (layer "In6.Cu") (net 214))
  (segment (start 84.536858 129.702053) (end 84.495434 129.616035) (width 0.109) (layer "In6.Cu") (net 214))
  (segment (start 82.071323 126.176393) (end 82.090511 126.136546) (width 0.109) (layer "In6.Cu") (net 214))
  (segment (start 80.659437 126.905129) (end 80.563964 126.905129) (width 0.109) (layer "In6.Cu") (net 214))
  (segment (start 81.19248 127.062235) (end 82.043748 126.210969) (width 0.109) (layer "In6.Cu") (net 214))
  (segment (start 81.006974 124.955826) (end 80.962748 124.955826) (width 0.109) (layer "In6.Cu") (net 214))
  (segment (start 80.213718 126.217644) (end 80.273245 126.143) (width 0.109) (layer "In6.Cu") (net 214))
  (segment (start 84.766876 128.661795) (end 84.727031 128.642607) (width 0.109) (layer "In6.Cu") (net 214))
  (segment (start 78.639844 124.099463) (end 78.667418 124.064886) (width 0.109) (layer "In6.Cu") (net 214))
  (segment (start 82.845444 126.794296) (end 82.801218 126.794296) (width 0.109) (layer "In6.Cu") (net 214))
  (segment (start 82.929999 129.342999) (end 82.908755 129.24992) (width 0.109) (layer "In6.Cu") (net 214))
  (segment (start 81.124513 125.291734) (end 81.152088 125.257158) (width 0.109) (layer "In6.Cu") (net 214))
  (segment (start 82.148692 128.621403) (end 82.111715 128.584426) (width 0.109) (layer "In6.Cu") (net 214))
  (segment (start 82.309354 128.722354) (end 82.223336 128.68093) (width 0.109) (layer "In6.Cu") (net 214))
  (segment (start 82.111715 128.584426) (end 82.052188 128.509782) (width 0.109) (layer "In6.Cu") (net 214))
  (segment (start 83.03095 129.503661) (end 82.971423 129.429017) (width 0.109) (layer "In6.Cu") (net 214))
  (segment (start 81.757769 127.761695) (end 81.671751 127.803119) (width 0.109) (layer "In6.Cu") (net 214))
  (segment (start 78.820967 125.066659) (end 78.725494 125.066659) (width 0.109) (layer "In6.Cu") (net 214))
  (segment (start 81.881983 125.875061) (end 81.838866 125.884902) (width 0.109) (layer "In6.Cu") (net 214))
  (segment (start 78.914046 125.045414) (end 78.820967 125.066659) (width 0.109) (layer "In6.Cu") (net 214))
  (segment (start 84.858057 128.851134) (end 84.858058 128.80691) (width 0.109) (layer "In6.Cu") (net 214))
  (segment (start 83.938822 127.931899) (end 83.938823 127.887675) (width 0.109) (layer "In6.Cu") (net 214))
  (segment (start 82.801218 126.794296) (end 82.758101 126.804137) (width 0.109) (layer "In6.Cu") (net 214))
  (segment (start 82.751648 128.621403) (end 82.677004 128.68093) (width 0.109) (layer "In6.Cu") (net 214))
  (segment (start 81.171277 125.086853) (end 81.152087 125.047006) (width 0.109) (layer "In6.Cu") (net 214))
  (segment (start 78.8045 110.575967) (end 78.975 110.405467) (width 0.109) (layer "In6.Cu") (net 214))
  (segment (start 80.962748 124.955826) (end 80.919631 124.965667) (width 0.109) (layer "In6.Cu") (net 214))
  (segment (start 82.590986 128.722354) (end 82.497907 128.743599) (width 0.109) (layer "In6.Cu") (net 214))
  (segment (start 80.518975 125.338662) (end 79.993943 125.863698) (width 0.109) (layer "In6.Cu") (net 214))
  (segment (start 80.213718 126.671312) (end 80.172294 126.585294) (width 0.109) (layer "In6.Cu") (net 214))
  (segment (start 81.764443 125.931665) (end 81.43821 126.257897) (width 0.109) (layer "In6.Cu") (net 214))
  (segment (start 82.718254 126.823325) (end 82.683678 126.8509) (width 0.109) (layer "In6.Cu") (net 214))
  (segment (start 89.2565 134.569) (end 88.398686 134.569) (width 0.109) (layer "In6.Cu") (net 214))
  (segment (start 82.888561 126.804137) (end 82.845444 126.794296) (width 0.109) (layer "In6.Cu") (net 214))
  (segment (start 80.563964 126.905129) (end 80.470884 126.883884) (width 0.109) (layer "In6.Cu") (net 214))
  (segment (start 83.637489 127.74256) (end 83.602913 127.770135) (width 0.109) (layer "In6.Cu") (net 214))
  (segment (start 82.090511 126.136546) (end 82.100352 126.093429) (width 0.109) (layer "In6.Cu") (net 214))
  (segment (start 79.960549 124.06562) (end 79.925973 124.093195) (width 0.109) (layer "In6.Cu") (net 214))
  (segment (start 82.043749 125.931665) (end 82.009171 125.90409) (width 0.109) (layer "In6.Cu") (net 214))
  (segment (start 83.321669 129.662834) (end 83.228589 129.641589) (width 0.109) (layer "In6.Cu") (net 214))
  (segment (start 82.971423 128.975349) (end 83.03095 128.900705) (width 0.109) (layer "In6.Cu") (net 214))
  (segment (start 79.644729 125.985894) (end 79.551649 125.964649) (width 0.109) (layer "In6.Cu") (net 214))
  (segment (start 77.2125 111.017186) (end 77.653719 110.575967) (width 0.109) (layer "In6.Cu") (net 214))
  (segment (start 77.2125 114.702814) (end 77.2125 111.017186) (width 0.109) (layer "In6.Cu") (net 214))
  (segment (start 83.228589 129.641589) (end 83.142571 129.600165) (width 0.109) (layer "In6.Cu") (net 214))
  (segment (start 83.764679 127.713531) (end 83.720453 127.713531) (width 0.109) (layer "In6.Cu") (net 214))
  (segment (start 83.596239 129.600165) (end 83.510221 129.641589) (width 0.109) (layer "In6.Cu") (net 214))
  (segment (start 78.333825 124.465193) (end 78.375249 124.379174) (width 0.109) (layer "In6.Cu") (net 214))
  (segment (start 86.9725 133.142814) (end 86.9725 132.152813) (width 0.109) (layer "In6.Cu") (net 214))
  (segment (start 79.231815 125.477507) (end 79.253059 125.384427) (width 0.109) (layer "In6.Cu") (net 214))
  (segment (start 79.390987 125.863698) (end 79.35401 125.826721) (width 0.109) (layer "In6.Cu") (net 214))
  (segment (start 80.252041 124.298076) (end 80.261882 124.254959) (width 0.109) (layer "In6.Cu") (net 214))
  (segment (start 81.969326 125.884902) (end 81.926209 125.875061) (width 0.109) (layer "In6.Cu") (net 214))
  (segment (start 80.232853 124.337923) (end 80.252041 124.298076) (width 0.109) (layer "In6.Cu") (net 214))
  (segment (start 83.928981 127.975016) (end 83.938822 127.931899) (width 0.109) (layer "In6.Cu") (net 214))
  (segment (start 89.2565 134.574) (end 89.2565 134.569) (width 0.109) (layer "In6.Cu") (net 214))
  (segment (start 81.578672 127.824364) (end 81.483199 127.824364) (width 0.109) (layer "In6.Cu") (net 214))
  (segment (start 81.070285 127.41145) (end 81.070285 127.315977) (width 0.109) (layer "In6.Cu") (net 214))
  (segment (start 78.667418 123.854734) (end 78.639844 123.820157) (width 0.109) (layer "In6.Cu") (net 214))
  (segment (start 82.683678 126.8509) (end 82.357445 127.177132) (width 0.109) (layer "In6.Cu") (net 214))
  (segment (start 82.357445 127.177132) (end 81.832413 127.702168) (width 0.109) (layer "In6.Cu") (net 214))
  (segment (start 82.100352 126.093429) (end 82.100353 126.049205) (width 0.109) (layer "In6.Cu") (net 214))
  (segment (start 80.919631 124.965667) (end 80.879784 124.984855) (width 0.109) (layer "In6.Cu") (net 214))
  (segment (start 80.205279 124.093195) (end 80.170701 124.06562) (width 0.109) (layer "In6.Cu") (net 214))
  (segment (start 79.000064 125.00399) (end 78.914046 125.045414) (width 0.109) (layer "In6.Cu") (net 214))
  (segment (start 80.172294 126.303662) (end 80.213718 126.217644) (width 0.109) (layer "In6.Cu") (net 214))
  (segment (start 82.052188 128.056114) (end 82.111715 127.98147) (width 0.109) (layer "In6.Cu") (net 214))
  (segment (start 82.929999 129.061367) (end 82.971423 128.975349) (width 0.109) (layer "In6.Cu") (net 214))
  (segment (start 78.333825 124.746824) (end 78.31258 124.653745) (width 0.109) (layer "In6.Cu") (net 214))
  (segment (start 80.087739 124.036591) (end 80.043513 124.036591) (width 0.109) (layer "In6.Cu") (net 214))
  (segment (start 83.938823 127.887675) (end 83.928982 127.844558) (width 0.109) (layer "In6.Cu") (net 214))
  (segment (start 79.294483 125.298409) (end 79.35401 125.223765) (width 0.109) (layer "In6.Cu") (net 214))
  (segment (start 82.677004 128.68093) (end 82.590986 128.722354) (width 0.109) (layer "In6.Cu") (net 214))
  (segment (start 83.720453 127.713531) (end 83.677336 127.723372) (width 0.109) (layer "In6.Cu") (net 214))
  (segment (start 83.909792 127.804711) (end 83.882219 127.770135) (width 0.109) (layer "In6.Cu") (net 214))
  (segment (start 79.919299 125.923225) (end 79.833281 125.964649) (width 0.109) (layer "In6.Cu") (net 214))
  (segment (start 82.009171 125.90409) (end 81.969326 125.884902) (width 0.109) (layer "In6.Cu") (net 214))
  (segment (start 80.261883 124.210735) (end 80.252042 124.167618) (width 0.109) (layer "In6.Cu") (net 214))
  (segment (start 78.375249 124.379174) (end 78.434775 124.304531) (width 0.109) (layer "In6.Cu") (net 214))
  (segment (start 81.229457 127.702168) (end 81.19248 127.665191) (width 0.109) (layer "In6.Cu") (net 214))
  (segment (start 83.928982 127.844558) (end 83.909792 127.804711) (width 0.109) (layer "In6.Cu") (net 214))
  (segment (start 78.639844 123.820157) (end 77.8225 123.002814) (width 0.109) (layer "In6.Cu") (net 214))
  (segment (start 81.926209 125.875061) (end 81.881983 125.875061) (width 0.109) (layer "In6.Cu") (net 214))
  (segment (start 83.882218 128.049439) (end 83.909793 128.014863) (width 0.109) (layer "In6.Cu") (net 214))
  (segment (start 82.100353 126.049205) (end 82.090512 126.006088) (width 0.109) (layer "In6.Cu") (net 214))
  (segment (start 80.310222 126.782933) (end 80.273245 126.745956) (width 0.109) (layer "In6.Cu") (net 214))
  (segment (start 78.696448 123.937697) (end 78.686607 123.89458) (width 0.109) (layer "In6.Cu") (net 214))
  (segment (start 81.152087 125.047006) (end 81.124514 125.01243) (width 0.109) (layer "In6.Cu") (net 214))
  (segment (start 83.882219 127.770135) (end 83.847641 127.74256) (width 0.109) (layer "In6.Cu") (net 214))
  (segment (start 84.47419 129.427484) (end 84.495435 129.334405) (width 0.109) (layer "In6.Cu") (net 214))
  (segment (start 83.670883 129.540638) (end 83.596239 129.600165) (width 0.109) (layer "In6.Cu") (net 214))
  (segment (start 81.050091 124.965667) (end 81.006974 124.955826) (width 0.109) (layer "In6.Cu") (net 214))
  (segment (start 81.98952 128.330685) (end 81.98952 128.235212) (width 0.109) (layer "In6.Cu") (net 214))
  (segment (start 82.497907 128.743599) (end 82.402434 128.743599) (width 0.109) (layer "In6.Cu") (net 214))
  (segment (start 83.510221 129.641589) (end 83.417142 129.662834) (width 0.109) (layer "In6.Cu") (net 214))
  (segment (start 80.15105 126.492215) (end 80.15105 126.396742) (width 0.109) (layer "In6.Cu") (net 214))
  (segment (start 83.602913 127.770135) (end 83.27668 128.096367) (width 0.109) (layer "In6.Cu") (net 214))
  (segment (start 81.089936 124.984855) (end 81.050091 124.965667) (width 0.109) (layer "In6.Cu") (net 214))
  (segment (start 79.074708 124.944463) (end 79.000064 125.00399) (width 0.109) (layer "In6.Cu") (net 214))
  (segment (start 83.909793 128.014863) (end 83.928981 127.975016) (width 0.109) (layer "In6.Cu") (net 214))
  (segment (start 79.833281 125.964649) (end 79.740202 125.985894) (width 0.109) (layer "In6.Cu") (net 214))
  (segment (start 88.398686 134.569) (end 86.9725 133.142814) (width 0.109) (layer "In6.Cu") (net 214))
  (segment (start 83.142571 129.600165) (end 83.067927 129.540638) (width 0.109) (layer "In6.Cu") (net 214))
  (segment (start 80.261882 124.254959) (end 80.261883 124.210735) (width 0.109) (layer "In6.Cu") (net 214))
  (segment (start 80.273245 126.745956) (end 80.213718 126.671312) (width 0.109) (layer "In6.Cu") (net 214))
  (segment (start 84.801453 128.968674) (end 84.829028 128.934098) (width 0.109) (layer "In6.Cu") (net 214))
  (segment (start 81.091529 127.222897) (end 81.132953 127.136879) (width 0.109) (layer "In6.Cu") (net 214))
  (segment (start 82.962983 127.130204) (end 82.990558 127.095628) (width 0.109) (layer "In6.Cu") (net 214))
  (segment (start 80.470884 126.883884) (end 80.384866 126.84246) (width 0.109) (layer "In6.Cu") (net 214))
  (segment (start 79.253059 125.384427) (end 79.294483 125.298409) (width 0.109) (layer "In6.Cu") (net 214))
  (segment (start 80.043513 124.036591) (end 80.000396 124.046432) (width 0.109) (layer "In6.Cu") (net 214))
  (segment (start 84.801454 128.68937) (end 84.766876 128.661795) (width 0.109) (layer "In6.Cu") (net 214))
  (segment (start 82.908755 129.154447) (end 82.929999 129.061367) (width 0.109) (layer "In6.Cu") (net 214))
  (segment (start 84.848216 128.894251) (end 84.858057 128.851134) (width 0.109) (layer "In6.Cu") (net 214))
  (segment (start 81.304101 127.761695) (end 81.229457 127.702168) (width 0.109) (layer "In6.Cu") (net 214))
  (segment (start 83.03095 128.900705) (end 83.882218 128.049439) (width 0.109) (layer "In6.Cu") (net 214))
  (segment (start 84.829028 128.934098) (end 84.848216 128.894251) (width 0.109) (layer "In6.Cu") (net 214))
  (segment (start 80.232852 124.127771) (end 80.205279 124.093195) (width 0.109) (layer "In6.Cu") (net 214))
  (segment (start 82.928406 126.823325) (end 82.888561 126.804137) (width 0.109) (layer "In6.Cu") (net 214))
  (segment (start 78.725494 125.066659) (end 78.632414 125.045414) (width 0.109) (layer "In6.Cu") (net 214))
  (segment (start 82.990557 126.885476) (end 82.962984 126.8509) (width 0.109) (layer "In6.Cu") (net 214))
  (segment (start 77.8225 123.002814) (end 77.8225 115.312814) (width 0.109) (layer "In6.Cu") (net 214))
  (segment (start 82.071322 125.966241) (end 82.043749 125.931665) (width 0.109) (layer "In6.Cu") (net 214))
  (segment (start 84.858058 128.80691) (end 84.848217 128.763793) (width 0.109) (layer "In6.Cu") (net 214))
  (segment (start 82.052188 128.509782) (end 82.010764 128.423764) (width 0.109) (layer "In6.Cu") (net 214))
  (segment (start 82.223336 128.68093) (end 82.148692 128.621403) (width 0.109) (layer "In6.Cu") (net 214))
  (segment (start 84.495434 129.616035) (end 84.474189 129.522956) (width 0.109) (layer "In6.Cu") (net 214))
  (segment (start 82.990558 127.095628) (end 83.009746 127.055781) (width 0.109) (layer "In6.Cu") (net 214))
  (segment (start 79.294483 125.752077) (end 79.253059 125.666059) (width 0.109) (layer "In6.Cu") (net 214))
  (segment (start 80.384866 126.84246) (end 80.310222 126.782933) (width 0.109) (layer "In6.Cu") (net 214))
  (segment (start 79.35401 125.826721) (end 79.294483 125.752077) (width 0.109) (layer "In6.Cu") (net 214))
  (segment (start 84.596385 129.173743) (end 84.801453 128.968674) (width 0.109) (layer "In6.Cu") (net 214))
  (segment (start 81.98952 128.235212) (end 82.010764 128.142132) (width 0.109) (layer "In6.Cu") (net 214))
  (segment (start 83.27668 128.096367) (end 82.751648 128.621403) (width 0.109) (layer "In6.Cu") (net 214))
  (segment (start 86.9725 132.152813) (end 84.596384 129.776697) (width 0.109) (layer "In6.Cu") (net 214))
  (segment (start 81.43821 126.257897) (end 80.913178 126.782933) (width 0.109) (layer "In6.Cu") (net 214))
  (segment (start 80.170701 124.06562) (end 80.130856 124.046432) (width 0.109) (layer "In6.Cu") (net 214))
  (segment (start 82.962984 126.8509) (end 82.928406 126.823325) (width 0.109) (layer "In6.Cu") (net 214))
  (segment (start 84.536858 129.248385) (end 84.596385 129.173743) (width 0.109) (layer "In6.Cu") (net 214))
  (segment (start 81.171276 125.217311) (end 81.181117 125.174194) (width 0.109) (layer "In6.Cu") (net 214))
  (segment (start 82.010764 128.142132) (end 82.052188 128.056114) (width 0.109) (layer "In6.Cu") (net 214))
  (segment (start 83.009746 127.055781) (end 83.019587 127.012664) (width 0.109) (layer "In6.Cu") (net 214))
  (segment (start 83.019588 126.96844) (end 83.009747 126.925323) (width 0.109) (layer "In6.Cu") (net 214))
  (segment (start 81.671751 127.803119) (end 81.578672 127.824364) (width 0.109) (layer "In6.Cu") (net 214))
  (segment (start 78.696448 123.981923) (end 78.696448 123.937697) (width 0.109) (layer "In6.Cu") (net 214))
  (segment (start 78.632414 125.045414) (end 78.546396 125.00399) (width 0.109) (layer "In6.Cu") (net 214))
  (segment (start 80.172294 126.585294) (end 80.15105 126.492215) (width 0.109) (layer "In6.Cu") (net 214))
  (segment (start 84.683914 128.632766) (end 84.639688 128.632766) (width 0.109) (layer "In6.Cu") (net 214))
  (segment (start 81.124514 125.01243) (end 81.089936 124.984855) (width 0.109) (layer "In6.Cu") (net 214))
  (segment (start 78.434775 124.907486) (end 78.375249 124.832842) (width 0.109) (layer "In6.Cu") (net 214))
  (segment (start 81.832413 127.702168) (end 81.757769 127.761695) (width 0.109) (layer "In6.Cu") (net 214))
  (segment (start 82.908755 129.24992) (end 82.908755 129.154447) (width 0.109) (layer "In6.Cu") (net 214))
  (segment (start 80.273245 126.143) (end 81.124513 125.291734) (width 0.109) (layer "In6.Cu") (net 214))
  (segment (start 81.19248 127.665191) (end 81.132953 127.590547) (width 0.109) (layer "In6.Cu") (net 214))
  (segment (start 81.181118 125.12997) (end 81.171277 125.086853) (width 0.109) (layer "In6.Cu") (net 214))
  (segment (start 83.847641 127.74256) (end 83.807796 127.723372) (width 0.109) (layer "In6.Cu") (net 214))
  (segment (start 84.829027 128.723946) (end 84.801454 128.68937) (width 0.109) (layer "In6.Cu") (net 214))
  (segment (start 84.474189 129.522956) (end 84.47419 129.427484) (width 0.109) (layer "In6.Cu") (net 214))
  (segment (start 77.653719 110.575967) (end 78.8045 110.575967) (width 0.109) (layer "In6.Cu") (net 214))
  (segment (start 82.111715 127.98147) (end 82.962983 127.130204) (width 0.109) (layer "In6.Cu") (net 214))
  (segment (start 80.130856 124.046432) (end 80.087739 124.036591) (width 0.109) (layer "In6.Cu") (net 214))
  (segment (start 80.913178 126.782933) (end 80.838534 126.84246) (width 0.109) (layer "In6.Cu") (net 214))
  (segment (start 78.31258 124.558272) (end 78.333825 124.465193) (width 0.109) (layer "In6.Cu") (net 214))
  (segment (start 84.596571 128.642607) (end 84.556724 128.661795) (width 0.109) (layer "In6.Cu") (net 214))
  (segment (start 80.845208 125.01243) (end 80.518975 125.338662) (width 0.109) (layer "In6.Cu") (net 214))
  (segment (start 78.375249 124.832842) (end 78.333825 124.746824) (width 0.109) (layer "In6.Cu") (net 214))
  (segment (start 83.417142 129.662834) (end 83.321669 129.662834) (width 0.109) (layer "In6.Cu") (net 214))
  (segment (start 83.677336 127.723372) (end 83.637489 127.74256) (width 0.109) (layer "In6.Cu") (net 214))
  (segment (start 79.35401 125.223765) (end 80.205278 124.372499) (width 0.109) (layer "In6.Cu") (net 214))
  (segment (start 78.471752 124.944463) (end 78.434775 124.907486) (width 0.109) (layer "In6.Cu") (net 214))
  (segment (start 84.639688 128.632766) (end 84.596571 128.642607) (width 0.109) (layer "In6.Cu") (net 214))
  (segment (start 81.483199 127.824364) (end 81.390119 127.803119) (width 0.109) (layer "In6.Cu") (net 214))
  (segment (start 80.838534 126.84246) (end 80.752516 126.883884) (width 0.109) (layer "In6.Cu") (net 214))
  (segment (start 81.091529 127.504529) (end 81.070285 127.41145) (width 0.109) (layer "In6.Cu") (net 214))
  (segment (start 81.132953 127.136879) (end 81.19248 127.062235) (width 0.109) (layer "In6.Cu") (net 214))
  (segment (start 84.495435 129.334405) (end 84.536858 129.248385) (width 0.109) (layer "In6.Cu") (net 214))
  (segment (start 82.758101 126.804137) (end 82.718254 126.823325) (width 0.109) (layer "In6.Cu") (net 214))
  (segment (start 80.15105 126.396742) (end 80.172294 126.303662) (width 0.109) (layer "In6.Cu") (net 214))
  (segment (start 83.067927 129.540638) (end 83.03095 129.503661) (width 0.109) (layer "In6.Cu") (net 214))
  (segment (start 80.000396 124.046432) (end 79.960549 124.06562) (width 0.109) (layer "In6.Cu") (net 214))
  (segment (start 78.686607 123.89458) (end 78.667418 123.854734) (width 0.109) (layer "In6.Cu") (net 214))
  (segment (start 83.019587 127.012664) (end 83.019588 126.96844) (width 0.109) (layer "In6.Cu") (net 214))
  (segment (start 79.925973 124.093195) (end 79.074708 124.944463) (width 0.109) (layer "In6.Cu") (net 214))
  (segment (start 84.556724 128.661795) (end 84.522148 128.68937) (width 0.109) (layer "In6.Cu") (net 214))
  (segment (start 84.848217 128.763793) (end 84.829027 128.723946) (width 0.109) (layer "In6.Cu") (net 214))
  (segment (start 83.009747 126.925323) (end 82.990557 126.885476) (width 0.109) (layer "In6.Cu") (net 214))
  (segment (start 81.9 111.75) (end 80.999999 111.75) (width 0.182) (layer "B.Cu") (net 214))
  (segment (start 80.443992 111.401702) (end 80.443992 111.055751) (width 0.182) (layer "B.Cu") (net 214))
  (segment (start 79.084 110.514467) (end 78.975 110.405467) (width 0.182) (layer "B.Cu") (net 214))
  (segment (start 80.938999 111.811) (end 80.85329 111.811) (width 0.182) (layer "B.Cu") (net 214))
  (segment (start 80.443992 111.055751) (end 79.902708 110.514467) (width 0.182) (layer "B.Cu") (net 214))
  (segment (start 80.85329 111.811) (end 80.443992 111.401702) (width 0.182) (layer "B.Cu") (net 214))
  (segment (start 79.902708 110.514467) (end 79.084 110.514467) (width 0.182) (layer "B.Cu") (net 214))
  (segment (start 80.999999 111.75) (end 80.938999 111.811) (width 0.182) (layer "B.Cu") (net 214))
  (segment (start 89.4415 134.124) (end 89.8265 133.814) (width 0.182) (layer "F.Cu") (net 215))
  (via (at 89.4415 134.124) (size 0.45) (drill 0.1) (layers "F.Cu" "B.Cu") (net 215))
  (via (at 78.975 111.001468) (size 0.45) (drill 0.1) (layers "F.Cu" "B.Cu") (net 215))
  (segment (start 85.101207 128.688207) (end 85.059783 128.602189) (width 0.109) (layer "In6.Cu") (net 215))
  (segment (start 85.101207 128.969839) (end 85.122452 128.87676) (width 0.109) (layer "In6.Cu") (net 215))
  (segment (start 80.526277 124.280585) (end 80.526276 124.185111) (width 0.109) (layer "In6.Cu") (net 215))
  (segment (start 89.2565 134.309) (end 89.2565 134.314) (width 0.109) (layer "In6.Cu") (net 215))
  (segment (start 81.596164 127.550129) (end 81.553047 127.55997) (width 0.109) (layer "In6.Cu") (net 215))
  (segment (start 82.364747 126.119055) (end 82.364746 126.023581) (width 0.109) (layer "In6.Cu") (net 215))
  (segment (start 88.27119 133.878093) (end 88.251015 133.887809) (width 0.109) (layer "In6.Cu") (net 215))
  (segment (start 77.4675 111.7675) (end 77.4675 111.122814) (width 0.109) (layer "In6.Cu") (net 215))
  (segment (start 78.751117 124.802266) (end 78.708 124.792425) (width 0.109) (layer "In6.Cu") (net 215))
  (segment (start 80.444473 126.339402) (end 80.472047 126.304825) (width 0.109) (layer "In6.Cu") (net 215))
  (segment (start 84.738583 129.453108) (end 84.748424 129.409991) (width 0.109) (layer "In6.Cu") (net 215))
  (segment (start 78.878305 124.773236) (end 78.838459 124.792425) (width 0.109) (layer "In6.Cu") (net 215))
  (segment (start 82.224063 126.391285) (end 82.24255 126.372795) (width 0.109) (layer "In6.Cu") (net 215))
  (segment (start 81.63601 127.53094) (end 81.596164 127.550129) (width 0.109) (layer "In6.Cu") (net 215))
  (segment (start 79.552812 125.664896) (end 79.525238 125.630319) (width 0.109) (layer "In6.Cu") (net 215))
  (segment (start 83.883382 127.470382) (end 83.790302 127.449137) (width 0.109) (layer "In6.Cu") (net 215))
  (segment (start 78.080232 122.370754) (end 78.0775 122.3465) (width 0.109) (layer "In6.Cu") (net 215))
  (segment (start 78.633577 124.745662) (end 78.606003 124.711085) (width 0.109) (layer "In6.Cu") (net 215))
  (segment (start 80.505032 124.092032) (end 80.463608 124.006014) (width 0.109) (layer "In6.Cu") (net 215))
  (segment (start 80.385593 124.552815) (end 80.40408 124.534325) (width 0.109) (layer "In6.Cu") (net 215))
  (segment (start 83.182989 129.267413) (end 83.173148 129.224296) (width 0.109) (layer "In6.Cu") (net 215))
  (segment (start 77.54839 111.868932) (end 77.5264 111.861237) (width 0.109) (layer "In6.Cu") (net 215))
  (segment (start 77.616683 112.179237) (end 77.63641 112.166842) (width 0.109) (layer "In6.Cu") (net 215))
  (segment (start 78.139206 122.444705) (end 78.118539 122.431719) (width 0.109) (layer "In6.Cu") (net 215))
  (segment (start 83.173148 129.224296) (end 83.173148 129.18007) (width 0.109) (layer "In6.Cu") (net 215))
  (segment (start 78.0775 122.897186) (end 78.0775 122.7825) (width 0.109) (layer "In6.Cu") (net 215))
  (segment (start 82.472282 128.479205) (end 82.428057 128.479205) (width 0.109) (layer "In6.Cu") (net 215))
  (segment (start 85.000255 128.527544) (end 84.963278 128.490567) (width 0.109) (layer "In6.Cu") (net 215))
  (segment (start 77.675582 111.975582) (end 77.672974 111.95243) (width 0.109) (layer "In6.Cu") (net 215))
  (segment (start 84.203217 127.957525) (end 84.203216 127.862051) (width 0.109) (layer "In6.Cu") (net 215))
  (segment (start 88.374929 133.901771) (end 88.357421 133.887809) (width 0.109) (layer "In6.Cu") (net 215))
  (segment (start 88.215999 133.915732) (end 88.195824 133.925448) (width 0.109) (layer "In6.Cu") (net 215))
  (segment (start 84.203216 127.862051) (end 84.181972 127.768972) (width 0.109) (layer "In6.Cu") (net 215))
  (segment (start 82.13093 125.673336) (end 82.044912 125.631912) (width 0.109) (layer "In6.Cu") (net 215))
  (segment (start 83.124808 126.652097) (end 83.050165 126.592571) (width 0.109) (layer "In6.Cu") (net 215))
  (segment (start 78.10128 122.714539) (end 78.118539 122.69728) (width 0.109) (layer "In6.Cu") (net 215))
  (segment (start 83.202178 129.097107) (end 83.229752 129.06253) (width 0.109) (layer "In6.Cu") (net 215))
  (segment (start 88.293021 133.87311) (end 88.27119 133.878093) (width 0.109) (layer "In6.Cu") (net 215))
  (segment (start 77.665279 111.93044) (end 77.652884 111.910713) (width 0.109) (layer "In6.Cu") (net 215))
  (segment (start 84.767614 129.580298) (end 84.748425 129.540451) (width 0.109) (layer "In6.Cu") (net 215))
  (segment (start 82.521854 126.652099) (end 81.670587 127.503366) (width 0.109) (layer "In6.Cu") (net 215))
  (segment (start 78.708 124.792425) (end 78.668154 124.773236) (width 0.109) (layer "In6.Cu") (net 215))
  (segment (start 78.088294 122.735206) (end 78.10128 122.714539) (width 0.109) (layer "In6.Cu") (net 215))
  (segment (start 80.633812 126.640735) (end 80.589587 126.640735) (width 0.109) (layer "In6.Cu") (net 215))
  (segment (start 79.587389 125.69247) (end 79.552812 125.664896) (width 0.109) (layer "In6.Cu") (net 215))
  (segment (start 81.334678 127.385826) (end 81.334678 127.3416) (width 0.109) (layer "In6.Cu") (net 215))
  (segment (start 77.665279 112.130641) (end 77.672974 112.108651) (width 0.109) (layer "In6.Cu") (net 215))
  (segment (start 83.202178 129.307259) (end 83.182989 129.267413) (width 0.109) (layer "In6.Cu") (net 215))
  (segment (start 80.844045 124.712677) (end 80.758027 124.754101) (width 0.109) (layer "In6.Cu") (net 215))
  (segment (start 78.351917 122.611793) (end 78.359979 122.588754) (width 0.109) (layer "In6.Cu") (net 215))
  (segment (start 78.668154 124.773236) (end 78.633577 124.745662) (width 0.109) (layer "In6.Cu") (net 215))
  (segment (start 82.589822 128.422601) (end 82.555245 128.450175) (width 0.109) (layer "In6.Cu") (net 215))
  (segment (start 83.221313 127.217387) (end 83.262737 127.131369) (width 0.109) (layer "In6.Cu") (net 215))
  (segment (start 78.301005 122.466294) (end 78.277966 122.458232) (width 0.109) (layer "In6.Cu") (net 215))
  (segment (start 80.415443 126.422365) (end 80.425284 126.379248) (width 0.109) (layer "In6.Cu") (net 215))
  (segment (start 83.347292 129.39844) (end 83.304175 129.388599) (width 0.109) (layer "In6.Cu") (net 215))
  (segment (start 78.795342 124.802266) (end 78.751117 124.802266) (width 0.109) (layer "In6.Cu") (net 215))
  (segment (start 78.139206 122.684294) (end 78.162245 122.676232) (width 0.109) (layer "In6.Cu") (net 215))
  (segment (start 82.310517 128.143295) (end 83.143298 127.31052) (width 0.109) (layer "In6.Cu") (net 215))
  (segment (start 78.838459 124.792425) (end 78.795342 124.802266) (width 0.109) (layer "In6.Cu") (net 215))
  (segment (start 83.515732 127.511806) (end 83.441089 127.571334) (width 0.109) (layer "In6.Cu") (net 215))
  (segment (start 80.505032 124.373664) (end 80.526277 124.280585) (width 0.109) (layer "In6.Cu") (net 215))
  (segment (start 78.898172 124.186644) (end 78.939597 124.100626) (width 0.109) (layer "In6.Cu") (net 215))
  (segment (start 83.182989 129.136953) (end 83.202178 129.097107) (width 0.109) (layer "In6.Cu") (net 215))
  (segment (start 81.76328 125.631912) (end 81.677262 125.673336) (width 0.109) (layer "In6.Cu") (net 215))
  (segment (start 88.109593 133.915732) (end 88.092085 133.901771) (width 0.109) (layer "In6.Cu") (net 215))
  (segment (start 81.951832 125.610667) (end 81.85636 125.610668) (width 0.109) (layer "In6.Cu") (net 215))
  (segment (start 78.586814 124.671238) (end 78.576973 124.628122) (width 0.109) (layer "In6.Cu") (net 215))
  (segment (start 88.129768 133.925448) (end 88.109593 133.915732) (width 0.109) (layer "In6.Cu") (net 215))
  (segment (start 81.334678 127.3416) (end 81.344519 127.298483) (width 0.109) (layer "In6.Cu") (net 215))
  (segment (start 80.113362 123.772197) (end 80.01789 123.772198) (width 0.109) (layer "In6.Cu") (net 215))
  (segment (start 84.062533 128.229755) (end 84.08102 128.211265) (width 0.109) (layer "In6.Cu") (net 215))
  (segment (start 81.602619 125.732864) (end 80.751352 126.584131) (width 0.109) (layer "In6.Cu") (net 215))
  (segment (start 79.506049 125.460013) (end 79.525238 125.420167) (width 0.109) (layer "In6.Cu") (net 215))
  (segment (start 82.310517 128.422601) (end 82.282943 128.388024) (width 0.109) (layer "In6.Cu") (net 215))
  (segment (start 88.251015 133.887809) (end 88.215999 133.915732) (width 0.109) (layer "In6.Cu") (net 215))
  (segment (start 82.302078 126.298152) (end 82.343502 126.212134) (width 0.109) (layer "In6.Cu") (net 215))
  (segment (start 78.586814 124.540779) (end 78.606003 124.500933) (width 0.109) (layer "In6.Cu") (net 215))
  (segment (start 83.391517 129.39844) (end 83.347292 129.39844) (width 0.109) (layer "In6.Cu") (net 215))
  (segment (start 80.472047 126.304825) (end 81.304828 125.47205) (width 0.109) (layer "In6.Cu") (net 215))
  (segment (start 80.683384 124.813629) (end 79.832117 125.664896) (width 0.109) (layer "In6.Cu") (net 215))
  (segment (start 82.343502 125.930502) (end 82.302078 125.844484) (width 0.109) (layer "In6.Cu") (net 215))
  (segment (start 78.838646 124.261288) (end 78.898172 124.186644) (width 0.109) (layer "In6.Cu") (net 215))
  (segment (start 78.162245 122.676232) (end 78.1865 122.6735) (width 0.109) (layer "In6.Cu") (net 215))
  (segment (start 77.5264 111.861237) (end 77.506673 111.848842) (width 0.109) (layer "In6.Cu") (net 215))
  (segment (start 83.161785 126.689074) (end 83.124808 126.652097) (width 0.109) (layer "In6.Cu") (net 215))
  (segment (start 78.606003 124.711085) (end 78.586814 124.671238) (width 0.109) (layer "In6.Cu") (net 215))
  (segment (start 80.526276 124.185111) (end 80.505032 124.092032) (width 0.109) (layer "In6.Cu") (net 215))
  (segment (start 77.4675 112.293582) (end 77.470109 112.27043) (width 0.109) (layer "In6.Cu") (net 215))
  (segment (start 83.229752 129.341836) (end 83.202178 129.307259) (width 0.109) (layer "In6.Cu") (net 215))
  (segment (start 81.508822 127.55997) (end 81.465705 127.550129) (width 0.109) (layer "In6.Cu") (net 215))
  (segment (start 80.758027 124.754101) (end 80.683384 124.813629) (width 0.109) (layer "In6.Cu") (net 215))
  (segment (start 84.767614 129.370146) (end 84.795187 129.335568) (width 0.109) (layer "In6.Cu") (net 215))
  (segment (start 82.515399 128.469364) (end 82.472282 128.479205) (width 0.109) (layer "In6.Cu") (net 215))
  (segment (start 88.357421 133.887809) (end 88.337246 133.878093) (width 0.109) (layer "In6.Cu") (net 215))
  (segment (start 81.85636 125.610668) (end 81.76328 125.631912) (width 0.109) (layer "In6.Cu") (net 215))
  (segment (start 78.321672 122.649719) (end 78.338931 122.63246) (width 0.109) (layer "In6.Cu") (net 215))
  (segment (start 80.506624 126.611705) (end 80.472047 126.584131) (width 0.109) (layer "In6.Cu") (net 215))
  (segment (start 78.576973 124.583896) (end 78.586814 124.540779) (width 0.109) (layer "In6.Cu") (net 215))
  (segment (start 84.888635 128.431041) (end 84.802617 128.389617) (width 0.109) (layer "In6.Cu") (net 215))
  (segment (start 78.0775 122.7825) (end 78.080232 122.758245) (width 0.109) (layer "In6.Cu") (net 215))
  (segment (start 80.40408 123.931369) (end 80.367103 123.894392) (width 0.109) (layer "In6.Cu") (net 215))
  (segment (start 79.79754 125.69247) (end 79.757694 125.711659) (width 0.109) (layer "In6.Cu") (net 215))
  (segment (start 85.059783 129.055857) (end 85.101207 128.969839) (width 0.109) (layer "In6.Cu") (net 215))
  (segment (start 82.263754 128.217718) (end 82.282943 128.177872) (width 0.109) (layer "In6.Cu") (net 215))
  (segment (start 83.229752 129.06253) (end 84.062533 128.229755) (width 0.109) (layer "In6.Cu") (net 215))
  (segment (start 84.360324 128.490569) (end 83.509057 129.341836) (width 0.109) (layer "In6.Cu") (net 215))
  (segment (start 78.1865 122.4555) (end 78.162245 122.452767) (width 0.109) (layer "In6.Cu") (net 215))
  (segment (start 78.359979 122.540245) (end 78.351917 122.517206) (width 0.109) (layer "In6.Cu") (net 215))
  (segment (start 80.463608 124.006014) (end 80.40408 123.931369) (width 0.109) (layer "In6.Cu") (net 215))
  (segment (start 79.714577 125.7215) (end 79.670352 125.7215) (width 0.109) (layer "In6.Cu") (net 215))
  (segment (start 77.652884 111.910713) (end 77.63641 111.894239) (width 0.109) (layer "In6.Cu") (net 215))
  (segment (start 83.47448 129.36941) (end 83.434634 129.388599) (width 0.109) (layer "In6.Cu") (net 215))
  (segment (start 84.08102 127.608309) (end 84.044043 127.571332) (width 0.109) (layer "In6.Cu") (net 215))
  (segment (start 81.425859 127.53094) (end 81.391282 127.503366) (width 0.109) (layer "In6.Cu") (net 215))
  (segment (start 88.358996 134.137828) (end 88.358996 134.115435) (width 0.109) (layer "In6.Cu") (net 215))
  (segment (start 78.301005 122.662705) (end 78.321672 122.649719) (width 0.109) (layer "In6.Cu") (net 215))
  (segment (start 77.63641 112.166842) (end 77.652884 112.150368) (width 0.109) (layer "In6.Cu") (net 215))
  (segment (start 89.4415 134.124) (end 89.2565 134.309) (width 0.109) (layer "In6.Cu") (net 215))
  (segment (start 80.472047 126.584131) (end 80.444473 126.549554) (width 0.109) (layer "In6.Cu") (net 215))
  (segment (start 84.614065 128.368373) (end 84.520985 128.389617) (width 0.109) (layer "In6.Cu") (net 215))
  (segment (start 78.898172 123.732976) (end 78.838646 123.658332) (width 0.109) (layer "In6.Cu") (net 215))
  (segment (start 84.181972 128.050604) (end 84.203217 127.957525) (width 0.109) (layer "In6.Cu") (net 215))
  (segment (start 85.122452 128.87676) (end 85.122451 128.781286) (width 0.109) (layer "In6.Cu") (net 215))
  (segment (start 79.838792 123.834866) (end 79.764149 123.894394) (width 0.109) (layer "In6.Cu") (net 215))
  (segment (start 82.871067 126.529902) (end 82.775595 126.529903) (width 0.109) (layer "In6.Cu") (net 215))
  (segment (start 78.359979 122.588754) (end 78.362712 122.5645) (width 0.109) (layer "In6.Cu") (net 215))
  (segment (start 87.2275 133.037186) (end 87.2275 132.047185) (width 0.109) (layer "In6.Cu") (net 215))
  (segment (start 79.525238 125.630319) (end 79.506049 125.590473) (width 0.109) (layer "In6.Cu") (net 215))
  (segment (start 81.382843 125.378917) (end 81.424267 125.292899) (width 0.109) (layer "In6.Cu") (net 215))
  (segment (start 80.29246 123.834866) (end 80.206442 123.793442) (width 0.109) (layer "In6.Cu") (net 215))
  (segment (start 81.382843 124.925249) (end 81.323315 124.850604) (width 0.109) (layer "In6.Cu") (net 215))
  (segment (start 78.162245 122.452767) (end 78.139206 122.444705) (width 0.109) (layer "In6.Cu") (net 215))
  (segment (start 80.40408 124.534325) (end 80.463608 124.459682) (width 0.109) (layer "In6.Cu") (net 215))
  (segment (start 81.445511 125.104346) (end 81.424267 125.011267) (width 0.109) (layer "In6.Cu") (net 215))
  (segment (start 78.338931 122.63246) (end 78.351917 122.611793) (width 0.109) (layer "In6.Cu") (net 215))
  (segment (start 78.939597 124.100626) (end 78.960841 124.007547) (width 0.109) (layer "In6.Cu") (net 215))
  (segment (start 78.253712 122.6735) (end 78.277966 122.670767) (width 0.109) (layer "In6.Cu") (net 215))
  (segment (start 77.470109 112.27043) (end 77.477804 112.24844) (width 0.109) (layer "In6.Cu") (net 215))
  (segment (start 79.525238 125.420167) (end 79.552812 125.38559) (width 0.109) (layer "In6.Cu") (net 215))
  (segment (start 88.411334 134.018238) (end 88.416317 133.996406) (width 0.109) (layer "In6.Cu") (net 215))
  (segment (start 77.490199 112.228713) (end 77.506673 112.212239) (width 0.109) (layer "In6.Cu") (net 215))
  (segment (start 81.344519 127.428943) (end 81.334678 127.385826) (width 0.109) (layer "In6.Cu") (net 215))
  (segment (start 84.748425 129.540451) (end 84.738583 129.497334) (width 0.109) (layer "In6.Cu") (net 215))
  (segment (start 83.262737 126.849737) (end 83.221313 126.763719) (width 0.109) (layer "In6.Cu") (net 215))
  (segment (start 77.4675 111.122814) (end 77.759347 110.830967) (width 0.109) (layer "In6.Cu") (net 215))
  (segment (start 78.576973 124.628122) (end 78.576973 124.583896) (width 0.109) (layer "In6.Cu") (net 215))
  (segment (start 80.367103 123.894392) (end 80.29246 123.834866) (width 0.109) (layer "In6.Cu") (net 215))
  (segment (start 81.670587 127.503366) (end 81.63601 127.53094) (width 0.109) (layer "In6.Cu") (net 215))
  (segment (start 78.0775 122.3465) (end 78.0775 115.207186) (width 0.109) (layer "In6.Cu") (net 215))
  (segment (start 78.118539 122.431719) (end 78.10128 122.41446) (width 0.109) (layer "In6.Cu") (net 215))
  (segment (start 81.323315 124.850604) (end 81.286338 124.813627) (width 0.109) (layer "In6.Cu") (net 215))
  (segment (start 80.676929 126.630894) (end 80.633812 126.640735) (width 0.109) (layer "In6.Cu") (net 215))
  (segment (start 82.044912 125.631912) (end 81.951832 125.610667) (width 0.109) (layer "In6.Cu") (net 215))
  (segment (start 84.802617 128.389617) (end 84.709537 128.368372) (width 0.109) (layer "In6.Cu") (net 215))
  (segment (start 79.764149 123.894394) (end 78.912882 124.745662) (width 0.109) (layer "In6.Cu") (net 215))
  (segment (start 88.315414 133.87311) (end 88.293021 133.87311) (width 0.109) (layer "In6.Cu") (net 215))
  (segment (start 78.321672 122.47928) (end 78.301005 122.466294) (width 0.109) (layer "In6.Cu") (net 215))
  (segment (start 82.24255 126.372795) (end 82.302078 126.298152) (width 0.109) (layer "In6.Cu") (net 215))
  (segment (start 84.738583 129.497334) (end 84.738583 129.453108) (width 0.109) (layer "In6.Cu") (net 215))
  (segment (start 78.975 111.001467) (end 78.975 111.001468) (width 0.109) (layer "In6.Cu") (net 215))
  (segment (start 77.616683 111.881844) (end 77.594693 111.874149) (width 0.109) (layer "In6.Cu") (net 215))
  (segment (start 77.54839 112.192149) (end 77.594693 112.186932) (width 0.109) (layer "In6.Cu") (net 215))
  (segment (start 81.424267 125.011267) (end 81.382843 124.925249) (width 0.109) (layer "In6.Cu") (net 215))
  (segment (start 77.675582 112.0855) (end 77.675582 111.975582) (width 0.109) (layer "In6.Cu") (net 215))
  (segment (start 84.140548 128.136622) (end 84.181972 128.050604) (width 0.109) (layer "In6.Cu") (net 215))
  (segment (start 83.262737 127.131369) (end 83.283982 127.03829) (width 0.109) (layer "In6.Cu") (net 215))
  (segment (start 83.441089 127.571334) (end 82.589822 128.422601) (width 0.109) (layer "In6.Cu") (net 215))
  (segment (start 82.302078 125.844484) (end 82.24255 125.769839) (width 0.109) (layer "In6.Cu") (net 215))
  (segment (start 79.552812 125.38559) (end 80.385593 124.552815) (width 0.109) (layer "In6.Cu") (net 215))
  (segment (start 82.282943 128.388024) (end 82.263754 128.348178) (width 0.109) (layer "In6.Cu") (net 215))
  (segment (start 77.490199 111.832368) (end 77.477804 111.812641) (width 0.109) (layer "In6.Cu") (net 215))
  (segment (start 83.143298 127.31052) (end 83.161785 127.29203) (width 0.109) (layer "In6.Cu") (net 215))
  (segment (start 77.4675 114.597186) (end 77.4675 112.293582) (width 0.109) (layer "In6.Cu") (net 215))
  (segment (start 88.401618 133.932007) (end 88.387657 133.914499) (width 0.109) (layer "In6.Cu") (net 215))
  (segment (start 77.5264 112.199844) (end 77.54839 112.192149) (width 0.109) (layer "In6.Cu") (net 215))
  (segment (start 82.596497 126.592571) (end 82.521854 126.652099) (width 0.109) (layer "In6.Cu") (net 215))
  (segment (start 80.937125 124.691433) (end 80.844045 124.712677) (width 0.109) (layer "In6.Cu") (net 215))
  (segment (start 78.338931 122.496539) (end 78.321672 122.47928) (width 0.109) (layer "In6.Cu") (net 215))
  (segment (start 81.304828 125.47205) (end 81.323315 125.45356) (width 0.109) (layer "In6.Cu") (net 215))
  (segment (start 81.445512 125.19982) (end 81.445511 125.104346) (width 0.109) (layer "In6.Cu") (net 215))
  (segment (start 88.173992 133.930431) (end 88.151599 133.930431) (width 0.109) (layer "In6.Cu") (net 215))
  (segment (start 77.672974 111.95243) (end 77.665279 111.93044) (width 0.109) (layer "In6.Cu") (net 215))
  (segment (start 84.795187 129.614874) (end 84.767614 129.580298) (width 0.109) (layer "In6.Cu") (net 215))
  (segment (start 81.424267 125.292899) (end 81.445512 125.19982) (width 0.109) (layer "In6.Cu") (net 215))
  (segment (start 88.416317 133.974013) (end 88.411334 133.952182) (width 0.109) (layer "In6.Cu") (net 215))
  (segment (start 82.38494 128.469364) (end 82.345094 128.450175) (width 0.109) (layer "In6.Cu") (net 215))
  (segment (start 79.757694 125.711659) (end 79.714577 125.7215) (width 0.109) (layer "In6.Cu") (net 215))
  (segment (start 82.345094 128.450175) (end 82.310517 128.422601) (width 0.109) (layer "In6.Cu") (net 215))
  (segment (start 80.425284 126.509708) (end 80.415443 126.466591) (width 0.109) (layer "In6.Cu") (net 215))
  (segment (start 85.059783 128.602189) (end 85.000255 128.527544) (width 0.109) (layer "In6.Cu") (net 215))
  (segment (start 88.504314 134.314) (end 88.387657 134.197343) (width 0.109) (layer "In6.Cu") (net 215))
  (segment (start 89.2565 134.314) (end 88.504314 134.314) (width 0.109) (layer "In6.Cu") (net 215))
  (segment (start 83.161785 127.29203) (end 83.221313 127.217387) (width 0.109) (layer "In6.Cu") (net 215))
  (segment (start 82.428057 128.479205) (end 82.38494 128.469364) (width 0.109) (layer "In6.Cu") (net 215))
  (segment (start 80.463608 124.459682) (end 80.505032 124.373664) (width 0.109) (layer "In6.Cu") (net 215))
  (segment (start 83.221313 126.763719) (end 83.161785 126.689074) (width 0.109) (layer "In6.Cu") (net 215))
  (segment (start 77.477804 112.24844) (end 77.490199 112.228713) (width 0.109) (layer "In6.Cu") (net 215))
  (segment (start 83.9694 127.511806) (end 83.883382 127.470382) (width 0.109) (layer "In6.Cu") (net 215))
  (segment (start 88.416317 133.996406) (end 88.416317 133.974013) (width 0.109) (layer "In6.Cu") (net 215))
  (segment (start 80.444473 126.549554) (end 80.425284 126.509708) (width 0.109) (layer "In6.Cu") (net 215))
  (segment (start 81.465705 127.550129) (end 81.425859 127.53094) (width 0.109) (layer "In6.Cu") (net 215))
  (segment (start 84.140548 127.682954) (end 84.08102 127.608309) (width 0.109) (layer "In6.Cu") (net 215))
  (segment (start 79.496208 125.50313) (end 79.506049 125.460013) (width 0.109) (layer "In6.Cu") (net 215))
  (segment (start 85.000255 129.1305) (end 85.059783 129.055857) (width 0.109) (layer "In6.Cu") (net 215))
  (segment (start 79.832117 125.664896) (end 79.79754 125.69247) (width 0.109) (layer "In6.Cu") (net 215))
  (segment (start 88.151599 133.930431) (end 88.129768 133.925448) (width 0.109) (layer "In6.Cu") (net 215))
  (segment (start 84.434967 128.431041) (end 84.360324 128.490569) (width 0.109) (layer "In6.Cu") (net 215))
  (segment (start 84.08102 128.211265) (end 84.140548 128.136622) (width 0.109) (layer "In6.Cu") (net 215))
  (segment (start 80.716775 126.611705) (end 80.676929 126.630894) (width 0.109) (layer "In6.Cu") (net 215))
  (segment (start 83.790302 127.449137) (end 83.69483 127.449138) (width 0.109) (layer "In6.Cu") (net 215))
  (segment (start 78.838646 123.658332) (end 78.0775 122.897186) (width 0.109) (layer "In6.Cu") (net 215))
  (segment (start 78.351917 122.517206) (end 78.338931 122.496539) (width 0.109) (layer "In6.Cu") (net 215))
  (segment (start 81.323315 125.45356) (end 81.382843 125.378917) (width 0.109) (layer "In6.Cu") (net 215))
  (segment (start 78.080232 122.758245) (end 78.088294 122.735206) (width 0.109) (layer "In6.Cu") (net 215))
  (segment (start 82.253913 128.305061) (end 82.253913 128.260835) (width 0.109) (layer "In6.Cu") (net 215))
  (segment (start 78.1865 122.6735) (end 78.253712 122.6735) (width 0.109) (layer "In6.Cu") (net 215))
  (segment (start 80.54647 126.630894) (end 80.506624 126.611705) (width 0.109) (layer "In6.Cu") (net 215))
  (segment (start 82.253913 128.260835) (end 82.263754 128.217718) (width 0.109) (layer "In6.Cu") (net 215))
  (segment (start 88.373695 134.073429) (end 88.401618 134.038413) (width 0.109) (layer "In6.Cu") (net 215))
  (segment (start 78.277966 122.670767) (end 78.301005 122.662705) (width 0.109) (layer "In6.Cu") (net 215))
  (segment (start 84.981768 129.14899) (end 85.000255 129.1305) (width 0.109) (layer "In6.Cu") (net 215))
  (segment (start 88.387657 133.914499) (end 88.374929 133.901771) (width 0.109) (layer "In6.Cu") (net 215))
  (segment (start 80.589587 126.640735) (end 80.54647 126.630894) (width 0.109) (layer "In6.Cu") (net 215))
  (segment (start 77.470109 111.790651) (end 77.4675 111.7675) (width 0.109) (layer "In6.Cu") (net 215))
  (segment (start 84.709537 128.368372) (end 84.614065 128.368373) (width 0.109) (layer "In6.Cu") (net 215))
  (segment (start 84.181972 127.768972) (end 84.140548 127.682954) (width 0.109) (layer "In6.Cu") (net 215))
  (segment (start 83.283982 127.03829) (end 83.283981 126.942816) (width 0.109) (layer "In6.Cu") (net 215))
  (segment (start 81.391282 127.22406) (end 82.224063 126.391285) (width 0.109) (layer "In6.Cu") (net 215))
  (segment (start 83.509057 129.341836) (end 83.47448 129.36941) (width 0.109) (layer "In6.Cu") (net 215))
  (segment (start 80.01789 123.772198) (end 79.92481 123.793442) (width 0.109) (layer "In6.Cu") (net 215))
  (segment (start 88.363979 134.093604) (end 88.373695 134.073429) (width 0.109) (layer "In6.Cu") (net 215))
  (segment (start 81.286338 124.813627) (end 81.211695 124.754101) (width 0.109) (layer "In6.Cu") (net 215))
  (segment (start 77.672974 112.108651) (end 77.675582 112.0855) (width 0.109) (layer "In6.Cu") (net 215))
  (segment (start 78.118539 122.69728) (end 78.139206 122.684294) (width 0.109) (layer "In6.Cu") (net 215))
  (segment (start 83.60175 127.470382) (end 83.515732 127.511806) (width 0.109) (layer "In6.Cu") (net 215))
  (segment (start 88.401618 134.038413) (end 88.411334 134.018238) (width 0.109) (layer "In6.Cu") (net 215))
  (segment (start 77.759347 110.830967) (end 78.8045 110.830967) (width 0.109) (layer "In6.Cu") (net 215))
  (segment (start 88.337246 133.878093) (end 88.315414 133.87311) (width 0.109) (layer "In6.Cu") (net 215))
  (segment (start 83.69483 127.449138) (end 83.60175 127.470382) (width 0.109) (layer "In6.Cu") (net 215))
  (segment (start 82.682515 126.551147) (end 82.596497 126.592571) (width 0.109) (layer "In6.Cu") (net 215))
  (segment (start 82.24255 125.769839) (end 82.205573 125.732862) (width 0.109) (layer "In6.Cu") (net 215))
  (segment (start 82.964147 126.551147) (end 82.871067 126.529902) (width 0.109) (layer "In6.Cu") (net 215))
  (segment (start 82.282943 128.177872) (end 82.310517 128.143295) (width 0.109) (layer "In6.Cu") (net 215))
  (segment (start 88.363979 134.15966) (end 88.358996 134.137828) (width 0.109) (layer "In6.Cu") (net 215))
  (segment (start 84.963278 128.490567) (end 84.888635 128.431041) (width 0.109) (layer "In6.Cu") (net 215))
  (segment (start 78.253712 122.4555) (end 78.1865 122.4555) (width 0.109) (layer "In6.Cu") (net 215))
  (segment (start 83.304175 129.388599) (end 83.264329 129.36941) (width 0.109) (layer "In6.Cu") (net 215))
  (segment (start 78.8045 110.830967) (end 78.975 111.001467) (width 0.109) (layer "In6.Cu") (net 215))
  (segment (start 82.364746 126.023581) (end 82.343502 125.930502) (width 0.109) (layer "In6.Cu") (net 215))
  (segment (start 77.477804 111.812641) (end 77.470109 111.790651) (width 0.109) (layer "In6.Cu") (net 215))
  (segment (start 79.627235 125.711659) (end 79.587389 125.69247) (width 0.109) (layer "In6.Cu") (net 215))
  (segment (start 81.363708 127.468789) (end 81.344519 127.428943) (width 0.109) (layer "In6.Cu") (net 215))
  (segment (start 88.387657 134.197343) (end 88.373695 134.179835) (width 0.109) (layer "In6.Cu") (net 215))
  (segment (start 88.092085 133.901771) (end 87.2275 133.037186) (width 0.109) (layer "In6.Cu") (net 215))
  (segment (start 80.425284 126.379248) (end 80.444473 126.339402) (width 0.109) (layer "In6.Cu") (net 215))
  (segment (start 78.088294 122.393793) (end 78.080232 122.370754) (width 0.109) (layer "In6.Cu") (net 215))
  (segment (start 79.92481 123.793442) (end 79.838792 123.834866) (width 0.109) (layer "In6.Cu") (net 215))
  (segment (start 81.553047 127.55997) (end 81.508822 127.55997) (width 0.109) (layer "In6.Cu") (net 215))
  (segment (start 80.206442 123.793442) (end 80.113362 123.772197) (width 0.109) (layer "In6.Cu") (net 215))
  (segment (start 81.211695 124.754101) (end 81.125677 124.712677) (width 0.109) (layer "In6.Cu") (net 215))
  (segment (start 81.391282 127.503366) (end 81.363708 127.468789) (width 0.109) (layer "In6.Cu") (net 215))
  (segment (start 79.496208 125.547356) (end 79.496208 125.50313) (width 0.109) (layer "In6.Cu") (net 215))
  (segment (start 83.434634 129.388599) (end 83.391517 129.39844) (width 0.109) (layer "In6.Cu") (net 215))
  (segment (start 78.960841 124.007547) (end 78.960841 123.912074) (width 0.109) (layer "In6.Cu") (net 215))
  (segment (start 81.344519 127.298483) (end 81.363708 127.258637) (width 0.109) (layer "In6.Cu") (net 215))
  (segment (start 78.362712 122.5645) (end 78.359979 122.540245) (width 0.109) (layer "In6.Cu") (net 215))
  (segment (start 81.677262 125.673336) (end 81.602619 125.732864) (width 0.109) (layer "In6.Cu") (net 215))
  (segment (start 84.520985 128.389617) (end 84.434967 128.431041) (width 0.109) (layer "In6.Cu") (net 215))
  (segment (start 77.594693 112.186932) (end 77.616683 112.179237) (width 0.109) (layer "In6.Cu") (net 215))
  (segment (start 79.670352 125.7215) (end 79.627235 125.711659) (width 0.109) (layer "In6.Cu") (net 215))
  (segment (start 82.205573 125.732862) (end 82.13093 125.673336) (width 0.109) (layer "In6.Cu") (net 215))
  (segment (start 81.032597 124.691432) (end 80.937125 124.691433) (width 0.109) (layer "In6.Cu") (net 215))
  (segment (start 88.358996 134.115435) (end 88.363979 134.093604) (width 0.109) (layer "In6.Cu") (net 215))
  (segment (start 84.795187 129.335568) (end 84.981768 129.14899) (width 0.109) (layer "In6.Cu") (net 215))
  (segment (start 79.506049 125.590473) (end 79.496208 125.547356) (width 0.109) (layer "In6.Cu") (net 215))
  (segment (start 82.775595 126.529903) (end 82.682515 126.551147) (width 0.109) (layer "In6.Cu") (net 215))
  (segment (start 78.606003 124.500933) (end 78.633577 124.466356) (width 0.109) (layer "In6.Cu") (net 215))
  (segment (start 82.555245 128.450175) (end 82.515399 128.469364) (width 0.109) (layer "In6.Cu") (net 215))
  (segment (start 80.751352 126.584131) (end 80.716775 126.611705) (width 0.109) (layer "In6.Cu") (net 215))
  (segment (start 87.2275 132.047185) (end 84.795187 129.614874) (width 0.109) (layer "In6.Cu") (net 215))
  (segment (start 77.63641 111.894239) (end 77.616683 111.881844) (width 0.109) (layer "In6.Cu") (net 215))
  (segment (start 78.912882 124.745662) (end 78.878305 124.773236) (width 0.109) (layer "In6.Cu") (net 215))
  (segment (start 81.125677 124.712677) (end 81.032597 124.691432) (width 0.109) (layer "In6.Cu") (net 215))
  (segment (start 84.748424 129.409991) (end 84.767614 129.370146) (width 0.109) (layer "In6.Cu") (net 215))
  (segment (start 77.594693 111.874149) (end 77.54839 111.868932) (width 0.109) (layer "In6.Cu") (net 215))
  (segment (start 83.264329 129.36941) (end 83.229752 129.341836) (width 0.109) (layer "In6.Cu") (net 215))
  (segment (start 78.939597 123.818994) (end 78.898172 123.732976) (width 0.109) (layer "In6.Cu") (net 215))
  (segment (start 78.633577 124.466356) (end 78.838646 124.261288) (width 0.109) (layer "In6.Cu") (net 215))
  (segment (start 83.173148 129.18007) (end 83.182989 129.136953) (width 0.109) (layer "In6.Cu") (net 215))
  (segment (start 82.343502 126.212134) (end 82.364747 126.119055) (width 0.109) (layer "In6.Cu") (net 215))
  (segment (start 78.0775 115.207186) (end 77.4675 114.597186) (width 0.109) (layer "In6.Cu") (net 215))
  (segment (start 77.506673 112.212239) (end 77.5264 112.199844) (width 0.109) (layer "In6.Cu") (net 215))
  (segment (start 83.050165 126.592571) (end 82.964147 126.551147) (width 0.109) (layer "In6.Cu") (net 215))
  (segment (start 83.283981 126.942816) (end 83.262737 126.849737) (width 0.109) (layer "In6.Cu") (net 215))
  (segment (start 78.277966 122.458232) (end 78.253712 122.4555) (width 0.109) (layer "In6.Cu") (net 215))
  (segment (start 81.363708 127.258637) (end 81.391282 127.22406) (width 0.109) (layer "In6.Cu") (net 215))
  (segment (start 85.122451 128.781286) (end 85.101207 128.688207) (width 0.109) (layer "In6.Cu") (net 215))
  (segment (start 80.415443 126.466591) (end 80.415443 126.422365) (width 0.109) (layer "In6.Cu") (net 215))
  (segment (start 78.10128 122.41446) (end 78.088294 122.393793) (width 0.109) (layer "In6.Cu") (net 215))
  (segment (start 77.652884 112.150368) (end 77.665279 112.130641) (width 0.109) (layer "In6.Cu") (net 215))
  (segment (start 82.263754 128.348178) (end 82.253913 128.305061) (width 0.109) (layer "In6.Cu") (net 215))
  (segment (start 84.044043 127.571332) (end 83.9694 127.511806) (width 0.109) (layer "In6.Cu") (net 215))
  (segment (start 88.411334 133.952182) (end 88.401618 133.932007) (width 0.109) (layer "In6.Cu") (net 215))
  (segment (start 88.373695 134.179835) (end 88.363979 134.15966) (width 0.109) (layer "In6.Cu") (net 215))
  (segment (start 77.506673 111.848842) (end 77.490199 111.832368) (width 0.109) (layer "In6.Cu") (net 215))
  (segment (start 88.195824 133.925448) (end 88.173992 133.930431) (width 0.109) (layer "In6.Cu") (net 215))
  (segment (start 78.960841 123.912074) (end 78.939597 123.818994) (width 0.109) (layer "In6.Cu") (net 215))
  (segment (start 80.999999 112.25) (end 80.938999 112.189) (width 0.182) (layer "B.Cu") (net 215))
  (segment (start 80.938999 112.189) (end 80.696712 112.189) (width 0.182) (layer "B.Cu") (net 215))
  (segment (start 81.9 112.25) (end 80.999999 112.25) (width 0.182) (layer "B.Cu") (net 215))
  (segment (start 78.975 111.001467) (end 78.975 111.001468) (width 0.182) (layer "B.Cu") (net 215))
  (segment (start 80.066001 111.212319) (end 79.746149 110.892467) (width 0.182) (layer "B.Cu") (net 215))
  (segment (start 79.746149 110.892467) (end 79.084 110.892467) (width 0.182) (layer "B.Cu") (net 215))
  (segment (start 79.084 110.892467) (end 78.975 111.001467) (width 0.182) (layer "B.Cu") (net 215))
  (segment (start 80.696712 112.189) (end 80.066001 111.558289) (width 0.182) (layer "B.Cu") (net 215))
  (segment (start 80.066001 111.558289) (end 80.066001 111.212319) (width 0.182) (layer "B.Cu") (net 215))
  (segment (start 90.7865 133.179) (end 91.1715 132.869) (width 0.182) (layer "F.Cu") (net 216))
  (via (at 78.6 111.798532) (size 0.45) (drill 0.1) (layers "F.Cu" "B.Cu") (net 216))
  (via (at 91.1715 132.869) (size 0.45) (drill 0.1) (layers "F.Cu" "B.Cu") (net 216))
  (segment (start 77.985444 119.260675) (end 77.947059 119.265) (width 0.109) (layer "In4.Cu") (net 216))
  (segment (start 76.203471 116.904889) (end 76.127098 116.952877) (width 0.109) (layer "In4.Cu") (net 216))
  (segment (start 77.030417 114.367344) (end 77.009865 114.400051) (width 0.109) (layer "In4.Cu") (net 216))
  (segment (start 78.119559 117.8925) (end 78.115235 117.930884) (width 0.109) (layer "In4.Cu") (net 216))
  (segment (start 76.378238 115.32) (end 77.947059 115.32) (width 0.109) (layer "In4.Cu") (net 216))
  (segment (start 76.203471 115.704889) (end 76.127098 115.752877) (width 0.109) (layer "In4.Cu") (net 216))
  (segment (start 78.021904 116.537082) (end 78.054611 116.557634) (width 0.109) (layer "In4.Cu") (net 216))
  (segment (start 77.275531 120.504889) (end 77.199158 120.552877) (width 0.109) (layer "In4.Cu") (net 216))
  (segment (start 76.288607 117.709901) (end 76.378238 117.72) (width 0.109) (layer "In4.Cu") (net 216))
  (segment (start 75.985539 114.778166) (end 75.975441 114.867797) (width 0.109) (layer "In4.Cu") (net 216))
  (segment (start 78.115235 120.330884) (end 78.102477 120.367344) (width 0.109) (layer "In4.Cu") (net 216))
  (segment (start 76.982551 114.427365) (end 76.949844 114.447917) (width 0.109) (layer "In4.Cu") (net 216))
  (segment (start 76.378238 117.72) (end 77.947059 117.72) (width 0.109) (layer "In4.Cu") (net 216))
  (segment (start 75.975441 119.667797) (end 75.975441 119.717202) (width 0.109) (layer "In4.Cu") (net 216))
  (segment (start 77.985444 115.324324) (end 78.021904 115.337082) (width 0.109) (layer "In4.Cu") (net 216))
  (segment (start 78.021904 120.447917) (end 77.985444 120.460675) (width 0.109) (layer "In4.Cu") (net 216))
  (segment (start 76.127098 120.032122) (end 76.203471 120.08011) (width 0.109) (layer "In4.Cu") (net 216))
  (segment (start 78.102477 117.967344) (end 78.081925 118.000051) (width 0.109) (layer "In4.Cu") (net 216))
  (segment (start 76.127098 118.152877) (end 76.063318 118.216657) (width 0.109) (layer "In4.Cu") (net 216))
  (segment (start 76.01533 115.89303) (end 75.985539 115.978166) (width 0.109) (layer "In4.Cu") (net 216))
  (segment (start 78.054611 115.357634) (end 78.081925 115.384948) (width 0.109) (layer "In4.Cu") (net 216))
  (segment (start 78.054611 118.957634) (end 78.081925 118.984948) (width 0.109) (layer "In4.Cu") (net 216))
  (segment (start 76.127098 119.352877) (end 76.063318 119.416657) (width 0.109) (layer "In4.Cu") (net 216))
  (segment (start 75.975441 117.267797) (end 75.975441 117.317202) (width 0.109) (layer "In4.Cu") (net 216))
  (segment (start 76.203471 114.504889) (end 76.127098 114.552877) (width 0.109) (layer "In4.Cu") (net 216))
  (segment (start 76.203471 115.28011) (end 76.288607 115.309901) (width 0.109) (layer "In4.Cu") (net 216))
  (segment (start 76.01533 118.29303) (end 75.985539 118.378166) (width 0.109) (layer "In4.Cu") (net 216))
  (segment (start 77.135378 120.616657) (end 77.08739 120.69303) (width 0.109) (layer "In4.Cu") (net 216))
  (segment (start 76.127098 115.752877) (end 76.063318 115.816657) (width 0.109) (layer "In4.Cu") (net 216))
  (segment (start 78.081925 115.600051) (end 78.054611 115.627365) (width 0.109) (layer "In4.Cu") (net 216))
  (segment (start 75.985539 115.006833) (end 76.01533 115.091969) (width 0.109) (layer "In4.Cu") (net 216))
  (segment (start 78.119559 115.4925) (end 78.115235 115.530884) (width 0.109) (layer "In4.Cu") (net 216))
  (segment (start 77.0475 114.2925) (end 77.043175 114.330884) (width 0.109) (layer "In4.Cu") (net 216))
  (segment (start 77.947059 115.665) (end 76.378238 115.665) (width 0.109) (layer "In4.Cu") (net 216))
  (segment (start 90.7 131.905314) (end 90.7 132.3975) (width 0.109) (layer "In4.Cu") (net 216))
  (segment (start 76.203471 118.104889) (end 76.127098 118.152877) (width 0.109) (layer "In4.Cu") (net 216))
  (segment (start 76.378238 118.92) (end 77.947059 118.92) (width 0.109) (layer "In4.Cu") (net 216))
  (segment (start 76.913384 114.460675) (end 76.875 114.465) (width 0.109) (layer "In4.Cu") (net 216))
  (segment (start 77.985444 117.724324) (end 78.021904 117.737082) (width 0.109) (layer "In4.Cu") (net 216))
  (segment (start 75.985539 118.606833) (end 76.01533 118.691969) (width 0.109) (layer "In4.Cu") (net 216))
  (segment (start 76.288607 116.509901) (end 76.378238 116.52) (width 0.109) (layer "In4.Cu") (net 216))
  (segment (start 75.975441 117.317202) (end 75.985539 117.406833) (width 0.109) (layer "In4.Cu") (net 216))
  (segment (start 77.009865 114.400051) (end 76.982551 114.427365) (width 0.109) (layer "In4.Cu") (net 216))
  (segment (start 78.115235 119.130884) (end 78.102477 119.167344) (width 0.109) (layer "In4.Cu") (net 216))
  (segment (start 78.115235 117.854115) (end 78.119559 117.8925) (width 0.109) (layer "In4.Cu") (net 216))
  (segment (start 78.021904 118.937082) (end 78.054611 118.957634) (width 0.109) (layer "In4.Cu") (net 216))
  (segment (start 78.102477 115.567344) (end 78.081925 115.600051) (width 0.109) (layer "In4.Cu") (net 216))
  (segment (start 78.081925 119.200051) (end 78.054611 119.227365) (width 0.109) (layer "In4.Cu") (net 216))
  (segment (start 78.115235 117.930884) (end 78.102477 117.967344) (width 0.109) (layer "In4.Cu") (net 216))
  (segment (start 78.119559 119.0925) (end 78.115235 119.130884) (width 0.109) (layer "In4.Cu") (net 216))
  (segment (start 78.119559 116.6925) (end 78.115235 116.730884) (width 0.109) (layer "In4.Cu") (net 216))
  (segment (start 78.081925 118.000051) (end 78.054611 118.027365) (width 0.109) (layer "In4.Cu") (net 216))
  (segment (start 78.081925 120.400051) (end 78.054611 120.427365) (width 0.109) (layer "In4.Cu") (net 216))
  (segment (start 77.947059 115.32) (end 77.985444 115.324324) (width 0.109) (layer "In4.Cu") (net 216))
  (segment (start 75.975441 118.517202) (end 75.985539 118.606833) (width 0.109) (layer "In4.Cu") (net 216))
  (segment (start 76.378238 114.465) (end 76.288607 114.475098) (width 0.109) (layer "In4.Cu") (net 216))
  (segment (start 78.021904 115.337082) (end 78.054611 115.357634) (width 0.109) (layer "In4.Cu") (net 216))
  (segment (start 76.01533 115.091969) (end 76.063318 115.168342) (width 0.109) (layer "In4.Cu") (net 216))
  (segment (start 78.054611 118.027365) (end 78.021904 118.047917) (width 0.109) (layer "In4.Cu") (net 216))
  (segment (start 76.203471 118.88011) (end 76.288607 118.909901) (width 0.109) (layer "In4.Cu") (net 216))
  (segment (start 77.947059 116.52) (end 77.985444 116.524324) (width 0.109) (layer "In4.Cu") (net 216))
  (segment (start 77.985444 115.660675) (end 77.947059 115.665) (width 0.109) (layer "In4.Cu") (net 216))
  (segment (start 76.378238 120.12) (end 77.947059 120.12) (width 0.109) (layer "In4.Cu") (net 216))
  (segment (start 77.985444 118.060675) (end 77.947059 118.065) (width 0.109) (layer "In4.Cu") (net 216))
  (segment (start 76.288607 116.875098) (end 76.203471 116.904889) (width 0.109) (layer "In4.Cu") (net 216))
  (segment (start 77.700654 111.969032) (end 77.0475 112.622186) (width 0.109) (layer "In4.Cu") (net 216))
  (segment (start 76.288607 120.109901) (end 76.378238 120.12) (width 0.109) (layer "In4.Cu") (net 216))
  (segment (start 76.01533 116.291969) (end 76.063318 116.368342) (width 0.109) (layer "In4.Cu") (net 216))
  (segment (start 76.127098 115.232122) (end 76.203471 115.28011) (width 0.109) (layer "In4.Cu") (net 216))
  (segment (start 76.288607 115.675098) (end 76.203471 115.704889) (width 0.109) (layer "In4.Cu") (net 216))
  (segment (start 78.021904 116.847917) (end 77.985444 116.860675) (width 0.109) (layer "In4.Cu") (net 216))
  (segment (start 76.063318 119.416657) (end 76.01533 119.49303) (width 0.109) (layer "In4.Cu") (net 216))
  (segment (start 77.947059 116.865) (end 76.378238 116.865) (width 0.109) (layer "In4.Cu") (net 216))
  (segment (start 78.115235 115.454115) (end 78.119559 115.4925) (width 0.109) (layer "In4.Cu") (net 216))
  (segment (start 77.985444 120.124324) (end 78.021904 120.137082) (width 0.109) (layer "In4.Cu") (net 216))
  (segment (start 76.01533 119.49303) (end 75.985539 119.578166) (width 0.109) (layer "In4.Cu") (net 216))
  (segment (start 78.054611 116.557634) (end 78.081925 116.584948) (width 0.109) (layer "In4.Cu") (net 216))
  (segment (start 75.985539 115.978166) (end 75.975441 116.067797) (width 0.109) (layer "In4.Cu") (net 216))
  (segment (start 76.01533 117.491969) (end 76.063318 117.568342) (width 0.109) (layer "In4.Cu") (net 216))
  (segment (start 77.985444 116.860675) (end 77.947059 116.865) (width 0.109) (layer "In4.Cu") (net 216))
  (segment (start 76.378238 115.665) (end 76.288607 115.675098) (width 0.109) (layer "In4.Cu") (net 216))
  (segment (start 78.021904 117.737082) (end 78.054611 117.757634) (width 0.109) (layer "In4.Cu") (net 216))
  (segment (start 76.127098 117.632122) (end 76.203471 117.68011) (width 0.109) (layer "In4.Cu") (net 216))
  (segment (start 77.0475 123.452814) (end 85.272186 131.6775) (width 0.109) (layer "In4.Cu") (net 216))
  (segment (start 76.203471 119.304889) (end 76.127098 119.352877) (width 0.109) (layer "In4.Cu") (net 216))
  (segment (start 76.127098 116.432122) (end 76.203471 116.48011) (width 0.109) (layer "In4.Cu") (net 216))
  (segment (start 78.054611 120.157634) (end 78.081925 120.184948) (width 0.109) (layer "In4.Cu") (net 216))
  (segment (start 75.985539 117.178166) (end 75.975441 117.267797) (width 0.109) (layer "In4.Cu") (net 216))
  (segment (start 78.115235 120.254115) (end 78.119559 120.2925) (width 0.109) (layer "In4.Cu") (net 216))
  (segment (start 78.102477 116.617655) (end 78.115235 116.654115) (width 0.109) (layer "In4.Cu") (net 216))
  (segment (start 75.975441 116.117202) (end 75.985539 116.206833) (width 0.109) (layer "In4.Cu") (net 216))
  (segment (start 78.102477 116.767344) (end 78.081925 116.800051) (width 0.109) (layer "In4.Cu") (net 216))
  (segment (start 78.081925 116.800051) (end 78.054611 116.827365) (width 0.109) (layer "In4.Cu") (net 216))
  (segment (start 77.0475 112.622186) (end 77.0475 114.2925) (width 0.109) (layer "In4.Cu") (net 216))
  (segment (start 76.203471 120.08011) (end 76.288607 120.109901) (width 0.109) (layer "In4.Cu") (net 216))
  (segment (start 76.288607 119.275098) (end 76.203471 119.304889) (width 0.109) (layer "In4.Cu") (net 216))
  (segment (start 78.021904 115.647917) (end 77.985444 115.660675) (width 0.109) (layer "In4.Cu") (net 216))
  (segment (start 78.102477 120.217655) (end 78.115235 120.254115) (width 0.109) (layer "In4.Cu") (net 216))
  (segment (start 76.063318 117.568342) (end 76.127098 117.632122) (width 0.109) (layer "In4.Cu") (net 216))
  (segment (start 76.127098 118.832122) (end 76.203471 118.88011) (width 0.109) (layer "In4.Cu") (net 216))
  (segment (start 76.378238 118.065) (end 76.288607 118.075098) (width 0.109) (layer "In4.Cu") (net 216))
  (segment (start 75.975441 116.067797) (end 75.975441 116.117202) (width 0.109) (layer "In4.Cu") (net 216))
  (segment (start 75.985539 117.406833) (end 76.01533 117.491969) (width 0.109) (layer "In4.Cu") (net 216))
  (segment (start 76.203471 117.68011) (end 76.288607 117.709901) (width 0.109) (layer "In4.Cu") (net 216))
  (segment (start 77.947059 120.12) (end 77.985444 120.124324) (width 0.109) (layer "In4.Cu") (net 216))
  (segment (start 90.7 132.3975) (end 91.1715 132.869) (width 0.109) (layer "In4.Cu") (net 216))
  (segment (start 77.450298 120.465) (end 77.360667 120.475098) (width 0.109) (layer "In4.Cu") (net 216))
  (segment (start 76.288607 118.909901) (end 76.378238 118.92) (width 0.109) (layer "In4.Cu") (net 216))
  (segment (start 76.378238 116.52) (end 77.947059 116.52) (width 0.109) (layer "In4.Cu") (net 216))
  (segment (start 77.947059 119.265) (end 76.378238 119.265) (width 0.109) (layer "In4.Cu") (net 216))
  (segment (start 78.115235 115.530884) (end 78.102477 115.567344) (width 0.109) (layer "In4.Cu") (net 216))
  (segment (start 85.272186 131.6775) (end 90.472186 131.6775) (width 0.109) (layer "In4.Cu") (net 216))
  (segment (start 78.102477 119.017655) (end 78.115235 119.054115) (width 0.109) (layer "In4.Cu") (net 216))
  (segment (start 78.021904 118.047917) (end 77.985444 118.060675) (width 0.109) (layer "In4.Cu") (net 216))
  (segment (start 76.01533 117.09303) (end 75.985539 117.178166) (width 0.109) (layer "In4.Cu") (net 216))
  (segment (start 76.063318 118.216657) (end 76.01533 118.29303) (width 0.109) (layer "In4.Cu") (net 216))
  (segment (start 77.947059 120.465) (end 77.450298 120.465) (width 0.109) (layer "In4.Cu") (net 216))
  (segment (start 76.063318 114.616657) (end 76.01533 114.69303) (width 0.109) (layer "In4.Cu") (net 216))
  (segment (start 75.975441 118.467797) (end 75.975441 118.517202) (width 0.109) (layer "In4.Cu") (net 216))
  (segment (start 75.985539 119.578166) (end 75.975441 119.667797) (width 0.109) (layer "In4.Cu") (net 216))
  (segment (start 76.288607 115.309901) (end 76.378238 115.32) (width 0.109) (layer "In4.Cu") (net 216))
  (segment (start 76.127098 116.952877) (end 76.063318 117.016657) (width 0.109) (layer "In4.Cu") (net 216))
  (segment (start 76.063318 115.168342) (end 76.127098 115.232122) (width 0.109) (layer "In4.Cu") (net 216))
  (segment (start 78.115235 116.730884) (end 78.102477 116.767344) (width 0.109) (layer "In4.Cu") (net 216))
  (segment (start 78.081925 118.984948) (end 78.102477 119.017655) (width 0.109) (layer "In4.Cu") (net 216))
  (segment (start 76.378238 119.265) (end 76.288607 119.275098) (width 0.109) (layer "In4.Cu") (net 216))
  (segment (start 78.054611 117.757634) (end 78.081925 117.784948) (width 0.109) (layer "In4.Cu") (net 216))
  (segment (start 78.021904 120.137082) (end 78.054611 120.157634) (width 0.109) (layer "In4.Cu") (net 216))
  (segment (start 78.6 111.798532) (end 78.4295 111.969032) (width 0.109) (layer "In4.Cu") (net 216))
  (segment (start 77.985444 118.924324) (end 78.021904 118.937082) (width 0.109) (layer "In4.Cu") (net 216))
  (segment (start 76.063318 118.768342) (end 76.127098 118.832122) (width 0.109) (layer "In4.Cu") (net 216))
  (segment (start 77.360667 120.475098) (end 77.275531 120.504889) (width 0.109) (layer "In4.Cu") (net 216))
  (segment (start 77.947059 117.72) (end 77.985444 117.724324) (width 0.109) (layer "In4.Cu") (net 216))
  (segment (start 76.875 114.465) (end 76.378238 114.465) (width 0.109) (layer "In4.Cu") (net 216))
  (segment (start 78.081925 120.184948) (end 78.102477 120.217655) (width 0.109) (layer "In4.Cu") (net 216))
  (segment (start 76.378238 116.865) (end 76.288607 116.875098) (width 0.109) (layer "In4.Cu") (net 216))
  (segment (start 77.043175 114.330884) (end 77.030417 114.367344) (width 0.109) (layer "In4.Cu") (net 216))
  (segment (start 78.081925 116.584948) (end 78.102477 116.617655) (width 0.109) (layer "In4.Cu") (net 216))
  (segment (start 75.985539 118.378166) (end 75.975441 118.467797) (width 0.109) (layer "In4.Cu") (net 216))
  (segment (start 75.985539 116.206833) (end 76.01533 116.291969) (width 0.109) (layer "In4.Cu") (net 216))
  (segment (start 78.115235 116.654115) (end 78.119559 116.6925) (width 0.109) (layer "In4.Cu") (net 216))
  (segment (start 76.063318 119.968342) (end 76.127098 120.032122) (width 0.109) (layer "In4.Cu") (net 216))
  (segment (start 75.975441 114.867797) (end 75.975441 114.917202) (width 0.109) (layer "In4.Cu") (net 216))
  (segment (start 76.063318 117.016657) (end 76.01533 117.09303) (width 0.109) (layer "In4.Cu") (net 216))
  (segment (start 77.08739 120.69303) (end 77.057599 120.778166) (width 0.109) (layer "In4.Cu") (net 216))
  (segment (start 78.081925 117.784948) (end 78.102477 117.817655) (width 0.109) (layer "In4.Cu") (net 216))
  (segment (start 78.054611 119.227365) (end 78.021904 119.247917) (width 0.109) (layer "In4.Cu") (net 216))
  (segment (start 75.975441 114.917202) (end 75.985539 115.006833) (width 0.109) (layer "In4.Cu") (net 216))
  (segment (start 78.054611 115.627365) (end 78.021904 115.647917) (width 0.109) (layer "In4.Cu") (net 216))
  (segment (start 76.01533 118.691969) (end 76.063318 118.768342) (width 0.109) (layer "In4.Cu") (net 216))
  (segment (start 77.985444 116.524324) (end 78.021904 116.537082) (width 0.109) (layer "In4.Cu") (net 216))
  (segment (start 78.081925 115.384948) (end 78.102477 115.417655) (width 0.109) (layer "In4.Cu") (net 216))
  (segment (start 78.021904 119.247917) (end 77.985444 119.260675) (width 0.109) (layer "In4.Cu") (net 216))
  (segment (start 78.115235 119.054115) (end 78.119559 119.0925) (width 0.109) (layer "In4.Cu") (net 216))
  (segment (start 77.057599 120.778166) (end 77.0475 120.867797) (width 0.109) (layer "In4.Cu") (net 216))
  (segment (start 78.102477 115.417655) (end 78.115235 115.454115) (width 0.109) (layer "In4.Cu") (net 216))
  (segment (start 76.063318 115.816657) (end 76.01533 115.89303) (width 0.109) (layer "In4.Cu") (net 216))
  (segment (start 75.985539 119.806833) (end 76.01533 119.891969) (width 0.109) (layer "In4.Cu") (net 216))
  (segment (start 78.102477 117.817655) (end 78.115235 117.854115) (width 0.109) (layer "In4.Cu") (net 216))
  (segment (start 75.975441 119.717202) (end 75.985539 119.806833) (width 0.109) (layer "In4.Cu") (net 216))
  (segment (start 76.288607 114.475098) (end 76.203471 114.504889) (width 0.109) (layer "In4.Cu") (net 216))
  (segment (start 78.102477 120.367344) (end 78.081925 120.400051) (width 0.109) (layer "In4.Cu") (net 216))
  (segment (start 76.063318 116.368342) (end 76.127098 116.432122) (width 0.109) (layer "In4.Cu") (net 216))
  (segment (start 76.949844 114.447917) (end 76.913384 114.460675) (width 0.109) (layer "In4.Cu") (net 216))
  (segment (start 76.01533 119.891969) (end 76.063318 119.968342) (width 0.109) (layer "In4.Cu") (net 216))
  (segment (start 76.288607 118.075098) (end 76.203471 118.104889) (width 0.109) (layer "In4.Cu") (net 216))
  (segment (start 78.054611 116.827365) (end 78.021904 116.847917) (width 0.109) (layer "In4.Cu") (net 216))
  (segment (start 76.203471 116.48011) (end 76.288607 116.509901) (width 0.109) (layer "In4.Cu") (net 216))
  (segment (start 78.054611 120.427365) (end 78.021904 120.447917) (width 0.109) (layer "In4.Cu") (net 216))
  (segment (start 90.472186 131.6775) (end 90.7 131.905314) (width 0.109) (layer "In4.Cu") (net 216))
  (segment (start 76.01533 114.69303) (end 75.985539 114.778166) (width 0.109) (layer "In4.Cu") (net 216))
  (segment (start 77.985444 120.460675) (end 77.947059 120.465) (width 0.109) (layer "In4.Cu") (net 216))
  (segment (start 78.102477 119.167344) (end 78.081925 119.200051) (width 0.109) (layer "In4.Cu") (net 216))
  (segment (start 77.947059 118.065) (end 76.378238 118.065) (width 0.109) (layer "In4.Cu") (net 216))
  (segment (start 77.199158 120.552877) (end 77.135378 120.616657) (width 0.109) (layer "In4.Cu") (net 216))
  (segment (start 76.127098 114.552877) (end 76.063318 114.616657) (width 0.109) (layer "In4.Cu") (net 216))
  (segment (start 77.0475 120.867797) (end 77.0475 123.452814) (width 0.109) (layer "In4.Cu") (net 216))
  (segment (start 78.119559 120.2925) (end 78.115235 120.330884) (width 0.109) (layer "In4.Cu") (net 216))
  (segment (start 78.4295 111.969032) (end 77.700654 111.969032) (width 0.109) (layer "In4.Cu") (net 216))
  (segment (start 77.947059 118.92) (end 77.985444 118.924324) (width 0.109) (layer "In4.Cu") (net 216))
  (segment (start 78.709 111.907532) (end 79.12482 111.907532) (width 0.182) (layer "B.Cu") (net 216))
  (segment (start 79.12482 111.907532) (end 79.238296 112.021008) (width 0.182) (layer "B.Cu") (net 216))
  (segment (start 80.938999 112.811) (end 80.999999 112.75) (width 0.182) (layer "B.Cu") (net 216))
  (segment (start 80.999999 112.75) (end 81.9 112.75) (width 0.182) (layer "B.Cu") (net 216))
  (segment (start 80.80924 112.811) (end 80.938999 112.811) (width 0.182) (layer "B.Cu") (net 216))
  (segment (start 79.238296 112.021008) (end 80.019248 112.021008) (width 0.182) (layer "B.Cu") (net 216))
  (segment (start 78.6 111.798532) (end 78.709 111.907532) (width 0.182) (layer "B.Cu") (net 216))
  (segment (start 80.019248 112.021008) (end 80.80924 112.811) (width 0.182) (layer "B.Cu") (net 216))
  (segment (start 90.7865 132.544) (end 91.1715 132.233999) (width 0.182) (layer "F.Cu") (net 217))
  (via (at 78.6 112.394533) (size 0.45) (drill 0.1) (layers "F.Cu" "B.Cu") (net 217))
  (via (at 91.1715 132.233999) (size 0.45) (drill 0.1) (layers "F.Cu" "B.Cu") (net 217))
  (segment (start 77.373265 112.955121) (end 77.399685 112.964365) (width 0.109) (layer "In4.Cu") (net 217))
  (segment (start 76.402941 115.065) (end 77.971762 115.065) (width 0.109) (layer "In4.Cu") (net 217))
  (segment (start 77.633405 123.417728) (end 77.655963 123.422877) (width 0.109) (layer "In4.Cu") (net 217))
  (segment (start 76.247523 118.417655) (end 76.234765 118.454115) (width 0.109) (layer "In4.Cu") (net 217))
  (segment (start 77.464147 123.476954) (end 77.487285 123.476955) (width 0.109) (layer "In4.Cu") (net 217))
  (segment (start 78.222902 115.832122) (end 78.146529 115.88011) (width 0.109) (layer "In4.Cu") (net 217))
  (segment (start 88.62483 131.147765) (end 88.645679 131.114584) (width 0.109) (layer "In4.Cu") (net 217))
  (segment (start 77.971762 119.52) (end 76.402941 119.52) (width 0.109) (layer "In4.Cu") (net 217))
  (segment (start 77.971762 115.065) (end 78.061393 115.075098) (width 0.109) (layer "In4.Cu") (net 217))
  (segment (start 77.971762 120.72) (end 77.475 120.72) (width 0.109) (layer "In4.Cu") (net 217))
  (segment (start 76.268075 119.584948) (end 76.247523 119.617655) (width 0.109) (layer "In4.Cu") (net 217))
  (segment (start 78.222902 119.952877) (end 78.286682 120.016657) (width 0.109) (layer "In4.Cu") (net 217))
  (segment (start 88.743558 131.053082) (end 88.7825 131.048694) (width 0.109) (layer "In4.Cu") (net 217))
  (segment (start 77.509841 123.471806) (end 77.530688 123.461768) (width 0.109) (layer "In4.Cu") (net 217))
  (segment (start 78.374559 117.917202) (end 78.364461 118.006833) (width 0.109) (layer "In4.Cu") (net 217))
  (segment (start 77.702924 123.747611) (end 77.72636 123.771046) (width 0.109) (layer "In4.Cu") (net 217))
  (segment (start 78.374559 120.267797) (end 78.374559 120.317202) (width 0.109) (layer "In4.Cu") (net 217))
  (segment (start 76.247523 119.767344) (end 76.268075 119.800051) (width 0.109) (layer "In4.Cu") (net 217))
  (segment (start 78.061393 117.475098) (end 78.146529 117.504889) (width 0.109) (layer "In4.Cu") (net 217))
  (segment (start 77.610269 123.417729) (end 77.633405 123.417728) (width 0.109) (layer "In4.Cu") (net 217))
  (segment (start 78.286682 118.816657) (end 78.33467 118.89303) (width 0.109) (layer "In4.Cu") (net 217))
  (segment (start 78.146529 117.08011) (end 78.061393 117.109901) (width 0.109) (layer "In4.Cu") (net 217))
  (segment (start 77.074469 114.68011) (end 76.989333 114.709901) (width 0.109) (layer "In4.Cu") (net 217))
  (segment (start 77.329772 112.920436) (end 77.349564 112.940228) (width 0.109) (layer "In4.Cu") (net 217))
  (segment (start 78.33467 117.69303) (end 78.364461 117.778166) (width 0.109) (layer "In4.Cu") (net 217))
  (segment (start 77.673311 123.662982) (end 77.673312 123.68612) (width 0.109) (layer "In4.Cu") (net 217))
  (segment (start 76.268075 116.200051) (end 76.295389 116.227365) (width 0.109) (layer "In4.Cu") (net 217))
  (segment (start 77.605437 112.994771) (end 77.625229 113.014563) (width 0.109) (layer "In4.Cu") (net 217))
  (segment (start 77.727389 123.494304) (end 77.732538 123.516861) (width 0.109) (layer "In4.Cu") (net 217))
  (segment (start 76.402941 114.72) (end 76.364556 114.724324) (width 0.109) (layer "In4.Cu") (net 217))
  (segment (start 76.328096 114.737082) (end 76.295389 114.757634) (width 0.109) (layer "In4.Cu") (net 217))
  (segment (start 76.247523 117.367344) (end 76.268075 117.400051) (width 0.109) (layer "In4.Cu") (net 217))
  (segment (start 88.603112 131.286442) (end 88.6075 131.2475) (width 0.109) (layer "In4.Cu") (net 217))
  (segment (start 76.234765 119.730884) (end 76.247523 119.767344) (width 0.109) (layer "In4.Cu") (net 217))
  (segment (start 76.295389 117.427365) (end 76.328096 117.447917) (width 0.109) (layer "In4.Cu") (net 217))
  (segment (start 88.590169 131.32343) (end 88.603112 131.286442) (width 0.109) (layer "In4.Cu") (net 217))
  (segment (start 78.364461 119.206833) (end 78.33467 119.291969) (width 0.109) (layer "In4.Cu") (net 217))
  (segment (start 77.6525 113.0925) (end 77.649366 113.120315) (width 0.109) (layer "In4.Cu") (net 217))
  (segment (start 77.3025 114.317202) (end 77.292401 114.406833) (width 0.109) (layer "In4.Cu") (net 217))
  (segment (start 78.33467 116.891969) (end 78.286682 116.968342) (width 0.109) (layer "In4.Cu") (net 217))
  (segment (start 77.314879 112.896735) (end 77.329772 112.920436) (width 0.109) (layer "In4.Cu") (net 217))
  (segment (start 78.364461 115.378166) (end 78.374559 115.467797) (width 0.109) (layer "In4.Cu") (net 217))
  (segment (start 78.061393 118.309901) (end 77.971762 118.32) (width 0.109) (layer "In4.Cu") (net 217))
  (segment (start 76.234765 114.930884) (end 76.247523 114.967344) (width 0.109) (layer "In4.Cu") (net 217))
  (segment (start 78.286682 120.568342) (end 78.222902 120.632122) (width 0.109) (layer "In4.Cu") (net 217))
  (segment (start 89.093558 131.418113) (end 89.1325 131.4225) (width 0.109) (layer "In4.Cu") (net 217))
  (segment (start 78.146529 118.704889) (end 78.222902 118.752877) (width 0.109) (layer "In4.Cu") (net 217))
  (segment (start 76.328096 115.047917) (end 76.364556 115.060675) (width 0.109) (layer "In4.Cu") (net 217))
  (segment (start 76.364556 114.724324) (end 76.328096 114.737082) (width 0.109) (layer "In4.Cu") (net 217))
  (segment (start 78.286682 115.768342) (end 78.222902 115.832122) (width 0.109) (layer "In4.Cu") (net 217))
  (segment (start 76.234765 117.330884) (end 76.247523 117.367344) (width 0.109) (layer "In4.Cu") (net 217))
  (segment (start 76.364556 115.924324) (end 76.328096 115.937082) (width 0.109) (layer "In4.Cu") (net 217))
  (segment (start 76.295389 118.357634) (end 76.268075 118.384948) (width 0.109) (layer "In4.Cu") (net 217))
  (segment (start 77.314879 113.288264) (end 77.305635 113.314684) (width 0.109) (layer "In4.Cu") (net 217))
  (segment (start 77.806282 112.224032) (end 77.3025 112.727814) (width 0.109) (layer "In4.Cu") (net 217))
  (segment (start 76.295389 115.027365) (end 76.328096 115.047917) (width 0.109) (layer "In4.Cu") (net 217))
  (segment (start 77.673312 123.68612) (end 77.678459 123.708676) (width 0.109) (layer "In4.Cu") (net 217))
  (segment (start 76.402941 117.465) (end 77.971762 117.465) (width 0.109) (layer "In4.Cu") (net 217))
  (segment (start 78.364461 117.778166) (end 78.374559 117.867797) (width 0.109) (layer "In4.Cu") (net 217))
  (segment (start 88.9575 131.2475) (end 88.961887 131.286442) (width 0.109) (layer "In4.Cu") (net 217))
  (segment (start 76.364556 115.060675) (end 76.402941 115.065) (width 0.109) (layer "In4.Cu") (net 217))
  (segment (start 76.295389 119.827365) (end 76.328096 119.847917) (width 0.109) (layer "In4.Cu") (net 217))
  (segment (start 77.649366 113.120315) (end 77.640122 113.146735) (width 0.109) (layer "In4.Cu") (net 217))
  (segment (start 77.400156 120.737082) (end 77.367449 120.757634) (width 0.109) (layer "In4.Cu") (net 217))
  (segment (start 78.6 112.394533) (end 78.6 112.394532) (width 0.109) (layer "In4.Cu") (net 217))
  (segment (start 76.402941 115.92) (end 76.364556 115.924324) (width 0.109) (layer "In4.Cu") (net 217))
  (segment (start 77.971762 116.265) (end 78.061393 116.275098) (width 0.109) (layer "In4.Cu") (net 217))
  (segment (start 76.230441 117.2925) (end 76.234765 117.330884) (width 0.109) (layer "In4.Cu") (net 217))
  (segment (start 76.234765 114.854115) (end 76.230441 114.8925) (width 0.109) (layer "In4.Cu") (net 217))
  (segment (start 78.222902 115.152877) (end 78.286682 115.216657) (width 0.109) (layer "In4.Cu") (net 217))
  (segment (start 89.023389 131.384321) (end 89.05657 131.40517) (width 0.109) (layer "In4.Cu") (net 217))
  (segment (start 78.364461 115.606833) (end 78.33467 115.691969) (width 0.109) (layer "In4.Cu") (net 217))
  (segment (start 78.374559 116.667797) (end 78.374559 116.717202) (width 0.109) (layer "In4.Cu") (net 217))
  (segment (start 77.3025 112.8425) (end 77.305635 112.870315) (width 0.109) (layer "In4.Cu") (net 217))
  (segment (start 77.717352 123.583402) (end 77.688498 123.619579) (width 0.109) (layer "In4.Cu") (net 217))
  (segment (start 78.374559 115.517202) (end 78.364461 115.606833) (width 0.109) (layer "In4.Cu") (net 217))
  (segment (start 76.247523 116.017655) (end 76.234765 116.054115) (width 0.109) (layer "In4.Cu") (net 217))
  (segment (start 78.061393 116.275098) (end 78.146529 116.304889) (width 0.109) (layer "In4.Cu") (net 217))
  (segment (start 88.89161 131.086874) (end 88.91932 131.114584) (width 0.109) (layer "In4.Cu") (net 217))
  (segment (start 76.402941 118.665) (end 77.971762 118.665) (width 0.109) (layer "In4.Cu") (net 217))
  (segment (start 77.548777 123.447343) (end 77.548776 123.447341) (width 0.109) (layer "In4.Cu") (net 217))
  (segment (start 77.587711 123.422876) (end 77.610269 123.417729) (width 0.109) (layer "In4.Cu") (net 217))
  (segment (start 77.971762 117.465) (end 78.061393 117.475098) (width 0.109) (layer "In4.Cu") (net 217))
  (segment (start 89.1325 131.4225) (end 90.577814 131.4225) (width 0.109) (layer "In4.Cu") (net 217))
  (segment (start 76.364556 117.460675) (end 76.402941 117.465) (width 0.109) (layer "In4.Cu") (net 217))
  (segment (start 76.234765 119.654115) (end 76.230441 119.6925) (width 0.109) (layer "In4.Cu") (net 217))
  (segment (start 78.364461 116.806833) (end 78.33467 116.891969) (width 0.109) (layer "In4.Cu") (net 217))
  (segment (start 77.150842 114.632122) (end 77.074469 114.68011) (width 0.109) (layer "In4.Cu") (net 217))
  (segment (start 77.555316 113.214365) (end 77.5275 113.2175) (width 0.109) (layer "In4.Cu") (net 217))
  (segment (start 78.286682 117.616657) (end 78.33467 117.69303) (width 0.109) (layer "In4.Cu") (net 217))
  (segment (start 76.899702 114.72) (end 76.402941 114.72) (width 0.109) (layer "In4.Cu") (net 217))
  (segment (start 88.821441 131.053082) (end 88.858429 131.066025) (width 0.109) (layer "In4.Cu") (net 217))
  (segment (start 77.649366 113.064684) (end 77.6525 113.0925) (width 0.109) (layer "In4.Cu") (net 217))
  (segment (start 78.061393 119.509901) (end 77.971762 119.52) (width 0.109) (layer "In4.Cu") (net 217))
  (segment (start 76.234765 118.454115) (end 76.230441 118.4925) (width 0.109) (layer "In4.Cu") (net 217))
  (segment (start 76.328096 115.937082) (end 76.295389 115.957634) (width 0.109) (layer "In4.Cu") (net 217))
  (segment (start 77.530688 123.461768) (end 77.548777 123.447343) (width 0.109) (layer "In4.Cu") (net 217))
  (segment (start 78.222902 118.232122) (end 78.146529 118.28011) (width 0.109) (layer "In4.Cu") (net 217))
  (segment (start 78.33467 116.49303) (end 78.364461 116.578166) (width 0.109) (layer "In4.Cu") (net 217))
  (segment (start 78.222902 119.432122) (end 78.146529 119.48011) (width 0.109) (layer "In4.Cu") (net 217))
  (segment (start 88.91932 131.114584) (end 88.940169 131.147765) (width 0.109) (layer "In4.Cu") (net 217))
  (segment (start 78.222902 116.352877) (end 78.286682 116.416657) (width 0.109) (layer "In4.Cu") (net 217))
  (segment (start 77.487285 123.476955) (end 77.509841 123.471806) (width 0.109) (layer "In4.Cu") (net 217))
  (segment (start 78.146529 115.104889) (end 78.222902 115.152877) (width 0.109) (layer "In4.Cu") (net 217))
  (segment (start 88.4325 131.4225) (end 88.471441 131.418113) (width 0.109) (layer "In4.Cu") (net 217))
  (segment (start 77.399685 113.220634) (end 77.373265 113.229878) (width 0.109) (layer "In4.Cu") (net 217))
  (segment (start 78.374559 119.117202) (end 78.364461 119.206833) (width 0.109) (layer "In4.Cu") (net 217))
  (segment (start 78.061393 115.075098) (end 78.146529 115.104889) (width 0.109) (layer "In4.Cu") (net 217))
  (segment (start 88.6075 131.2475) (end 88.6075 131.223694) (width 0.109) (layer "In4.Cu") (net 217))
  (segment (start 76.364556 119.860675) (end 76.402941 119.865) (width 0.109) (layer "In4.Cu") (net 217))
  (segment (start 78.061393 118.675098) (end 78.146529 118.704889) (width 0.109) (layer "In4.Cu") (net 217))
  (segment (start 88.611887 131.184753) (end 88.62483 131.147765) (width 0.109) (layer "In4.Cu") (net 217))
  (segment (start 78.374559 120.317202) (end 78.364461 120.406833) (width 0.109) (layer "In4.Cu") (net 217))
  (segment (start 76.402941 119.52) (end 76.364556 119.524324) (width 0.109) (layer "In4.Cu") (net 217))
  (segment (start 88.940169 131.147765) (end 88.953112 131.184753) (width 0.109) (layer "In4.Cu") (net 217))
  (segment (start 88.858429 131.066025) (end 88.89161 131.086874) (width 0.109) (layer "In4.Cu") (net 217))
  (segment (start 77.3025 113.3425) (end 77.3025 114.317202) (width 0.109) (layer "In4.Cu") (net 217))
  (segment (start 76.295389 117.157634) (end 76.268075 117.184948) (width 0.109) (layer "In4.Cu") (net 217))
  (segment (start 88.953112 131.184753) (end 88.9575 131.223694) (width 0.109) (layer "In4.Cu") (net 217))
  (segment (start 78.286682 118.168342) (end 78.222902 118.232122) (width 0.109) (layer "In4.Cu") (net 217))
  (segment (start 76.402941 116.265) (end 77.971762 116.265) (width 0.109) (layer "In4.Cu") (net 217))
  (segment (start 78.061393 115.909901) (end 77.971762 115.92) (width 0.109) (layer "In4.Cu") (net 217))
  (segment (start 78.286682 120.016657) (end 78.33467 120.09303) (width 0.109) (layer "In4.Cu") (net 217))
  (segment (start 76.402941 117.12) (end 76.364556 117.124324) (width 0.109) (layer "In4.Cu") (net 217))
  (segment (start 76.234765 116.130884) (end 76.247523 116.167344) (width 0.109) (layer "In4.Cu") (net 217))
  (segment (start 78.146529 120.68011) (end 78.061393 120.709901) (width 0.109) (layer "In4.Cu") (net 217))
  (segment (start 77.694898 123.447342) (end 77.702926 123.45537) (width 0.109) (layer "In4.Cu") (net 217))
  (segment (start 76.295389 115.957634) (end 76.268075 115.984948) (width 0.109) (layer "In4.Cu") (net 217))
  (segment (start 76.328096 116.247917) (end 76.364556 116.260675) (width 0.109) (layer "In4.Cu") (net 217))
  (segment (start 76.247523 119.617655) (end 76.234765 119.654115) (width 0.109) (layer "In4.Cu") (net 217))
  (segment (start 76.268075 119.800051) (end 76.295389 119.827365) (width 0.109) (layer "In4.Cu") (net 217))
  (segment (start 90.975 132.037499) (end 91.1715 132.233999) (width 0.109) (layer "In4.Cu") (net 217))
  (segment (start 88.645679 131.114584) (end 88.673389 131.086874) (width 0.109) (layer "In4.Cu") (net 217))
  (segment (start 88.97483 131.32343) (end 88.995679 131.356611) (width 0.109) (layer "In4.Cu") (net 217))
  (segment (start 77.688499 123.729523) (end 77.702924 123.747611) (width 0.109) (layer "In4.Cu") (net 217))
  (segment (start 76.364556 117.124324) (end 76.328096 117.137082) (width 0.109) (layer "In4.Cu") (net 217))
  (segment (start 78.146529 119.48011) (end 78.061393 119.509901) (width 0.109) (layer "In4.Cu") (net 217))
  (segment (start 77.717351 123.473458) (end 77.727389 123.494304) (width 0.109) (layer "In4.Cu") (net 217))
  (segment (start 77.305635 113.314684) (end 77.3025 113.3425) (width 0.109) (layer "In4.Cu") (net 217))
  (segment (start 77.349564 113.244771) (end 77.329772 113.264563) (width 0.109) (layer "In4.Cu") (net 217))
  (segment (start 76.328096 118.337082) (end 76.295389 118.357634) (width 0.109) (layer "In4.Cu") (net 217))
  (segment (start 88.508429 131.40517) (end 88.54161 131.384321) (width 0.109) (layer "In4.Cu") (net 217))
  (segment (start 77.581736 112.979878) (end 77.605437 112.994771) (width 0.109) (layer "In4.Cu") (net 217))
  (segment (start 76.268075 118.384948) (end 76.247523 118.417655) (width 0.109) (layer "In4.Cu") (net 217))
  (segment (start 88.961887 131.286442) (end 88.97483 131.32343) (width 0.109) (layer "In4.Cu") (net 217))
  (segment (start 77.625229 113.014563) (end 77.640122 113.038264) (width 0.109) (layer "In4.Cu") (net 217))
  (segment (start 76.295389 116.227365) (end 76.328096 116.247917) (width 0.109) (layer "In4.Cu") (net 217))
  (segment (start 77.625229 113.170436) (end 77.605437 113.190228) (width 0.109) (layer "In4.Cu") (net 217))
  (segment (start 78.6 112.394532) (end 78.4295 112.224032) (width 0.109) (layer "In4.Cu") (net 217))
  (segment (start 77.72739 123.562556) (end 77.717352 123.583402) (width 0.109) (layer "In4.Cu") (net 217))
  (segment (start 89.05657 131.40517) (end 89.093558 131.418113) (width 0.109) (layer "In4.Cu") (net 217))
  (segment (start 78.286682 115.216657) (end 78.33467 115.29303) (width 0.109) (layer "In4.Cu") (net 217))
  (segment (start 78.33467 119.291969) (end 78.286682 119.368342) (width 0.109) (layer "In4.Cu") (net 217))
  (segment (start 78.286682 119.368342) (end 78.222902 119.432122) (width 0.109) (layer "In4.Cu") (net 217))
  (segment (start 78.222902 117.032122) (end 78.146529 117.08011) (width 0.109) (layer "In4.Cu") (net 217))
  (segment (start 76.328096 118.647917) (end 76.364556 118.660675) (width 0.109) (layer "In4.Cu") (net 217))
  (segment (start 76.230441 118.4925) (end 76.234765 118.530884) (width 0.109) (layer "In4.Cu") (net 217))
  (segment (start 77.292401 114.406833) (end 77.26261 114.491969) (width 0.109) (layer "In4.Cu") (net 217))
  (segment (start 77.4275 113.2175) (end 77.399685 113.220634) (width 0.109) (layer "In4.Cu") (net 217))
  (segment (start 76.295389 118.627365) (end 76.328096 118.647917) (width 0.109) (layer "In4.Cu") (net 217))
  (segment (start 77.688498 123.619579) (end 77.67846 123.640426) (width 0.109) (layer "In4.Cu") (net 217))
  (segment (start 78.222902 120.632122) (end 78.146529 120.68011) (width 0.109) (layer "In4.Cu") (net 217))
  (segment (start 77.566866 123.432916) (end 77.587711 123.422876) (width 0.109) (layer "In4.Cu") (net 217))
  (segment (start 78.286682 116.968342) (end 78.222902 117.032122) (width 0.109) (layer "In4.Cu") (net 217))
  (segment (start 77.4275 112.9675) (end 77.5275 112.9675) (width 0.109) (layer "In4.Cu") (net 217))
  (segment (start 76.268075 118.600051) (end 76.295389 118.627365) (width 0.109) (layer "In4.Cu") (net 217))
  (segment (start 77.399685 112.964365) (end 77.4275 112.9675) (width 0.109) (layer "In4.Cu") (net 217))
  (segment (start 76.364556 116.260675) (end 76.402941 116.265) (width 0.109) (layer "In4.Cu") (net 217))
  (segment (start 76.328096 117.447917) (end 76.364556 117.460675) (width 0.109) (layer "In4.Cu") (net 217))
  (segment (start 76.268075 115.984948) (end 76.247523 116.017655) (width 0.109) (layer "In4.Cu") (net 217))
  (segment (start 77.548776 123.447341) (end 77.566866 123.432916) (width 0.109) (layer "In4.Cu") (net 217))
  (segment (start 90.975 131.819686) (end 90.975 132.037499) (width 0.109) (layer "In4.Cu") (net 217))
  (segment (start 78.061393 120.709901) (end 77.971762 120.72) (width 0.109) (layer "In4.Cu") (net 217))
  (segment (start 77.971762 118.665) (end 78.061393 118.675098) (width 0.109) (layer "In4.Cu") (net 217))
  (segment (start 78.33467 115.691969) (end 78.286682 115.768342) (width 0.109) (layer "In4.Cu") (net 217))
  (segment (start 76.234765 116.054115) (end 76.230441 116.0925) (width 0.109) (layer "In4.Cu") (net 217))
  (segment (start 77.214622 114.568342) (end 77.150842 114.632122) (width 0.109) (layer "In4.Cu") (net 217))
  (segment (start 77.555316 112.970634) (end 77.581736 112.979878) (width 0.109) (layer "In4.Cu") (net 217))
  (segment (start 88.995679 131.356611) (end 89.023389 131.384321) (width 0.109) (layer "In4.Cu") (net 217))
  (segment (start 77.3025 123.347186) (end 77.402657 123.447343) (width 0.109) (layer "In4.Cu") (net 217))
  (segment (start 76.295389 119.557634) (end 76.268075 119.584948) (width 0.109) (layer "In4.Cu") (net 217))
  (segment (start 77.340135 120.784948) (end 77.319583 120.817655) (width 0.109) (layer "In4.Cu") (net 217))
  (segment (start 78.364461 120.178166) (end 78.374559 120.267797) (width 0.109) (layer "In4.Cu") (net 217))
  (segment (start 76.268075 115.000051) (end 76.295389 115.027365) (width 0.109) (layer "In4.Cu") (net 217))
  (segment (start 77.306825 120.854115) (end 77.3025 120.8925) (width 0.109) (layer "In4.Cu") (net 217))
  (segment (start 77.441591 123.471807) (end 77.464147 123.476954) (width 0.109) (layer "In4.Cu") (net 217))
  (segment (start 77.5275 112.9675) (end 77.555316 112.970634) (width 0.109) (layer "In4.Cu") (net 217))
  (segment (start 78.364461 116.578166) (end 78.374559 116.667797) (width 0.109) (layer "In4.Cu") (net 217))
  (segment (start 77.3025 120.8925) (end 77.3025 123.347186) (width 0.109) (layer "In4.Cu") (net 217))
  (segment (start 77.678459 123.708676) (end 77.688499 123.729523) (width 0.109) (layer "In4.Cu") (net 217))
  (segment (start 76.328096 117.137082) (end 76.295389 117.157634) (width 0.109) (layer "In4.Cu") (net 217))
  (segment (start 76.364556 118.660675) (end 76.402941 118.665) (width 0.109) (layer "In4.Cu") (net 217))
  (segment (start 85.377814 131.4225) (end 88.4325 131.4225) (width 0.109) (layer "In4.Cu") (net 217))
  (segment (start 76.230441 119.6925) (end 76.234765 119.730884) (width 0.109) (layer "In4.Cu") (net 217))
  (segment (start 78.146529 116.304889) (end 78.222902 116.352877) (width 0.109) (layer "In4.Cu") (net 217))
  (segment (start 78.061393 119.875098) (end 78.146529 119.904889) (width 0.109) (layer "In4.Cu") (net 217))
  (segment (start 78.286682 116.416657) (end 78.33467 116.49303) (width 0.109) (layer "In4.Cu") (net 217))
  (segment (start 76.230441 116.0925) (end 76.234765 116.130884) (width 0.109) (layer "In4.Cu") (net 217))
  (segment (start 77.26261 114.491969) (end 77.214622 114.568342) (width 0.109) (layer "In4.Cu") (net 217))
  (segment (start 77.971762 119.865) (end 78.061393 119.875098) (width 0.109) (layer "In4.Cu") (net 217))
  (segment (start 77.367449 120.757634) (end 77.340135 120.784948) (width 0.109) (layer "In4.Cu") (net 217))
  (segment (start 76.989333 114.709901) (end 76.899702 114.72) (width 0.109) (layer "In4.Cu") (net 217))
  (segment (start 77.971762 117.12) (end 76.402941 117.12) (width 0.109) (layer "In4.Cu") (net 217))
  (segment (start 78.222902 118.752877) (end 78.286682 118.816657) (width 0.109) (layer "In4.Cu") (net 217))
  (segment (start 88.7825 131.048694) (end 88.821441 131.053082) (width 0.109) (layer "In4.Cu") (net 217))
  (segment (start 77.581736 113.205121) (end 77.555316 113.214365) (width 0.109) (layer "In4.Cu") (net 217))
  (segment (start 78.33467 115.29303) (end 78.364461 115.378166) (width 0.109) (layer "In4.Cu") (net 217))
  (segment (start 77.305635 112.870315) (end 77.314879 112.896735) (width 0.109) (layer "In4.Cu") (net 217))
  (segment (start 78.364461 118.006833) (end 78.33467 118.091969) (width 0.109) (layer "In4.Cu") (net 217))
  (segment (start 77.67846 123.640426) (end 77.673311 123.662982) (width 0.109) (layer "In4.Cu") (net 217))
  (segment (start 76.247523 117.217655) (end 76.234765 117.254115) (width 0.109) (layer "In4.Cu") (net 217))
  (segment (start 88.471441 131.418113) (end 88.508429 131.40517) (width 0.109) (layer "In4.Cu") (net 217))
  (segment (start 76.247523 114.817655) (end 76.234765 114.854115) (width 0.109) (layer "In4.Cu") (net 217))
  (segment (start 88.9575 131.223694) (end 88.9575 131.2475) (width 0.109) (layer "In4.Cu") (net 217))
  (segment (start 90.577814 131.4225) (end 90.975 131.819686) (width 0.109) (layer "In4.Cu") (net 217))
  (segment (start 78.374559 116.717202) (end 78.364461 116.806833) (width 0.109) (layer "In4.Cu") (net 217))
  (segment (start 76.295389 114.757634) (end 76.268075 114.784948) (width 0.109) (layer "In4.Cu") (net 217))
  (segment (start 77.5275 113.2175) (end 77.4275 113.2175) (width 0.109) (layer "In4.Cu") (net 217))
  (segment (start 76.268075 117.184948) (end 76.247523 117.217655) (width 0.109) (layer "In4.Cu") (net 217))
  (segment (start 88.54161 131.384321) (end 88.56932 131.356611) (width 0.109) (layer "In4.Cu") (net 217))
  (segment (start 76.268075 117.400051) (end 76.295389 117.427365) (width 0.109) (layer "In4.Cu") (net 217))
  (segment (start 76.230441 114.8925) (end 76.234765 114.930884) (width 0.109) (layer "In4.Cu") (net 217))
  (segment (start 78.33467 118.89303) (end 78.364461 118.978166) (width 0.109) (layer "In4.Cu") (net 217))
  (segment (start 76.328096 119.847917) (end 76.364556 119.860675) (width 0.109) (layer "In4.Cu") (net 217))
  (segment (start 88.6075 131.223694) (end 88.611887 131.184753) (width 0.109) (layer "In4.Cu") (net 217))
  (segment (start 78.146529 118.28011) (end 78.061393 118.309901) (width 0.109) (layer "In4.Cu") (net 217))
  (segment (start 77.349564 112.940228) (end 77.373265 112.955121) (width 0.109) (layer "In4.Cu") (net 217))
  (segment (start 88.673389 131.086874) (end 88.70657 131.066025) (width 0.109) (layer "In4.Cu") (net 217))
  (segment (start 77.72636 123.771046) (end 85.377814 131.4225) (width 0.109) (layer "In4.Cu") (net 217))
  (segment (start 77.640122 113.146735) (end 77.625229 113.170436) (width 0.109) (layer "In4.Cu") (net 217))
  (segment (start 76.402941 119.865) (end 77.971762 119.865) (width 0.109) (layer "In4.Cu") (net 217))
  (segment (start 76.402941 118.32) (end 76.364556 118.324324) (width 0.109) (layer "In4.Cu") (net 217))
  (segment (start 78.364461 118.978166) (end 78.374559 119.067797) (width 0.109) (layer "In4.Cu") (net 217))
  (segment (start 78.364461 120.406833) (end 78.33467 120.491969) (width 0.109) (layer "In4.Cu") (net 217))
  (segment (start 77.436616 120.724324) (end 77.400156 120.737082) (width 0.109) (layer "In4.Cu") (net 217))
  (segment (start 77.319583 120.817655) (end 77.306825 120.854115) (width 0.109) (layer "In4.Cu") (net 217))
  (segment (start 76.234765 117.254115) (end 76.230441 117.2925) (width 0.109) (layer "In4.Cu") (net 217))
  (segment (start 78.061393 117.109901) (end 77.971762 117.12) (width 0.109) (layer "In4.Cu") (net 217))
  (segment (start 77.329772 113.264563) (end 77.314879 113.288264) (width 0.109) (layer "In4.Cu") (net 217))
  (segment (start 78.4295 112.224032) (end 77.806282 112.224032) (width 0.109) (layer "In4.Cu") (net 217))
  (segment (start 78.33467 118.091969) (end 78.286682 118.168342) (width 0.109) (layer "In4.Cu") (net 217))
  (segment (start 76.364556 118.324324) (end 76.328096 118.337082) (width 0.109) (layer "In4.Cu") (net 217))
  (segment (start 78.222902 117.552877) (end 78.286682 117.616657) (width 0.109) (layer "In4.Cu") (net 217))
  (segment (start 76.364556 119.524324) (end 76.328096 119.537082) (width 0.109) (layer "In4.Cu") (net 217))
  (segment (start 78.146529 119.904889) (end 78.222902 119.952877) (width 0.109) (layer "In4.Cu") (net 217))
  (segment (start 78.374559 115.467797) (end 78.374559 115.517202) (width 0.109) (layer "In4.Cu") (net 217))
  (segment (start 77.732538 123.516861) (end 77.732539 123.539999) (width 0.109) (layer "In4.Cu") (net 217))
  (segment (start 76.268075 114.784948) (end 76.247523 114.817655) (width 0.109) (layer "In4.Cu") (net 217))
  (segment (start 76.247523 114.967344) (end 76.268075 115.000051) (width 0.109) (layer "In4.Cu") (net 217))
  (segment (start 78.33467 120.09303) (end 78.364461 120.178166) (width 0.109) (layer "In4.Cu") (net 217))
  (segment (start 77.605437 113.190228) (end 77.581736 113.205121) (width 0.109) (layer "In4.Cu") (net 217))
  (segment (start 77.702926 123.45537) (end 77.717351 123.473458) (width 0.109) (layer "In4.Cu") (net 217))
  (segment (start 77.420746 123.461768) (end 77.441591 123.471807) (width 0.109) (layer "In4.Cu") (net 217))
  (segment (start 78.374559 119.067797) (end 78.374559 119.117202) (width 0.109) (layer "In4.Cu") (net 217))
  (segment (start 76.247523 118.567344) (end 76.268075 118.600051) (width 0.109) (layer "In4.Cu") (net 217))
  (segment (start 76.234765 118.530884) (end 76.247523 118.567344) (width 0.109) (layer "In4.Cu") (net 217))
  (segment (start 77.971762 118.32) (end 76.402941 118.32) (width 0.109) (layer "In4.Cu") (net 217))
  (segment (start 77.676808 123.432915) (end 77.694898 123.447342) (width 0.109) (layer "In4.Cu") (net 217))
  (segment (start 76.247523 116.167344) (end 76.268075 116.200051) (width 0.109) (layer "In4.Cu") (net 217))
  (segment (start 77.732539 123.539999) (end 77.72739 123.562556) (width 0.109) (layer "In4.Cu") (net 217))
  (segment (start 76.328096 119.537082) (end 76.295389 119.557634) (width 0.109) (layer "In4.Cu") (net 217))
  (segment (start 77.373265 113.229878) (end 77.349564 113.244771) (width 0.109) (layer "In4.Cu") (net 217))
  (segment (start 78.146529 117.504889) (end 78.222902 117.552877) (width 0.109) (layer "In4.Cu") (net 217))
  (segment (start 77.971762 115.92) (end 76.402941 115.92) (width 0.109) (layer "In4.Cu") (net 217))
  (segment (start 78.374559 117.867797) (end 78.374559 117.917202) (width 0.109) (layer "In4.Cu") (net 217))
  (segment (start 78.33467 120.491969) (end 78.286682 120.568342) (width 0.109) (layer "In4.Cu") (net 217))
  (segment (start 88.56932 131.356611) (end 88.590169 131.32343) (width 0.109) (layer "In4.Cu") (net 217))
  (segment (start 77.3025 112.727814) (end 77.3025 112.8425) (width 0.109) (layer "In4.Cu") (net 217))
  (segment (start 77.640122 113.038264) (end 77.649366 113.064684) (width 0.109) (layer "In4.Cu") (net 217))
  (segment (start 77.402657 123.447343) (end 77.420746 123.461768) (width 0.109) (layer "In4.Cu") (net 217))
  (segment (start 78.146529 115.88011) (end 78.061393 115.909901) (width 0.109) (layer "In4.Cu") (net 217))
  (segment (start 88.70657 131.066025) (end 88.743558 131.053082) (width 0.109) (layer "In4.Cu") (net 217))
  (segment (start 77.475 120.72) (end 77.436616 120.724324) (width 0.109) (layer "In4.Cu") (net 217))
  (segment (start 77.655963 123.422877) (end 77.676808 123.432915) (width 0.109) (layer "In4.Cu") (net 217))
  (segment (start 78.968244 112.285532) (end 79.081711 112.398999) (width 0.182) (layer "B.Cu") (net 217))
  (segment (start 80.938999 113.189) (end 80.999999 113.25) (width 0.182) (layer "B.Cu") (net 217))
  (segment (start 79.081711 112.398999) (end 79.86268 112.398999) (width 0.182) (layer "B.Cu") (net 217))
  (segment (start 79.86268 112.398999) (end 80.652681 113.189) (width 0.182) (layer "B.Cu") (net 217))
  (segment (start 80.999999 113.25) (end 81.9 113.25) (width 0.182) (layer "B.Cu") (net 217))
  (segment (start 78.6 112.394533) (end 78.709001 112.285532) (width 0.182) (layer "B.Cu") (net 217))
  (segment (start 80.652681 113.189) (end 80.938999 113.189) (width 0.182) (layer "B.Cu") (net 217))
  (segment (start 78.709001 112.285532) (end 78.968244 112.285532) (width 0.182) (layer "B.Cu") (net 217))
  (segment (start 91.9815 134.759) (end 92.3665 134.449) (width 0.182) (layer "F.Cu") (net 218))
  (via (at 78.425 113.206018) (size 0.45) (drill 0.1) (layers "F.Cu" "B.Cu") (net 218))
  (via (at 91.9815 134.759) (size 0.45) (drill 0.1) (layers "F.Cu" "B.Cu") (net 218))
  (segment (start 79.657215 115.28346) (end 79.630908 115.358639) (width 0.109) (layer "In6.Cu") (net 218))
  (segment (start 78.767872 118.805) (end 80.331208 118.805) (width 0.109) (layer "In6.Cu") (net 218))
  (segment (start 80.686894 120.160686) (end 80.686894 120.204313) (width 0.109) (layer "In6.Cu") (net 218))
  (segment (start 78.672097 117.758877) (end 78.691494 117.778274) (width 0.109) (layer "In6.Cu") (net 218))
  (segment (start 79.657215 121.081539) (end 79.666133 121.160686) (width 0.109) (layer "In6.Cu") (net 218))
  (segment (start 78.767872 116.805) (end 80.331208 116.805) (width 0.109) (layer "In6.Cu") (net 218))
  (segment (start 78.645372 120.6825) (end 78.648443 120.709758) (width 0.109) (layer "In6.Cu") (net 218))
  (segment (start 80.609295 120.42608) (end 80.552975 120.4824) (width 0.109) (layer "In6.Cu") (net 218))
  (segment (start 78.740613 115.563071) (end 78.714721 115.572131) (width 0.109) (layer "In6.Cu") (net 218))
  (segment (start 80.65167 118.358639) (end 80.609295 118.42608) (width 0.109) (layer "In6.Cu") (net 218))
  (segment (start 80.552975 119.882599) (end 80.609295 119.938919) (width 0.109) (layer "In6.Cu") (net 218))
  (segment (start 78.740613 116.801928) (end 78.767872 116.805) (width 0.109) (layer "In6.Cu") (net 218))
  (segment (start 78.648443 115.655241) (end 78.645372 115.6825) (width 0.109) (layer "In6.Cu") (net 218))
  (segment (start 80.686894 117.160686) (end 80.686894 117.204313) (width 0.109) (layer "In6.Cu") (net 218))
  (segment (start 78.714721 115.572131) (end 78.691494 115.586725) (width 0.109) (layer "In6.Cu") (net 218))
  (segment (start 78.740613 117.801928) (end 78.767872 117.805) (width 0.109) (layer "In6.Cu") (net 218))
  (segment (start 78.691494 118.586725) (end 78.672097 118.606122) (width 0.109) (layer "In6.Cu") (net 218))
  (segment (start 80.686894 120.204313) (end 80.677977 120.28346) (width 0.109) (layer "In6.Cu") (net 218))
  (segment (start 78.648443 115.709758) (end 78.657503 115.73565) (width 0.109) (layer "In6.Cu") (net 218))
  (segment (start 78.767872 120.56) (end 78.740613 120.563071) (width 0.109) (layer "In6.Cu") (net 218))
  (segment (start 79.6675 122.367187) (end 88.2075 130.907188) (width 0.109) (layer "In6.Cu") (net 218))
  (segment (start 80.65167 119.358639) (end 80.609295 119.42608) (width 0.109) (layer "In6.Cu") (net 218))
  (segment (start 78.645372 118.6825) (end 78.648443 118.709758) (width 0.109) (layer "In6.Cu") (net 218))
  (segment (start 78.691494 119.586725) (end 78.672097 119.606122) (width 0.109) (layer "In6.Cu") (net 218))
  (segment (start 89.192814 133.3725) (end 92.241026 133.3725) (width 0.109) (layer "In6.Cu") (net 218))
  (segment (start 80.552975 119.4824) (end 80.485534 119.524775) (width 0.109) (layer "In6.Cu") (net 218))
  (segment (start 80.677977 117.081539) (end 80.686894 117.160686) (width 0.109) (layer "In6.Cu") (net 218))
  (segment (start 78.645372 116.6825) (end 78.648443 116.709758) (width 0.109) (layer "In6.Cu") (net 218))
  (segment (start 79.286557 113.376243) (end 79.6675 113.757186) (width 0.109) (layer "In6.Cu") (net 218))
  (segment (start 80.331208 116.805) (end 80.410355 116.813917) (width 0.109) (layer "In6.Cu") (net 218))
  (segment (start 78.740613 120.801928) (end 78.767872 120.805) (width 0.109) (layer "In6.Cu") (net 218))
  (segment (start 80.677977 118.28346) (end 80.65167 118.358639) (width 0.109) (layer "In6.Cu") (net 218))
  (segment (start 78.767872 118.56) (end 78.740613 118.563071) (width 0.109) (layer "In6.Cu") (net 218))
  (segment (start 80.609295 118.42608) (end 80.552975 118.4824) (width 0.109) (layer "In6.Cu") (net 218))
  (segment (start 80.331208 117.56) (end 78.767872 117.56) (width 0.109) (layer "In6.Cu") (net 218))
  (segment (start 78.657503 116.73565) (end 78.672097 116.758877) (width 0.109) (layer "In6.Cu") (net 218))
  (segment (start 92.45 133.581474) (end 92.45 134.31275) (width 0.109) (layer "In6.Cu") (net 218))
  (segment (start 80.609295 116.42608) (end 80.552975 116.4824) (width 0.109) (layer "In6.Cu") (net 218))
  (segment (start 80.609295 119.938919) (end 80.65167 120.00636) (width 0.109) (layer "In6.Cu") (net 218))
  (segment (start 78.714721 118.572131) (end 78.691494 118.586725) (width 0.109) (layer "In6.Cu") (net 218))
  (segment (start 80.331208 115.805) (end 80.410355 115.813917) (width 0.109) (layer "In6.Cu") (net 218))
  (segment (start 78.645372 119.6825) (end 78.648443 119.709758) (width 0.109) (layer "In6.Cu") (net 218))
  (segment (start 79.630908 121.00636) (end 79.657215 121.081539) (width 0.109) (layer "In6.Cu") (net 218))
  (segment (start 78.648443 117.655241) (end 78.645372 117.6825) (width 0.109) (layer "In6.Cu") (net 218))
  (segment (start 80.609295 119.42608) (end 80.552975 119.4824) (width 0.109) (layer "In6.Cu") (net 218))
  (segment (start 78.672097 120.606122) (end 78.657503 120.629349) (width 0.109) (layer "In6.Cu") (net 218))
  (segment (start 78.691494 119.778274) (end 78.714721 119.792868) (width 0.109) (layer "In6.Cu") (net 218))
  (segment (start 80.677977 118.081539) (end 80.686894 118.160686) (width 0.109) (layer "In6.Cu") (net 218))
  (segment (start 78.767872 116.56) (end 78.740613 116.563071) (width 0.109) (layer "In6.Cu") (net 218))
  (segment (start 80.677977 117.28346) (end 80.65167 117.358639) (width 0.109) (layer "In6.Cu") (net 218))
  (segment (start 78.425 113.206018) (end 78.595225 113.376243) (width 0.109) (layer "In6.Cu") (net 218))
  (segment (start 78.672097 115.606122) (end 78.657503 115.629349) (width 0.109) (layer "In6.Cu") (net 218))
  (segment (start 80.677977 120.28346) (end 80.65167 120.358639) (width 0.109) (layer "In6.Cu") (net 218))
  (segment (start 78.691494 120.778274) (end 78.714721 120.792868) (width 0.109) (layer "In6.Cu") (net 218))
  (segment (start 80.552975 117.882599) (end 80.609295 117.938919) (width 0.109) (layer "In6.Cu") (net 218))
  (segment (start 78.767872 119.805) (end 80.331208 119.805) (width 0.109) (layer "In6.Cu") (net 218))
  (segment (start 78.714721 116.572131) (end 78.691494 116.586725) (width 0.109) (layer "In6.Cu") (net 218))
  (segment (start 79.464772 115.524775) (end 79.389593 115.551082) (width 0.109) (layer "In6.Cu") (net 218))
  (segment (start 78.714721 118.792868) (end 78.740613 118.801928) (width 0.109) (layer "In6.Cu") (net 218))
  (segment (start 80.609295 118.938919) (end 80.65167 119.00636) (width 0.109) (layer "In6.Cu") (net 218))
  (segment (start 78.691494 120.586725) (end 78.672097 120.606122) (width 0.109) (layer "In6.Cu") (net 218))
  (segment (start 80.410355 115.813917) (end 80.485534 115.840224) (width 0.109) (layer "In6.Cu") (net 218))
  (segment (start 80.677977 120.081539) (end 80.686894 120.160686) (width 0.109) (layer "In6.Cu") (net 218))
  (segment (start 80.331208 119.56) (end 78.767872 119.56) (width 0.109) (layer "In6.Cu") (net 218))
  (segment (start 80.485534 118.840224) (end 80.552975 118.882599) (width 0.109) (layer "In6.Cu") (net 218))
  (segment (start 80.552975 116.882599) (end 80.609295 116.938919) (width 0.109) (layer "In6.Cu") (net 218))
  (segment (start 80.552975 120.4824) (end 80.485534 120.524775) (width 0.109) (layer "In6.Cu") (net 218))
  (segment (start 78.740613 116.563071) (end 78.714721 116.572131) (width 0.109) (layer "In6.Cu") (net 218))
  (segment (start 78.714721 119.572131) (end 78.691494 119.586725) (width 0.109) (layer "In6.Cu") (net 218))
  (segment (start 78.691494 115.586725) (end 78.672097 115.606122) (width 0.109) (layer "In6.Cu") (net 218))
  (segment (start 80.410355 118.551082) (end 80.331208 118.56) (width 0.109) (layer "In6.Cu") (net 218))
  (segment (start 78.657503 118.73565) (end 78.672097 118.758877) (width 0.109) (layer "In6.Cu") (net 218))
  (segment (start 80.552975 118.882599) (end 80.609295 118.938919) (width 0.109) (layer "In6.Cu") (net 218))
  (segment (start 80.609295 117.42608) (end 80.552975 117.4824) (width 0.109) (layer "In6.Cu") (net 218))
  (segment (start 79.532213 115.4824) (end 79.464772 115.524775) (width 0.109) (layer "In6.Cu") (net 218))
  (segment (start 80.485534 119.840224) (end 80.552975 119.882599) (width 0.109) (layer "In6.Cu") (net 218))
  (segment (start 78.648443 117.709758) (end 78.657503 117.73565) (width 0.109) (layer "In6.Cu") (net 218))
  (segment (start 78.657503 116.629349) (end 78.648443 116.655241) (width 0.109) (layer "In6.Cu") (net 218))
  (segment (start 78.714721 116.792868) (end 78.740613 116.801928) (width 0.109) (layer "In6.Cu") (net 218))
  (segment (start 78.691494 115.778274) (end 78.714721 115.792868) (width 0.109) (layer "In6.Cu") (net 218))
  (segment (start 78.657503 115.629349) (end 78.648443 115.655241) (width 0.109) (layer "In6.Cu") (net 218))
  (segment (start 78.740613 118.801928) (end 78.767872 118.805) (width 0.109) (layer "In6.Cu") (net 218))
  (segment (start 79.588533 115.42608) (end 79.532213 115.4824) (width 0.109) (layer "In6.Cu") (net 218))
  (segment (start 80.65167 116.00636) (end 80.677977 116.081539) (width 0.109) (layer "In6.Cu") (net 218))
  (segment (start 79.310446 120.805) (end 79.389593 120.813917) (width 0.109) (layer "In6.Cu") (net 218))
  (segment (start 78.657503 120.629349) (end 78.648443 120.655241) (width 0.109) (layer "In6.Cu") (net 218))
  (segment (start 80.485534 119.524775) (end 80.410355 119.551082) (width 0.109) (layer "In6.Cu") (net 218))
  (segment (start 80.410355 118.813917) (end 80.485534 118.840224) (width 0.109) (layer "In6.Cu") (net 218))
  (segment (start 80.609295 115.938919) (end 80.65167 116.00636) (width 0.109) (layer "In6.Cu") (net 218))
  (segment (start 78.672097 116.758877) (end 78.691494 116.778274) (width 0.109) (layer "In6.Cu") (net 218))
  (segment (start 78.657503 120.73565) (end 78.672097 120.758877) (width 0.109) (layer "In6.Cu") (net 218))
  (segment (start 80.609295 117.938919) (end 80.65167 118.00636) (width 0.109) (layer "In6.Cu") (net 218))
  (segment (start 80.410355 119.551082) (end 80.331208 119.56) (width 0.109) (layer "In6.Cu") (net 218))
  (segment (start 80.552975 117.4824) (end 80.485534 117.524775) (width 0.109) (layer "In6.Cu") (net 218))
  (segment (start 80.686894 116.204313) (end 80.677977 116.28346) (width 0.109) (layer "In6.Cu") (net 218))
  (segment (start 78.714721 120.792868) (end 78.740613 120.801928) (width 0.109) (layer "In6.Cu") (net 218))
  (segment (start 78.657503 119.629349) (end 78.648443 119.655241) (width 0.109) (layer "In6.Cu") (net 218))
  (segment (start 78.714721 115.792868) (end 78.740613 115.801928) (width 0.109) (layer "In6.Cu") (net 218))
  (segment (start 78.672097 120.758877) (end 78.691494 120.778274) (width 0.109) (layer "In6.Cu") (net 218))
  (segment (start 80.410355 117.551082) (end 80.331208 117.56) (width 0.109) (layer "In6.Cu") (net 218))
  (segment (start 80.485534 116.524775) (end 80.410355 116.551082) (width 0.109) (layer "In6.Cu") (net 218))
  (segment (start 80.65167 118.00636) (end 80.677977 118.081539) (width 0.109) (layer "In6.Cu") (net 218))
  (segment (start 78.657503 118.629349) (end 78.648443 118.655241) (width 0.109) (layer "In6.Cu") (net 218))
  (segment (start 79.6675 113.757186) (end 79.6675 115.1825) (width 0.109) (layer "In6.Cu") (net 218))
  (segment (start 80.331208 118.56) (end 78.767872 118.56) (width 0.109) (layer "In6.Cu") (net 218))
  (segment (start 78.691494 116.778274) (end 78.714721 116.792868) (width 0.109) (layer "In6.Cu") (net 218))
  (segment (start 78.740613 117.563071) (end 78.714721 117.572131) (width 0.109) (layer "In6.Cu") (net 218))
  (segment (start 78.648443 120.655241) (end 78.645372 120.6825) (width 0.109) (layer "In6.Cu") (net 218))
  (segment (start 80.686894 118.160686) (end 80.686894 118.204313) (width 0.109) (layer "In6.Cu") (net 218))
  (segment (start 80.552975 116.4824) (end 80.485534 116.524775) (width 0.109) (layer "In6.Cu") (net 218))
  (segment (start 80.410355 120.551082) (end 80.331208 120.56) (width 0.109) (layer "In6.Cu") (net 218))
  (segment (start 80.677977 116.28346) (end 80.65167 116.358639) (width 0.109) (layer "In6.Cu") (net 218))
  (segment (start 78.657503 117.629349) (end 78.648443 117.655241) (width 0.109) (layer "In6.Cu") (net 218))
  (segment (start 78.595225 113.376243) (end 79.286557 113.376243) (width 0.109) (layer "In6.Cu") (net 218))
  (segment (start 78.672097 116.606122) (end 78.657503 116.629349) (width 0.109) (layer "In6.Cu") (net 218))
  (segment (start 79.666133 115.204313) (end 79.657215 115.28346) (width 0.109) (layer "In6.Cu") (net 218))
  (segment (start 79.666133 121.160686) (end 79.666133 121.1825) (width 0.109) (layer "In6.Cu") (net 218))
  (segment (start 80.485534 118.524775) (end 80.410355 118.551082) (width 0.109) (layer "In6.Cu") (net 218))
  (segment (start 78.657503 115.73565) (end 78.672097 115.758877) (width 0.109) (layer "In6.Cu") (net 218))
  (segment (start 80.65167 120.358639) (end 80.609295 120.42608) (width 0.109) (layer "In6.Cu") (net 218))
  (segment (start 79.666133 121.1825) (end 79.6675 121.620495) (width 0.109) (layer "In6.Cu") (net 218))
  (segment (start 80.485534 117.524775) (end 80.410355 117.551082) (width 0.109) (layer "In6.Cu") (net 218))
  (segment (start 78.691494 118.778274) (end 78.714721 118.792868) (width 0.109) (layer "In6.Cu") (net 218))
  (segment (start 78.714721 119.792868) (end 78.740613 119.801928) (width 0.109) (layer "In6.Cu") (net 218))
  (segment (start 80.331208 118.805) (end 80.410355 118.813917) (width 0.109) (layer "In6.Cu") (net 218))
  (segment (start 78.740613 118.563071) (end 78.714721 118.572131) (width 0.109) (layer "In6.Cu") (net 218))
  (segment (start 80.677977 116.081539) (end 80.686894 116.160686) (width 0.109) (layer "In6.Cu") (net 218))
  (segment (start 78.672097 115.758877) (end 78.691494 115.778274) (width 0.109) (layer "In6.Cu") (net 218))
  (segment (start 78.740613 115.801928) (end 78.767872 115.805) (width 0.109) (layer "In6.Cu") (net 218))
  (segment (start 78.740613 119.801928) (end 78.767872 119.805) (width 0.109) (layer "In6.Cu") (net 218))
  (segment (start 80.686894 116.160686) (end 80.686894 116.204313) (width 0.109) (layer "In6.Cu") (net 218))
  (segment (start 80.609295 116.938919) (end 80.65167 117.00636) (width 0.109) (layer "In6.Cu") (net 218))
  (segment (start 79.6675 115.1825) (end 79.666133 115.1825) (width 0.109) (layer "In6.Cu") (net 218))
  (segment (start 92.45 134.31275) (end 92.00375 134.759) (width 0.109) (layer "In6.Cu") (net 218))
  (segment (start 80.485534 115.840224) (end 80.552975 115.882599) (width 0.109) (layer "In6.Cu") (net 218))
  (segment (start 80.485534 117.840224) (end 80.552975 117.882599) (width 0.109) (layer "In6.Cu") (net 218))
  (segment (start 78.672097 118.758877) (end 78.691494 118.778274) (width 0.109) (layer "In6.Cu") (net 218))
  (segment (start 80.65167 116.358639) (end 80.609295 116.42608) (width 0.109) (layer "In6.Cu") (net 218))
  (segment (start 78.648443 119.709758) (end 78.657503 119.73565) (width 0.109) (layer "In6.Cu") (net 218))
  (segment (start 78.645372 117.6825) (end 78.648443 117.709758) (width 0.109) (layer "In6.Cu") (net 218))
  (segment (start 78.740613 119.563071) (end 78.714721 119.572131) (width 0.109) (layer "In6.Cu") (net 218))
  (segment (start 78.648443 116.709758) (end 78.657503 116.73565) (width 0.109) (layer "In6.Cu") (net 218))
  (segment (start 79.310446 115.56) (end 78.767872 115.56) (width 0.109) (layer "In6.Cu") (net 218))
  (segment (start 79.630908 115.358639) (end 79.588533 115.42608) (width 0.109) (layer "In6.Cu") (net 218))
  (segment (start 79.389593 115.551082) (end 79.310446 115.56) (width 0.109) (layer "In6.Cu") (net 218))
  (segment (start 80.65167 117.358639) (end 80.609295 117.42608) (width 0.109) (layer "In6.Cu") (net 218))
  (segment (start 88.2075 130.907188) (end 88.2075 132.387186) (width 0.109) (layer "In6.Cu") (net 218))
  (segment (start 79.464772 120.840224) (end 79.532213 120.882599) (width 0.109) (layer "In6.Cu") (net 218))
  (segment (start 80.677977 119.081539) (end 80.686894 119.160686) (width 0.109) (layer "In6.Cu") (net 218))
  (segment (start 78.767872 115.56) (end 78.740613 115.563071) (width 0.109) (layer "In6.Cu") (net 218))
  (segment (start 80.331208 116.56) (end 78.767872 116.56) (width 0.109) (layer "In6.Cu") (net 218))
  (segment (start 92.241026 133.3725) (end 92.45 133.581474) (width 0.109) (layer "In6.Cu") (net 218))
  (segment (start 88.2075 132.387186) (end 89.192814 133.3725) (width 0.109) (layer "In6.Cu") (net 218))
  (segment (start 78.672097 117.606122) (end 78.657503 117.629349) (width 0.109) (layer "In6.Cu") (net 218))
  (segment (start 80.410355 116.551082) (end 80.331208 116.56) (width 0.109) (layer "In6.Cu") (net 218))
  (segment (start 78.691494 117.586725) (end 78.672097 117.606122) (width 0.109) (layer "In6.Cu") (net 218))
  (segment (start 78.648443 118.709758) (end 78.657503 118.73565) (width 0.109) (layer "In6.Cu") (net 218))
  (segment (start 78.648443 120.709758) (end 78.657503 120.73565) (width 0.109) (layer "In6.Cu") (net 218))
  (segment (start 78.672097 119.758877) (end 78.691494 119.778274) (width 0.109) (layer "In6.Cu") (net 218))
  (segment (start 80.65167 120.00636) (end 80.677977 120.081539) (width 0.109) (layer "In6.Cu") (net 218))
  (segment (start 79.588533 120.938919) (end 79.630908 121.00636) (width 0.109) (layer "In6.Cu") (net 218))
  (segment (start 78.645372 115.6825) (end 78.648443 115.709758) (width 0.109) (layer "In6.Cu") (net 218))
  (segment (start 80.552975 118.4824) (end 80.485534 118.524775) (width 0.109) (layer "In6.Cu") (net 218))
  (segment (start 79.389593 120.813917) (end 79.464772 120.840224) (width 0.109) (layer "In6.Cu") (net 218))
  (segment (start 80.331208 120.56) (end 78.767872 120.56) (width 0.109) (layer "In6.Cu") (net 218))
  (segment (start 79.6675 121.620495) (end 79.6675 122.367187) (width 0.109) (layer "In6.Cu") (net 218))
  (segment (start 78.648443 118.655241) (end 78.645372 118.6825) (width 0.109) (layer "In6.Cu") (net 218))
  (segment (start 80.686894 118.204313) (end 80.677977 118.28346) (width 0.109) (layer "In6.Cu") (net 218))
  (segment (start 78.672097 118.606122) (end 78.657503 118.629349) (width 0.109) (layer "In6.Cu") (net 218))
  (segment (start 80.485534 116.840224) (end 80.552975 116.882599) (width 0.109) (layer "In6.Cu") (net 218))
  (segment (start 80.485534 120.524775) (end 80.410355 120.551082) (width 0.109) (layer "In6.Cu") (net 218))
  (segment (start 78.648443 119.655241) (end 78.645372 119.6825) (width 0.109) (layer "In6.Cu") (net 218))
  (segment (start 80.331208 117.805) (end 80.410355 117.813917) (width 0.109) (layer "In6.Cu") (net 218))
  (segment (start 80.686894 117.204313) (end 80.677977 117.28346) (width 0.109) (layer "In6.Cu") (net 218))
  (segment (start 78.767872 117.805) (end 80.331208 117.805) (width 0.109) (layer "In6.Cu") (net 218))
  (segment (start 78.657503 117.73565) (end 78.672097 117.758877) (width 0.109) (layer "In6.Cu") (net 218))
  (segment (start 78.767872 115.805) (end 80.331208 115.805) (width 0.109) (layer "In6.Cu") (net 218))
  (segment (start 78.767872 117.56) (end 78.740613 117.563071) (width 0.109) (layer "In6.Cu") (net 218))
  (segment (start 80.552975 115.882599) (end 80.609295 115.938919) (width 0.109) (layer "In6.Cu") (net 218))
  (segment (start 80.686894 119.204313) (end 80.677977 119.28346) (width 0.109) (layer "In6.Cu") (net 218))
  (segment (start 80.677977 119.28346) (end 80.65167 119.358639) (width 0.109) (layer "In6.Cu") (net 218))
  (segment (start 78.714721 120.572131) (end 78.691494 120.586725) (width 0.109) (layer "In6.Cu") (net 218))
  (segment (start 80.410355 117.813917) (end 80.485534 117.840224) (width 0.109) (layer "In6.Cu") (net 218))
  (segment (start 80.686894 119.160686) (end 80.686894 119.204313) (width 0.109) (layer "In6.Cu") (net 218))
  (segment (start 78.691494 116.586725) (end 78.672097 116.606122) (width 0.109) (layer "In6.Cu") (net 218))
  (segment (start 78.767872 119.56) (end 78.740613 119.563071) (width 0.109) (layer "In6.Cu") (net 218))
  (segment (start 78.648443 116.655241) (end 78.645372 116.6825) (width 0.109) (layer "In6.Cu") (net 218))
  (segment (start 79.532213 120.882599) (end 79.588533 120.938919) (width 0.109) (layer "In6.Cu") (net 218))
  (segment (start 79.666133 115.1825) (end 79.666133 115.204313) (width 0.109) (layer "In6.Cu") (net 218))
  (segment (start 80.65167 117.00636) (end 80.677977 117.081539) (width 0.109) (layer "In6.Cu") (net 218))
  (segment (start 78.657503 119.73565) (end 78.672097 119.758877) (width 0.109) (layer "In6.Cu") (net 218))
  (segment (start 80.331208 119.805) (end 80.410355 119.813917) (width 0.109) (layer "In6.Cu") (net 218))
  (segment (start 78.767872 120.805) (end 79.310446 120.805) (width 0.109) (layer "In6.Cu") (net 218))
  (segment (start 78.672097 119.606122) (end 78.657503 119.629349) (width 0.109) (layer "In6.Cu") (net 218))
  (segment (start 80.410355 119.813917) (end 80.485534 119.840224) (width 0.109) (layer "In6.Cu") (net 218))
  (segment (start 78.740613 120.563071) (end 78.714721 120.572131) (width 0.109) (layer "In6.Cu") (net 218))
  (segment (start 78.691494 117.778274) (end 78.714721 117.792868) (width 0.109) (layer "In6.Cu") (net 218))
  (segment (start 80.65167 119.00636) (end 80.677977 119.081539) (width 0.109) (layer "In6.Cu") (net 218))
  (segment (start 78.714721 117.572131) (end 78.691494 117.586725) (width 0.109) (layer "In6.Cu") (net 218))
  (segment (start 78.714721 117.792868) (end 78.740613 117.801928) (width 0.109) (layer "In6.Cu") (net 218))
  (segment (start 92.00375 134.759) (end 91.9815 134.759) (width 0.109) (layer "In6.Cu") (net 218))
  (segment (start 80.410355 116.813917) (end 80.485534 116.840224) (width 0.109) (layer "In6.Cu") (net 218))
  (segment (start 80.999999 113.75) (end 81.9 113.75) (width 0.182) (layer "B.Cu") (net 218))
  (segment (start 80.503288 113.811) (end 80.938999 113.811) (width 0.182) (layer "B.Cu") (net 218))
  (segment (start 80.007031 113.314743) (end 80.503288 113.811) (width 0.182) (layer "B.Cu") (net 218))
  (segment (start 78.533725 113.314743) (end 80.007031 113.314743) (width 0.182) (layer "B.Cu") (net 218))
  (segment (start 80.938999 113.811) (end 80.999999 113.75) (width 0.182) (layer "B.Cu") (net 218))
  (segment (start 78.425 113.206018) (end 78.533725 113.314743) (width 0.182) (layer "B.Cu") (net 218))
  (segment (start 91.9815 134.124) (end 92.3665 133.814) (width 0.182) (layer "F.Cu") (net 219))
  (via (at 78.425 113.801468) (size 0.45) (drill 0.1) (layers "F.Cu" "B.Cu") (net 219))
  (via (at 91.9815 134.124) (size 0.45) (drill 0.1) (layers "F.Cu" "B.Cu") (net 219))
  (segment (start 78.591732 118.340224) (end 78.524291 118.382599) (width 0.109) (layer "In6.Cu") (net 219))
  (segment (start 80.405169 117.106122) (end 80.419763 117.129349) (width 0.109) (layer "In6.Cu") (net 219))
  (segment (start 78.591732 115.340224) (end 78.524291 115.382599) (width 0.109) (layer "In6.Cu") (net 219))
  (segment (start 79.401705 114.409793) (end 79.388719 114.43046) (width 0.109) (layer "In6.Cu") (net 219))
  (segment (start 78.746058 118.06) (end 80.309394 118.06) (width 0.109) (layer "In6.Cu") (net 219))
  (segment (start 89.849754 133.886176) (end 89.872793 133.878114) (width 0.109) (layer "In6.Cu") (net 219))
  (segment (start 79.37146 114.71328) (end 79.388719 114.730539) (width 0.109) (layer "In6.Cu") (net 219))
  (segment (start 80.336653 120.301928) (end 80.309394 120.305) (width 0.109) (layer "In6.Cu") (net 219))
  (segment (start 80.309394 119.06) (end 80.336653 119.063071) (width 0.109) (layer "In6.Cu") (net 219))
  (segment (start 78.666911 118.051082) (end 78.746058 118.06) (width 0.109) (layer "In6.Cu") (net 219))
  (segment (start 80.431894 116.1825) (end 80.428823 116.209758) (width 0.109) (layer "In6.Cu") (net 219))
  (segment (start 78.666911 118.313917) (end 78.591732 118.340224) (width 0.109) (layer "In6.Cu") (net 219))
  (segment (start 89.95828 133.668539) (end 89.975539 133.65128) (width 0.109) (layer "In6.Cu") (net 219))
  (segment (start 78.390372 115.704313) (end 78.399289 115.78346) (width 0.109) (layer "In6.Cu") (net 219))
  (segment (start 89.692719 133.668539) (end 89.705705 133.689206) (width 0.109) (layer "In6.Cu") (net 219))
  (segment (start 90.836793 133.916706) (end 90.85746 133.90372) (width 0.109) (layer "In6.Cu") (net 219))
  (segment (start 80.419763 116.129349) (end 80.428823 116.155241) (width 0.109) (layer "In6.Cu") (net 219))
  (segment (start 78.524291 119.382599) (end 78.467971 119.438919) (width 0.109) (layer "In6.Cu") (net 219))
  (segment (start 80.362545 118.292868) (end 80.336653 118.301928) (width 0.109) (layer "In6.Cu") (net 219))
  (segment (start 80.362545 117.292868) (end 80.336653 117.301928) (width 0.109) (layer "In6.Cu") (net 219))
  (segment (start 87.9525 131.012813) (end 87.9525 132.492814) (width 0.109) (layer "In6.Cu") (net 219))
  (segment (start 78.467971 115.438919) (end 78.425596 115.50636) (width 0.109) (layer "In6.Cu") (net 219))
  (segment (start 79.327754 114.468767) (end 79.3035 114.4715) (width 0.109) (layer "In6.Cu") (net 219))
  (segment (start 79.388719 114.43046) (end 79.37146 114.447719) (width 0.109) (layer "In6.Cu") (net 219))
  (segment (start 80.362545 119.072131) (end 80.385772 119.086725) (width 0.109) (layer "In6.Cu") (net 219))
  (segment (start 80.362545 119.292868) (end 80.336653 119.301928) (width 0.109) (layer "In6.Cu") (net 219))
  (segment (start 90.909294 133.689207) (end 90.92228 133.66854) (width 0.109) (layer "In6.Cu") (net 219))
  (segment (start 78.467971 119.438919) (end 78.425596 119.50636) (width 0.109) (layer "In6.Cu") (net 219))
  (segment (start 89.996206 133.638294) (end 90.019245 133.630232) (width 0.109) (layer "In6.Cu") (net 219))
  (segment (start 78.591732 119.340224) (end 78.524291 119.382599) (width 0.109) (layer "In6.Cu") (net 219))
  (segment (start 78.524291 117.9824) (end 78.591732 118.024775) (width 0.109) (layer "In6.Cu") (net 219))
  (segment (start 80.419763 119.23565) (end 80.405169 119.258877) (width 0.109) (layer "In6.Cu") (net 219))
  (segment (start 79.409767 121.620495) (end 79.409767 121.729767) (width 0.109) (layer "In6.Cu") (net 219))
  (segment (start 89.975539 133.65128) (end 89.996206 133.638294) (width 0.109) (layer "In6.Cu") (net 219))
  (segment (start 78.666911 120.313917) (end 78.591732 120.340224) (width 0.109) (layer "In6.Cu") (net 219))
  (segment (start 89.705705 133.689206) (end 89.713767 133.712245) (width 0.109) (layer "In6.Cu") (net 219))
  (segment (start 78.746058 120.06) (end 80.309394 120.06) (width 0.109) (layer "In6.Cu") (net 219))
  (segment (start 78.467971 117.438919) (end 78.425596 117.50636) (width 0.109) (layer "In6.Cu") (net 219))
  (segment (start 89.6075 133.6275) (end 89.631754 133.630232) (width 0.109) (layer "In6.Cu") (net 219))
  (segment (start 78.666911 116.313917) (end 78.591732 116.340224) (width 0.109) (layer "In6.Cu") (net 219))
  (segment (start 79.116309 114.533206) (end 79.108247 114.556245) (width 0.109) (layer "In6.Cu") (net 219))
  (segment (start 78.591732 117.340224) (end 78.524291 117.382599) (width 0.109) (layer "In6.Cu") (net 219))
  (segment (start 89.9345 133.7365) (end 89.937232 133.712245) (width 0.109) (layer "In6.Cu") (net 219))
  (segment (start 80.336653 116.301928) (end 80.309394 116.305) (width 0.109) (layer "In6.Cu") (net 219))
  (segment (start 80.405169 120.258877) (end 80.385772 120.278274) (width 0.109) (layer "In6.Cu") (net 219))
  (segment (start 80.385772 117.086725) (end 80.405169 117.106122) (width 0.109) (layer "In6.Cu") (net 219))
  (segment (start 89.654793 133.638294) (end 89.67546 133.65128) (width 0.109) (layer "In6.Cu") (net 219))
  (segment (start 78.425596 117.50636) (end 78.399289 117.581539) (width 0.109) (layer "In6.Cu") (net 219))
  (segment (start 78.425596 119.50636) (end 78.399289 119.581539) (width 0.109) (layer "In6.Cu") (net 219))
  (segment (start 79.108247 114.556245) (end 79.105515 114.5805) (width 0.109) (layer "In6.Cu") (net 219))
  (segment (start 79.4125 114.3625) (end 79.409767 114.386754) (width 0.109) (layer "In6.Cu") (net 219))
  (segment (start 80.336653 116.063071) (end 80.362545 116.072131) (width 0.109) (layer "In6.Cu") (net 219))
  (segment (start 79.315891 121.063071) (end 79.341783 121.072131) (width 0.109) (layer "In6.Cu") (net 219))
  (segment (start 78.524291 119.9824) (end 78.591732 120.024775) (width 0.109) (layer "In6.Cu") (net 219))
  (segment (start 78.390372 118.704313) (end 78.399289 118.78346) (width 0.109) (layer "In6.Cu") (net 219))
  (segment (start 80.385772 117.278274) (end 80.362545 117.292868) (width 0.109) (layer "In6.Cu") (net 219))
  (segment (start 79.327754 114.692232) (end 79.350793 114.700294) (width 0.109) (layer "In6.Cu") (net 219))
  (segment (start 79.108247 114.604754) (end 79.116309 114.627793) (width 0.109) (layer "In6.Cu") (net 219))
  (segment (start 78.390372 118.660686) (end 78.390372 118.704313) (width 0.109) (layer "In6.Cu") (net 219))
  (segment (start 89.713767 133.712245) (end 89.7165 133.7365) (width 0.109) (layer "In6.Cu") (net 219))
  (segment (start 80.385772 120.278274) (end 80.362545 120.292868) (width 0.109) (layer "In6.Cu") (net 219))
  (segment (start 79.167221 114.678705) (end 79.19026 114.686767) (width 0.109) (layer "In6.Cu") (net 219))
  (segment (start 78.666911 116.051082) (end 78.746058 116.06) (width 0.109) (layer "In6.Cu") (net 219))
  (segment (start 90.618793 133.638295) (end 90.63946 133.651281) (width 0.109) (layer "In6.Cu") (net 219))
  (segment (start 80.385772 118.278274) (end 80.362545 118.292868) (width 0.109) (layer "In6.Cu") (net 219))
  (segment (start 80.309394 118.305) (end 78.746058 118.305) (width 0.109) (layer "In6.Cu") (net 219))
  (segment (start 80.309394 118.06) (end 80.336653 118.063071) (width 0.109) (layer "In6.Cu") (net 219))
  (segment (start 90.813754 133.924768) (end 90.836793 133.916706) (width 0.109) (layer "In6.Cu") (net 219))
  (segment (start 79.384407 121.106122) (end 79.399001 121.129349) (width 0.109) (layer "In6.Cu") (net 219))
  (segment (start 90.656719 133.66854) (end 90.669705 133.689207) (width 0.109) (layer "In6.Cu") (net 219))
  (segment (start 80.405169 116.258877) (end 80.385772 116.278274) (width 0.109) (layer "In6.Cu") (net 219))
  (segment (start 90.92228 133.66854) (end 90.939539 133.651281) (width 0.109) (layer "In6.Cu") (net 219))
  (segment (start 78.524291 117.382599) (end 78.467971 117.438919) (width 0.109) (layer "In6.Cu") (net 219))
  (segment (start 78.746058 116.305) (end 78.666911 116.313917) (width 0.109) (layer "In6.Cu") (net 219))
  (segment (start 78.591732 119.024775) (end 78.666911 119.051082) (width 0.109) (layer "In6.Cu") (net 219))
  (segment (start 80.309394 116.06) (end 80.336653 116.063071) (width 0.109) (layer "In6.Cu") (net 219))
  (segment (start 90.5715 133.6275) (end 90.595754 133.630233) (width 0.109) (layer "In6.Cu") (net 219))
  (segment (start 78.666911 120.051082) (end 78.746058 120.06) (width 0.109) (layer "In6.Cu") (net 219))
  (segment (start 79.384407 115.258877) (end 79.36501 115.278274) (width 0.109) (layer "In6.Cu") (net 219))
  (segment (start 90.960206 133.638295) (end 90.983245 133.630233) (width 0.109) (layer "In6.Cu") (net 219))
  (segment (start 78.425596 119.858639) (end 78.467971 119.92608) (width 0.109) (layer "In6.Cu") (net 219))
  (segment (start 78.399289 120.78346) (end 78.425596 120.858639) (width 0.109) (layer "In6.Cu") (net 219))
  (segment (start 78.467971 116.92608) (end 78.524291 116.9824) (width 0.109) (layer "In6.Cu") (net 219))
  (segment (start 89.67546 133.65128) (end 89.692719 133.668539) (width 0.109) (layer "In6.Cu") (net 219))
  (segment (start 80.336653 118.063071) (end 80.362545 118.072131) (width 0.109) (layer "In6.Cu") (net 219))
  (segment (start 78.746058 117.06) (end 80.309394 117.06) (width 0.109) (layer "In6.Cu") (net 219))
  (segment (start 79.19026 114.686767) (end 79.214515 114.6895) (width 0.109) (layer "In6.Cu") (net 219))
  (segment (start 80.336653 119.301928) (end 80.309394 119.305) (width 0.109) (layer "In6.Cu") (net 219))
  (segment (start 80.419763 119.129349) (end 80.428823 119.155241) (width 0.109) (layer "In6.Cu") (net 219))
  (segment (start 78.591732 117.024775) (end 78.666911 117.051082) (width 0.109) (layer "In6.Cu") (net 219))
  (segment (start 90.019245 133.630232) (end 90.0435 133.6275) (width 0.109) (layer "In6.Cu") (net 219))
  (segment (start 78.467971 118.438919) (end 78.425596 118.50636) (width 0.109) (layer "In6.Cu") (net 219))
  (segment (start 89.757539 133.865128) (end 89.778206 133.878114) (width 0.109) (layer "In6.Cu") (net 219))
  (segment (start 79.4125 122.472812) (end 87.9525 131.012813) (width 0.109) (layer "In6.Cu") (net 219))
  (segment (start 80.405169 119.258877) (end 80.385772 119.278274) (width 0.109) (layer "In6.Cu") (net 219))
  (segment (start 78.467971 115.92608) (end 78.524291 115.9824) (width 0.109) (layer "In6.Cu") (net 219))
  (segment (start 78.425596 120.858639) (end 78.467971 120.92608) (width 0.109) (layer "In6.Cu") (net 219))
  (segment (start 78.524291 116.382599) (end 78.467971 116.438919) (width 0.109) (layer "In6.Cu") (net 219))
  (segment (start 78.467971 117.92608) (end 78.524291 117.9824) (width 0.109) (layer "In6.Cu") (net 219))
  (segment (start 80.336653 120.063071) (end 80.362545 120.072131) (width 0.109) (layer "In6.Cu") (net 219))
  (segment (start 89.631754 133.630232) (end 89.654793 133.638294) (width 0.109) (layer "In6.Cu") (net 219))
  (segment (start 87.9525 132.492814) (end 89.087186 133.6275) (width 0.109) (layer "In6.Cu") (net 219))
  (segment (start 79.129295 114.64846) (end 79.146554 114.665719) (width 0.109) (layer "In6.Cu") (net 219))
  (segment (start 78.746058 115.305) (end 78.666911 115.313917) (width 0.109) (layer "In6.Cu") (net 219))
  (segment (start 90.765245 133.924768) (end 90.7895 133.9275) (width 0.109) (layer "In6.Cu") (net 219))
  (segment (start 79.388719 114.730539) (end 79.401705 114.751206) (width 0.109) (layer "In6.Cu") (net 219))
  (segment (start 90.742206 133.916706) (end 90.765245 133.924768) (width 0.109) (layer "In6.Cu") (net 219))
  (segment (start 80.405169 119.106122) (end 80.419763 119.129349) (width 0.109) (layer "In6.Cu") (net 219))
  (segment (start 80.362545 116.072131) (end 80.385772 116.086725) (width 0.109) (layer "In6.Cu") (net 219))
  (segment (start 90.595754 133.630233) (end 90.618793 133.638295) (width 0.109) (layer "In6.Cu") (net 219))
  (segment (start 89.719232 133.804163) (end 89.727294 133.827202) (width 0.109) (layer "In6.Cu") (net 219))
  (segment (start 78.591732 120.340224) (end 78.524291 120.382599) (width 0.109) (layer "In6.Cu") (net 219))
  (segment (start 78.524291 115.9824) (end 78.591732 116.024775) (width 0.109) (layer "In6.Cu") (net 219))
  (segment (start 78.399289 115.78346) (end 78.425596 115.858639) (width 0.109) (layer "In6.Cu") (net 219))
  (segment (start 80.419763 116.23565) (end 80.405169 116.258877) (width 0.109) (layer "In6.Cu") (net 219))
  (segment (start 78.591732 116.024775) (end 78.666911 116.051082) (width 0.109) (layer "In6.Cu") (net 219))
  (segment (start 80.362545 120.072131) (end 80.385772 120.086725) (width 0.109) (layer "In6.Cu") (net 219))
  (segment (start 78.666911 119.051082) (end 78.746058 119.06) (width 0.109) (layer "In6.Cu") (net 219))
  (segment (start 90.0435 133.6275) (end 90.5715 133.6275) (width 0.109) (layer "In6.Cu") (net 219))
  (segment (start 78.399289 117.581539) (end 78.390372 117.660686) (width 0.109) (layer "In6.Cu") (net 219))
  (segment (start 89.778206 133.878114) (end 89.801245 133.886176) (width 0.109) (layer "In6.Cu") (net 219))
  (segment (start 78.390372 120.704313) (end 78.399289 120.78346) (width 0.109) (layer "In6.Cu") (net 219))
  (segment (start 78.425 113.801468) (end 78.595225 113.631243) (width 0.109) (layer "In6.Cu") (net 219))
  (segment (start 79.4125 121.7325) (end 79.4125 122.472812) (width 0.109) (layer "In6.Cu") (net 219))
  (segment (start 78.425596 120.50636) (end 78.399289 120.581539) (width 0.109) (layer "In6.Cu") (net 219))
  (segment (start 90.8985 133.8185) (end 90.8985 133.7365) (width 0.109) (layer "In6.Cu") (net 219))
  (segment (start 90.8985 133.7365) (end 90.901232 133.712246) (width 0.109) (layer "In6.Cu") (net 219))
  (segment (start 90.691294 133.865794) (end 90.70428 133.886461) (width 0.109) (layer "In6.Cu") (net 219))
  (segment (start 79.411133 121.1825) (end 79.409767 121.620495) (width 0.109) (layer "In6.Cu") (net 219))
  (segment (start 80.431894 119.1825) (end 80.428823 119.209758) (width 0.109) (layer "In6.Cu") (net 219))
  (segment (start 89.727294 133.827202) (end 89.74028 133.847869) (width 0.109) (layer "In6.Cu") (net 219))
  (segment (start 79.3035 114.6895) (end 79.327754 114.692232) (width 0.109) (layer "In6.Cu") (net 219))
  (segment (start 78.467971 120.438919) (end 78.425596 120.50636) (width 0.109) (layer "In6.Cu") (net 219))
  (segment (start 78.399289 120.581539) (end 78.390372 120.660686) (width 0.109) (layer "In6.Cu") (net 219))
  (segment (start 80.428823 119.209758) (end 80.419763 119.23565) (width 0.109) (layer "In6.Cu") (net 219))
  (segment (start 80.309394 117.305) (end 78.746058 117.305) (width 0.109) (layer "In6.Cu") (net 219))
  (segment (start 89.945294 133.689206) (end 89.95828 133.668539) (width 0.109) (layer "In6.Cu") (net 219))
  (segment (start 80.419763 118.129349) (end 80.428823 118.155241) (width 0.109) (layer "In6.Cu") (net 219))
  (segment (start 92.2 133.9055) (end 91.9815 134.124) (width 0.109) (layer "In6.Cu") (net 219))
  (segment (start 90.887705 133.865794) (end 90.895767 133.842755) (width 0.109) (layer "In6.Cu") (net 219))
  (segment (start 90.939539 133.651281) (end 90.960206 133.638295) (width 0.109) (layer "In6.Cu") (net 219))
  (segment (start 78.666911 115.313917) (end 78.591732 115.340224) (width 0.109) (layer "In6.Cu") (net 219))
  (segment (start 79.105515 114.5805) (end 79.108247 114.604754) (width 0.109) (layer "In6.Cu") (net 219))
  (segment (start 80.428823 120.209758) (end 80.419763 120.23565) (width 0.109) (layer "In6.Cu") (net 219))
  (segment (start 78.524291 120.382599) (end 78.467971 120.438919) (width 0.109) (layer "In6.Cu") (net 219))
  (segment (start 80.405169 118.106122) (end 80.419763 118.129349) (width 0.109) (layer "In6.Cu") (net 219))
  (segment (start 90.983245 133.630233) (end 91.0075 133.6275) (width 0.109) (layer "In6.Cu") (net 219))
  (segment (start 78.746058 119.06) (end 80.309394 119.06) (width 0.109) (layer "In6.Cu") (net 219))
  (segment (start 89.923705 133.827202) (end 89.931767 133.804163) (width 0.109) (layer "In6.Cu") (net 219))
  (segment (start 78.390372 119.660686) (end 78.390372 119.704313) (width 0.109) (layer "In6.Cu") (net 219))
  (segment (start 78.390372 117.660686) (end 78.390372 117.704313) (width 0.109) (layer "In6.Cu") (net 219))
  (segment (start 79.399001 121.129349) (end 79.408061 121.155241) (width 0.109) (layer "In6.Cu") (net 219))
  (segment (start 79.116309 114.627793) (end 79.129295 114.64846) (width 0.109) (layer "In6.Cu") (net 219))
  (segment (start 78.591732 118.024775) (end 78.666911 118.051082) (width 0.109) (layer "In6.Cu") (net 219))
  (segment (start 80.405169 117.258877) (end 80.385772 117.278274) (width 0.109) (layer "In6.Cu") (net 219))
  (segment (start 80.309394 120.305) (end 78.746058 120.305) (width 0.109) (layer "In6.Cu") (net 219))
  (segment (start 78.666911 117.313917) (end 78.591732 117.340224) (width 0.109) (layer "In6.Cu") (net 219))
  (segment (start 89.937232 133.712245) (end 89.945294 133.689206) (width 0.109) (layer "In6.Cu") (net 219))
  (segment (start 78.390372 119.704313) (end 78.399289 119.78346) (width 0.109) (layer "In6.Cu") (net 219))
  (segment (start 89.89346 133.865128) (end 89.910719 133.847869) (width 0.109) (layer "In6.Cu") (net 219))
  (segment (start 78.390372 117.704313) (end 78.399289 117.78346) (width 0.109) (layer "In6.Cu") (net 219))
  (segment (start 78.746058 121.06) (end 79.288633 121.06) (width 0.109) (layer "In6.Cu") (net 219))
  (segment (start 78.467971 118.92608) (end 78.524291 118.9824) (width 0.109) (layer "In6.Cu") (net 219))
  (segment (start 79.341783 121.072131) (end 79.36501 121.086725) (width 0.109) (layer "In6.Cu") (net 219))
  (segment (start 80.419763 120.129349) (end 80.428823 120.155241) (width 0.109) (layer "In6.Cu") (net 219))
  (segment (start 80.385772 116.278274) (end 80.362545 116.292868) (width 0.109) (layer "In6.Cu") (net 219))
  (segment (start 80.405169 120.106122) (end 80.419763 120.129349) (width 0.109) (layer "In6.Cu") (net 219))
  (segment (start 79.36501 115.278274) (end 79.341783 115.292868) (width 0.109) (layer "In6.Cu") (net 219))
  (segment (start 80.431894 117.1825) (end 80.428823 117.209758) (width 0.109) (layer "In6.Cu") (net 219))
  (segment (start 78.467971 116.438919) (end 78.425596 116.50636) (width 0.109) (layer "In6.Cu") (net 219))
  (segment (start 78.390372 116.660686) (end 78.390372 116.704313) (width 0.109) (layer "In6.Cu") (net 219))
  (segment (start 79.409767 114.774245) (end 79.409767 115.1825) (width 0.109) (layer "In6.Cu") (net 219))
  (segment (start 90.6805 133.8185) (end 90.683232 133.842755) (width 0.109) (layer "In6.Cu") (net 219))
  (segment (start 80.428823 119.155241) (end 80.431894 119.1825) (width 0.109) (layer "In6.Cu") (net 219))
  (segment (start 78.399289 119.78346) (end 78.425596 119.858639) (width 0.109) (layer "In6.Cu") (net 219))
  (segment (start 79.350793 114.700294) (end 79.37146 114.71328) (width 0.109) (layer "In6.Cu") (net 219))
  (segment (start 80.419763 118.23565) (end 80.405169 118.258877) (width 0.109) (layer "In6.Cu") (net 219))
  (segment (start 80.362545 118.072131) (end 80.385772 118.086725) (width 0.109) (layer "In6.Cu") (net 219))
  (segment (start 90.669705 133.689207) (end 90.677767 133.712246) (width 0.109) (layer "In6.Cu") (net 219))
  (segment (start 80.362545 116.292868) (end 80.336653 116.301928) (width 0.109) (layer "In6.Cu") (net 219))
  (segment (start 90.874719 133.886461) (end 90.887705 133.865794) (width 0.109) (layer "In6.Cu") (net 219))
  (segment (start 78.425596 116.858639) (end 78.467971 116.92608) (width 0.109) (layer "In6.Cu") (net 219))
  (segment (start 78.399289 116.78346) (end 78.425596 116.858639) (width 0.109) (layer "In6.Cu") (net 219))
  (segment (start 78.399289 115.581539) (end 78.390372 115.660686) (width 0.109) (layer "In6.Cu") (net 219))
  (segment (start 80.428823 118.155241) (end 80.431894 118.1825) (width 0.109) (layer "In6.Cu") (net 219))
  (segment (start 80.336653 117.063071) (end 80.362545 117.072131) (width 0.109) (layer "In6.Cu") (net 219))
  (segment (start 78.425596 115.858639) (end 78.467971 115.92608) (width 0.109) (layer "In6.Cu") (net 219))
  (segment (start 78.666911 121.051082) (end 78.746058 121.06) (width 0.109) (layer "In6.Cu") (net 219))
  (segment (start 79.146554 114.665719) (end 79.167221 114.678705) (width 0.109) (layer "In6.Cu") (net 219))
  (segment (start 89.087186 133.6275) (end 89.6075 133.6275) (width 0.109) (layer "In6.Cu") (net 219))
  (segment (start 79.3035 114.4715) (end 79.214515 114.4715) (width 0.109) (layer "In6.Cu") (net 219))
  (segment (start 79.350793 114.460705) (end 79.327754 114.468767) (width 0.109) (layer "In6.Cu") (net 219))
  (segment (start 78.524291 115.382599) (end 78.467971 115.438919) (width 0.109) (layer "In6.Cu") (net 219))
  (segment (start 78.399289 116.581539) (end 78.390372 116.660686) (width 0.109) (layer "In6.Cu") (net 219))
  (segment (start 89.801245 133.886176) (end 89.8255 133.888909) (width 0.109) (layer "In6.Cu") (net 219))
  (segment (start 91.0075 133.6275) (end 92.135398 133.6275) (width 0.109) (layer "In6.Cu") (net 219))
  (segment (start 78.595225 113.631243) (end 79.180929 113.631243) (width 0.109) (layer "In6.Cu") (net 219))
  (segment (start 78.524291 118.9824) (end 78.591732 119.024775) (width 0.109) (layer "In6.Cu") (net 219))
  (segment (start 79.408061 121.155241) (end 79.411133 121.1825) (width 0.109) (layer "In6.Cu") (net 219))
  (segment (start 92.2 133.692102) (end 92.2 133.9055) (width 0.109) (layer "In6.Cu") (net 219))
  (segment (start 90.6805 133.7365) (end 90.6805 133.8185) (width 0.109) (layer "In6.Cu") (net 219))
  (segment (start 78.425596 115.50636) (end 78.399289 115.581539) (width 0.109) (layer "In6.Cu") (net 219))
  (segment (start 80.385772 118.086725) (end 80.405169 118.106122) (width 0.109) (layer "In6.Cu") (net 219))
  (segment (start 79.37146 114.447719) (end 79.350793 114.460705) (width 0.109) (layer "In6.Cu") (net 219))
  (segment (start 80.428823 116.155241) (end 80.431894 116.1825) (width 0.109) (layer "In6.Cu") (net 219))
  (segment (start 80.419763 120.23565) (end 80.405169 120.258877) (width 0.109) (layer "In6.Cu") (net 219))
  (segment (start 79.167221 114.482294) (end 79.146554 114.49528) (width 0.109) (layer "In6.Cu") (net 219))
  (segment (start 78.399289 118.581539) (end 78.390372 118.660686) (width 0.109) (layer "In6.Cu") (net 219))
  (segment (start 78.390372 115.660686) (end 78.390372 115.704313) (width 0.109) (layer "In6.Cu") (net 219))
  (segment (start 80.428823 117.155241) (end 80.431894 117.1825) (width 0.109) (layer "In6.Cu") (net 219))
  (segment (start 80.428823 120.155241) (end 80.431894 120.1825) (width 0.109) (layer "In6.Cu") (net 219))
  (segment (start 78.399289 119.581539) (end 78.390372 119.660686) (width 0.109) (layer "In6.Cu") (net 219))
  (segment (start 80.309394 120.06) (end 80.336653 120.063071) (width 0.109) (layer "In6.Cu") (net 219))
  (segment (start 78.467971 119.92608) (end 78.524291 119.9824) (width 0.109) (layer "In6.Cu") (net 219))
  (segment (start 92.135398 133.6275) (end 92.2 133.692102) (width 0.109) (layer "In6.Cu") (net 219))
  (segment (start 79.146554 114.49528) (end 79.129295 114.512539) (width 0.109) (layer "In6.Cu") (net 219))
  (segment (start 78.666911 117.051082) (end 78.746058 117.06) (width 0.109) (layer "In6.Cu") (net 219))
  (segment (start 78.591732 116.340224) (end 78.524291 116.382599) (width 0.109) (layer "In6.Cu") (net 219))
  (segment (start 78.467971 120.92608) (end 78.524291 120.9824) (width 0.109) (layer "In6.Cu") (net 219))
  (segment (start 79.411133 115.1825) (end 79.408061 115.209758) (width 0.109) (layer "In6.Cu") (net 219))
  (segment (start 79.36501 121.086725) (end 79.384407 121.106122) (width 0.109) (layer "In6.Cu") (net 219))
  (segment (start 90.901232 133.712246) (end 90.909294 133.689207) (width 0.109) (layer "In6.Cu") (net 219))
  (segment (start 90.721539 133.90372) (end 90.742206 133.916706) (width 0.109) (layer "In6.Cu") (net 219))
  (segment (start 80.419763 117.23565) (end 80.405169 117.258877) (width 0.109) (layer "In6.Cu") (net 219))
  (segment (start 80.431894 120.1825) (end 80.428823 120.209758) (width 0.109) (layer "In6.Cu") (net 219))
  (segment (start 78.591732 121.024775) (end 78.666911 121.051082) (width 0.109) (layer "In6.Cu") (net 219))
  (segment (start 79.19026 114.474232) (end 79.167221 114.482294) (width 0.109) (layer "In6.Cu") (net 219))
  (segment (start 79.214515 114.4715) (end 79.19026 114.474232) (width 0.109) (layer "In6.Cu") (net 219))
  (segment (start 89.872793 133.878114) (end 89.89346 133.865128) (width 0.109) (layer "In6.Cu") (net 219))
  (segment (start 79.409767 121.729767) (end 79.4125 121.7325) (width 0.109) (layer "In6.Cu") (net 219))
  (segment (start 78.425596 118.50636) (end 78.399289 118.581539) (width 0.109) (layer "In6.Cu") (net 219))
  (segment (start 90.677767 133.712246) (end 90.6805 133.7365) (width 0.109) (layer "In6.Cu") (net 219))
  (segment (start 80.405169 118.258877) (end 80.385772 118.278274) (width 0.109) (layer "In6.Cu") (net 219))
  (segment (start 79.214515 114.6895) (end 79.3035 114.6895) (width 0.109) (layer "In6.Cu") (net 219))
  (segment (start 78.524291 120.9824) (end 78.591732 121.024775) (width 0.109) (layer "In6.Cu") (net 219))
  (segment (start 90.895767 133.842755) (end 90.8985 133.8185) (width 0.109) (layer "In6.Cu") (net 219))
  (segment (start 89.910719 133.847869) (end 89.923705 133.827202) (width 0.109) (layer "In6.Cu") (net 219))
  (segment (start 90.683232 133.842755) (end 90.691294 133.865794) (width 0.109) (layer "In6.Cu") (net 219))
  (segment (start 80.405169 116.106122) (end 80.419763 116.129349) (width 0.109) (layer "In6.Cu") (net 219))
  (segment (start 80.428823 116.209758) (end 80.419763 116.23565) (width 0.109) (layer "In6.Cu") (net 219))
  (segment (start 79.408061 115.209758) (end 79.399001 115.23565) (width 0.109) (layer "In6.Cu") (net 219))
  (segment (start 79.399001 115.23565) (end 79.384407 115.258877) (width 0.109) (layer "In6.Cu") (net 219))
  (segment (start 80.419763 117.129349) (end 80.428823 117.155241) (width 0.109) (layer "In6.Cu") (net 219))
  (segment (start 78.746058 117.305) (end 78.666911 117.313917) (width 0.109) (layer "In6.Cu") (net 219))
  (segment (start 80.336653 118.301928) (end 80.309394 118.305) (width 0.109) (layer "In6.Cu") (net 219))
  (segment (start 78.425596 117.858639) (end 78.467971 117.92608) (width 0.109) (layer "In6.Cu") (net 219))
  (segment (start 79.409767 115.1825) (end 79.411133 115.1825) (width 0.109) (layer "In6.Cu") (net 219))
  (segment (start 78.390372 120.660686) (end 78.390372 120.704313) (width 0.109) (layer "In6.Cu") (net 219))
  (segment (start 90.7895 133.9275) (end 90.813754 133.924768) (width 0.109) (layer "In6.Cu") (net 219))
  (segment (start 80.385772 119.086725) (end 80.405169 119.106122) (width 0.109) (layer "In6.Cu") (net 219))
  (segment (start 79.4125 113.862814) (end 79.4125 114.3625) (width 0.109) (layer "In6.Cu") (net 219))
  (segment (start 78.399289 117.78346) (end 78.425596 117.858639) (width 0.109) (layer "In6.Cu") (net 219))
  (segment (start 78.666911 119.313917) (end 78.591732 119.340224) (width 0.109) (layer "In6.Cu") (net 219))
  (segment (start 78.399289 118.78346) (end 78.425596 118.858639) (width 0.109) (layer "In6.Cu") (net 219))
  (segment (start 89.931767 133.804163) (end 89.9345 133.779909) (width 0.109) (layer "In6.Cu") (net 219))
  (segment (start 78.524291 116.9824) (end 78.591732 117.024775) (width 0.109) (layer "In6.Cu") (net 219))
  (segment (start 78.390372 116.704313) (end 78.399289 116.78346) (width 0.109) (layer "In6.Cu") (net 219))
  (segment (start 89.7165 133.779909) (end 89.719232 133.804163) (width 0.109) (layer "In6.Cu") (net 219))
  (segment (start 80.385772 120.086725) (end 80.405169 120.106122) (width 0.109) (layer "In6.Cu") (net 219))
  (segment (start 89.8255 133.888909) (end 89.849754 133.886176) (width 0.109) (layer "In6.Cu") (net 219))
  (segment (start 79.129295 114.512539) (end 79.116309 114.533206) (width 0.109) (layer "In6.Cu") (net 219))
  (segment (start 80.336653 117.301928) (end 80.309394 117.305) (width 0.109) (layer "In6.Cu") (net 219))
  (segment (start 79.315891 115.301928) (end 79.288633 115.305) (width 0.109) (layer "In6.Cu") (net 219))
  (segment (start 90.85746 133.90372) (end 90.874719 133.886461) (width 0.109) (layer "In6.Cu") (net 219))
  (segment (start 80.309394 117.06) (end 80.336653 117.063071) (width 0.109) (layer "In6.Cu") (net 219))
  (segment (start 78.524291 118.382599) (end 78.467971 118.438919) (width 0.109) (layer "In6.Cu") (net 219))
  (segment (start 79.409767 114.386754) (end 79.401705 114.409793) (width 0.109) (layer "In6.Cu") (net 219))
  (segment (start 89.7165 133.7365) (end 89.7165 133.779909) (width 0.109) (layer "In6.Cu") (net 219))
  (segment (start 90.70428 133.886461) (end 90.721539 133.90372) (width 0.109) (layer "In6.Cu") (net 219))
  (segment (start 79.288633 121.06) (end 79.315891 121.063071) (width 0.109) (layer "In6.Cu") (net 219))
  (segment (start 78.746058 118.305) (end 78.666911 118.313917) (width 0.109) (layer "In6.Cu") (net 219))
  (segment (start 80.428823 117.209758) (end 80.419763 117.23565) (width 0.109) (layer "In6.Cu") (net 219))
  (segment (start 80.385772 116.086725) (end 80.405169 116.106122) (width 0.109) (layer "In6.Cu") (net 219))
  (segment (start 80.385772 119.278274) (end 80.362545 119.292868) (width 0.109) (layer "In6.Cu") (net 219))
  (segment (start 78.425596 118.858639) (end 78.467971 118.92608) (width 0.109) (layer "In6.Cu") (net 219))
  (segment (start 78.746058 116.06) (end 80.309394 116.06) (width 0.109) (layer "In6.Cu") (net 219))
  (segment (start 79.341783 115.292868) (end 79.315891 115.301928) (width 0.109) (layer "In6.Cu") (net 219))
  (segment (start 80.431894 118.1825) (end 80.428823 118.209758) (width 0.109) (layer "In6.Cu") (net 219))
  (segment (start 80.336653 119.063071) (end 80.362545 119.072131) (width 0.109) (layer "In6.Cu") (net 219))
  (segment (start 80.428823 118.209758) (end 80.419763 118.23565) (width 0.109) (layer "In6.Cu") (net 219))
  (segment (start 80.362545 117.072131) (end 80.385772 117.086725) (width 0.109) (layer "In6.Cu") (net 219))
  (segment (start 89.74028 133.847869) (end 89.757539 133.865128) (width 0.109) (layer "In6.Cu") (net 219))
  (segment (start 80.309394 119.305) (end 78.746058 119.305) (width 0.109) (layer "In6.Cu") (net 219))
  (segment (start 79.288633 115.305) (end 78.746058 115.305) (width 0.109) (layer "In6.Cu") (net 219))
  (segment (start 80.309394 116.305) (end 78.746058 116.305) (width 0.109) (layer "In6.Cu") (net 219))
  (segment (start 78.746058 119.305) (end 78.666911 119.313917) (width 0.109) (layer "In6.Cu") (net 219))
  (segment (start 80.362545 120.292868) (end 80.336653 120.301928) (width 0.109) (layer "In6.Cu") (net 219))
  (segment (start 78.591732 120.024775) (end 78.666911 120.051082) (width 0.109) (layer "In6.Cu") (net 219))
  (segment (start 78.746058 120.305) (end 78.666911 120.313917) (width 0.109) (layer "In6.Cu") (net 219))
  (segment (start 89.9345 133.779909) (end 89.9345 133.7365) (width 0.109) (layer "In6.Cu") (net 219))
  (segment (start 78.425596 116.50636) (end 78.399289 116.581539) (width 0.109) (layer "In6.Cu") (net 219))
  (segment (start 90.63946 133.651281) (end 90.656719 133.66854) (width 0.109) (layer "In6.Cu") (net 219))
  (segment (start 79.180929 113.631243) (end 79.4125 113.862814) (width 0.109) (layer "In6.Cu") (net 219))
  (segment (start 79.401705 114.751206) (end 79.409767 114.774245) (width 0.109) (layer "In6.Cu") (net 219))
  (segment (start 78.533725 113.692743) (end 79.850455 113.692743) (width 0.182) (layer "B.Cu") (net 219))
  (segment (start 80.346712 114.189) (end 80.938999 114.189) (width 0.182) (layer "B.Cu") (net 219))
  (segment (start 78.425 113.801468) (end 78.533725 113.692743) (width 0.182) (layer "B.Cu") (net 219))
  (segment (start 80.999999 114.25) (end 81.9 114.25) (width 0.182) (layer "B.Cu") (net 219))
  (segment (start 80.938999 114.189) (end 80.999999 114.25) (width 0.182) (layer "B.Cu") (net 219))
  (segment (start 79.850455 113.692743) (end 80.346712 114.189) (width 0.182) (layer "B.Cu") (net 219))
  (segment (start 137.05 125.374999) (end 136.300001 125.374999) (width 0.182) (layer "F.Cu") (net 220))
  (segment (start 136.300001 125.374999) (end 136.115 125.56) (width 0.182) (layer "F.Cu") (net 220))
  (segment (start 136.115 125.56) (end 136.115 126.475) (width 0.182) (layer "F.Cu") (net 220))
  (segment (start 136.1 126.475) (end 135.75 126.825) (width 0.182) (layer "F.Cu") (net 220))
  (segment (start 135.75 126.825) (end 135.75 128.075001) (width 0.182) (layer "F.Cu") (net 220))
  (segment (start 136.115 126.475) (end 136.1 126.475) (width 0.182) (layer "F.Cu") (net 220))
  (segment (start 135.75 128.075) (end 135.75 128.5792) (width 0.182) (layer "F.Cu") (net 220))
  (segment (start 135.75 128.5792) (end 135.3 129.0292) (width 0.182) (layer "F.Cu") (net 220))
  (via (at 136.2 125.5) (size 0.45) (drill 0.1) (layers "F.Cu" "B.Cu") (net 220))
  (segment (start 81.245 140.53) (end 97.1 140.53) (width 0.109) (layer "In4.Cu") (net 220))
  (segment (start 132.236662 135.4) (end 135.238338 135.4) (width 0.109) (layer "In4.Cu") (net 220))
  (segment (start 110.605 131.405) (end 115.519489 136.319489) (width 0.109) (layer "In4.Cu") (net 220))
  (segment (start 98.78 132.6) (end 99.975 131.405) (width 0.109) (layer "In4.Cu") (net 220))
  (segment (start 78.8 142.975) (end 81.245 140.53) (width 0.109) (layer "In4.Cu") (net 220))
  (segment (start 99.975 131.405) (end 110.605 131.405) (width 0.109) (layer "In4.Cu") (net 220))
  (segment (start 97.1 140.53) (end 98.78 138.85) (width 0.109) (layer "In4.Cu") (net 220))
  (segment (start 135.238338 135.4) (end 136.2 134.438338) (width 0.109) (layer "In4.Cu") (net 220))
  (segment (start 136.2 134.438338) (end 136.2 125.5) (width 0.109) (layer "In4.Cu") (net 220))
  (segment (start 131.317173 136.319489) (end 132.236662 135.4) (width 0.109) (layer "In4.Cu") (net 220))
  (segment (start 115.519489 136.319489) (end 131.317173 136.319489) (width 0.109) (layer "In4.Cu") (net 220))
  (segment (start 98.78 138.85) (end 98.78 132.6) (width 0.109) (layer "In4.Cu") (net 220))
  (segment (start 114.3 146.4492) (end 114.3 147.2) (width 0.2) (layer "F.Cu") (net 221))
  (segment (start 113.56 142.1) (end 113.852451 142.392451) (width 0.182) (layer "F.Cu") (net 221))
  (segment (start 116.37 132.83) (end 116.37 140.673194) (width 0.182) (layer "F.Cu") (net 221))
  (segment (start 113.852451 142.392451) (end 114.332545 142.392451) (width 0.182) (layer "F.Cu") (net 221))
  (segment (start 126 118.5) (end 126.715 118.5) (width 0.182) (layer "F.Cu") (net 221))
  (segment (start 126 118.5) (end 126 117.5742) (width 0.182) (layer "F.Cu") (net 221))
  (segment (start 114.3 148.4) (end 114.3 147.2) (width 0.182) (layer "F.Cu") (net 221))
  (segment (start 116.37 140.673194) (end 114.650743 142.392451) (width 0.182) (layer "F.Cu") (net 221))
  (segment (start 114.650743 142.392451) (end 114.332545 142.392451) (width 0.182) (layer "F.Cu") (net 221))
  (segment (start 119.2 130) (end 116.37 132.83) (width 0.182) (layer "F.Cu") (net 221))
  (via (at 126 118.5) (size 0.45) (drill 0.1) (layers "F.Cu" "B.Cu") (net 221))
  (via (at 114.3 147.2) (size 0.45) (drill 0.1) (layers "F.Cu" "B.Cu") (net 221))
  (via (at 119.2 130) (size 0.45) (drill 0.1) (layers "F.Cu" "B.Cu") (net 221))
  (via (at 114.332545 142.392451) (size 0.45) (drill 0.1) (layers "F.Cu" "B.Cu") (net 221))
  (segment (start 123.7 120.1) (end 125.3 118.5) (width 0.109) (layer "In6.Cu") (net 221))
  (segment (start 119.2 130) (end 123.7 125.5) (width 0.109) (layer "In6.Cu") (net 221))
  (segment (start 123.7 125.5) (end 123.7 120.1) (width 0.109) (layer "In6.Cu") (net 221))
  (segment (start 114.3 147.2) (end 114.3 142.424996) (width 0.109) (layer "In6.Cu") (net 221))
  (segment (start 125.3 118.5) (end 126 118.5) (width 0.109) (layer "In6.Cu") (net 221))
  (segment (start 114.3 142.424996) (end 114.332545 142.392451) (width 0.109) (layer "In6.Cu") (net 221))
  (segment (start 124.788559 118.524723) (end 125.975277 118.524723) (width 0.182) (layer "B.Cu") (net 221))
  (segment (start 114.332545 142.932545) (end 114.332545 142.392451) (width 0.182) (layer "B.Cu") (net 221))
  (segment (start 115.215 143.1) (end 114.5 143.1) (width 0.182) (layer "B.Cu") (net 221))
  (segment (start 125.975277 118.524723) (end 126 118.5) (width 0.182) (layer "B.Cu") (net 221))
  (segment (start 114.5 143.1) (end 114.332545 142.932545) (width 0.182) (layer "B.Cu") (net 221))
  (segment (start 143.85 141.07) (end 143.85 141.35) (width 0.182) (layer "F.Cu") (net 222))
  (segment (start 144.07 140.85) (end 144.07 140.39) (width 0.182) (layer "F.Cu") (net 222))
  (segment (start 147.536 111.049) (end 147.536 110.721) (width 0.182) (layer "F.Cu") (net 222))
  (segment (start 144.07 140.39) (end 144.06 140.38) (width 0.182) (layer "F.Cu") (net 222))
  (segment (start 147.465 111.12) (end 147.536 111.049) (width 0.182) (layer "F.Cu") (net 222))
  (segment (start 144.07 140.85) (end 143.85 141.07) (width 0.182) (layer "F.Cu") (net 222))
  (segment (start 147.43 111.12) (end 147.465 111.12) (width 0.182) (layer "F.Cu") (net 222))
  (segment (start 147.3 110.485) (end 147.536 110.721) (width 0.182) (layer "F.Cu") (net 222))
  (via (at 147.43 111.12) (size 0.45) (drill 0.1) (layers "F.Cu" "B.Cu") (net 222))
  (via (at 144.06 140.38) (size 0.45) (drill 0.1) (layers "F.Cu" "B.Cu") (net 222))
  (segment (start 150.007186 112.7175) (end 149.127186 111.8375) (width 0.109) (layer "In4.Cu") (net 222))
  (segment (start 147.587499 111.617813) (end 147.587499 111.277499) (width 0.109) (layer "In4.Cu") (net 222))
  (segment (start 154.1825 125.542814) (end 153.8475 125.207814) (width 0.109) (layer "In4.Cu") (net 222))
  (segment (start 149.127186 111.8375) (end 147.807186 111.8375) (width 0.109) (layer "In4.Cu") (net 222))
  (segment (start 153.8475 113.027814) (end 153.537186 112.7175) (width 0.109) (layer "In4.Cu") (net 222))
  (segment (start 148.237186 130.4825) (end 149.997186 130.4825) (width 0.109) (layer "In4.Cu") (net 222))
  (segment (start 149.997186 130.4825) (end 154.1825 126.297186) (width 0.109) (layer "In4.Cu") (net 222))
  (segment (start 153.8475 125.207814) (end 153.8475 113.027814) (width 0.109) (layer "In4.Cu") (net 222))
  (segment (start 147.587499 111.277499) (end 147.43 111.12) (width 0.109) (layer "In4.Cu") (net 222))
  (segment (start 144.072 140.38) (end 144.2175 140.2345) (width 0.109) (layer "In4.Cu") (net 222))
  (segment (start 144.2175 134.502186) (end 148.237186 130.4825) (width 0.109) (layer "In4.Cu") (net 222))
  (segment (start 154.1825 126.297186) (end 154.1825 125.542814) (width 0.109) (layer "In4.Cu") (net 222))
  (segment (start 147.807186 111.8375) (end 147.587499 111.617813) (width 0.109) (layer "In4.Cu") (net 222))
  (segment (start 144.06 140.38) (end 144.072 140.38) (width 0.109) (layer "In4.Cu") (net 222))
  (segment (start 144.2175 140.2345) (end 144.2175 134.502186) (width 0.109) (layer "In4.Cu") (net 222))
  (segment (start 153.537186 112.7175) (end 150.007186 112.7175) (width 0.109) (layer "In4.Cu") (net 222))
  (segment (start 144.57 140.428) (end 144.57 140.795) (width 0.182) (layer "F.Cu") (net 223))
  (segment (start 147.914 110.721) (end 147.914 111.046) (width 0.182) (layer "F.Cu") (net 223))
  (segment (start 144.57 140.795) (end 144.85 141.075) (width 0.182) (layer "F.Cu") (net 223))
  (segment (start 148 111.12) (end 147.988 111.12) (width 0.182) (layer "F.Cu") (net 223))
  (segment (start 144.63 140.38) (end 144.618 140.38) (width 0.182) (layer "F.Cu") (net 223))
  (segment (start 144.618 140.38) (end 144.57 140.428) (width 0.182) (layer "F.Cu") (net 223))
  (segment (start 147.988 111.12) (end 147.914 111.046) (width 0.182) (layer "F.Cu") (net 223))
  (segment (start 144.85 141.075) (end 144.85 141.35) (width 0.182) (layer "F.Cu") (net 223))
  (segment (start 148.15 110.485) (end 147.914 110.721) (width 0.182) (layer "F.Cu") (net 223))
  (via (at 148 111.12) (size 0.45) (drill 0.1) (layers "F.Cu" "B.Cu") (net 223))
  (via (at 144.63 140.38) (size 0.45) (drill 0.1) (layers "F.Cu" "B.Cu") (net 223))
  (segment (start 144.63 140.38) (end 144.618 140.38) (width 0.109) (layer "In4.Cu") (net 223))
  (segment (start 154.1025 125.102186) (end 154.1025 112.922186) (width 0.109) (layer "In4.Cu") (net 223))
  (segment (start 147.842501 111.512187) (end 147.842501 111.277499) (width 0.109) (layer "In4.Cu") (net 223))
  (segment (start 144.4725 140.2345) (end 144.4725 134.607814) (width 0.109) (layer "In4.Cu") (net 223))
  (segment (start 154.1025 112.922186) (end 153.642814 112.4625) (width 0.109) (layer "In4.Cu") (net 223))
  (segment (start 144.4725 134.607814) (end 148.342814 130.7375) (width 0.109) (layer "In4.Cu") (net 223))
  (segment (start 148.342814 130.7375) (end 150.102814 130.7375) (width 0.109) (layer "In4.Cu") (net 223))
  (segment (start 147.842501 111.277499) (end 148 111.12) (width 0.109) (layer "In4.Cu") (net 223))
  (segment (start 150.102814 130.7375) (end 154.4375 126.402814) (width 0.109) (layer "In4.Cu") (net 223))
  (segment (start 147.912814 111.5825) (end 147.842501 111.512187) (width 0.109) (layer "In4.Cu") (net 223))
  (segment (start 150.112814 112.4625) (end 149.232814 111.5825) (width 0.109) (layer "In4.Cu") (net 223))
  (segment (start 154.4375 125.437186) (end 154.1025 125.102186) (width 0.109) (layer "In4.Cu") (net 223))
  (segment (start 144.618 140.38) (end 144.4725 140.2345) (width 0.109) (layer "In4.Cu") (net 223))
  (segment (start 149.232814 111.5825) (end 147.912814 111.5825) (width 0.109) (layer "In4.Cu") (net 223))
  (segment (start 154.4375 126.402814) (end 154.4375 125.437186) (width 0.109) (layer "In4.Cu") (net 223))
  (segment (start 153.642814 112.4625) (end 150.112814 112.4625) (width 0.109) (layer "In4.Cu") (net 223))
  (segment (start 107.13 144.575) (end 105.905 144.575) (width 0.182) (layer "F.Cu") (net 224))
  (segment (start 93.3265 115.399) (end 93.7115 115.088999) (width 0.182) (layer "F.Cu") (net 224))
  (segment (start 105.905 144.575) (end 105.9 144.57) (width 0.182) (layer "F.Cu") (net 224))
  (via (at 105.9 144.57) (size 0.45) (drill 0.1) (layers "F.Cu" "B.Cu") (net 224))
  (via (at 93.7115 115.088999) (size 0.45) (drill 0.1) (layers "F.Cu" "B.Cu") (net 224))
  (segment (start 94.728999 115.088999) (end 95.05 115.41) (width 0.109) (layer "In2.Cu") (net 224))
  (segment (start 108.3 132.37) (end 108.3 135.7) (width 0.109) (layer "In2.Cu") (net 224))
  (segment (start 107 138.707248) (end 107 143.788198) (width 0.109) (layer "In2.Cu") (net 224))
  (segment (start 107.388511 138.318737) (end 107 138.707248) (width 0.109) (layer "In2.Cu") (net 224))
  (segment (start 104.33 128.4) (end 108.3 132.37) (width 0.109) (layer "In2.Cu") (net 224))
  (segment (start 95.714702 119.814702) (end 95.714702 123.064702) (width 0.109) (layer "In2.Cu") (net 224))
  (segment (start 108.3 135.7) (end 107.2 136.8) (width 0.109) (layer "In2.Cu") (net 224))
  (segment (start 95.05 119.15) (end 95.714702 119.814702) (width 0.109) (layer "In2.Cu") (net 224))
  (segment (start 95.714702 123.064702) (end 101.05 128.4) (width 0.109) (layer "In2.Cu") (net 224))
  (segment (start 106.218198 144.57) (end 105.9 144.57) (width 0.109) (layer "In2.Cu") (net 224))
  (segment (start 107.2 136.8) (end 107.2 137.592752) (width 0.109) (layer "In2.Cu") (net 224))
  (segment (start 107.2 137.592752) (end 107.388512 137.781264) (width 0.109) (layer "In2.Cu") (net 224))
  (segment (start 95.05 115.41) (end 95.05 119.15) (width 0.109) (layer "In2.Cu") (net 224))
  (segment (start 93.7115 115.088999) (end 94.728999 115.088999) (width 0.109) (layer "In2.Cu") (net 224))
  (segment (start 101.05 128.4) (end 104.33 128.4) (width 0.109) (layer "In2.Cu") (net 224))
  (segment (start 107.388512 137.781264) (end 107.388511 138.318737) (width 0.109) (layer "In2.Cu") (net 224))
  (segment (start 107 143.788198) (end 106.218198 144.57) (width 0.109) (layer "In2.Cu") (net 224))
  (segment (start 85.659822 122.375) (end 87.2742 122.375) (width 0.2) (layer "F.Cu") (net 225))
  (segment (start 84.575 122.375) (end 84.15 122.8) (width 0.182) (layer "F.Cu") (net 225))
  (segment (start 87.2742 122.375) (end 87.65 121.9992) (width 0.2) (layer "F.Cu") (net 225))
  (segment (start 89.4415 126.504) (end 89.8265 126.194) (width 0.182) (layer "F.Cu") (net 225))
  (segment (start 85.659822 122.375) (end 84.575 122.375) (width 0.182) (layer "F.Cu") (net 225))
  (via (at 89.4415 126.504) (size 0.45) (drill 0.1) (layers "F.Cu" "B.Cu") (net 225))
  (via (at 84.15 122.8) (size 0.45) (drill 0.1) (layers "F.Cu" "B.Cu") (net 225))
  (segment (start 89.4415 126.504) (end 87.854 126.504) (width 0.109) (layer "In6.Cu") (net 225))
  (segment (start 87.854 126.504) (end 84.15 122.8) (width 0.109) (layer "In6.Cu") (net 225))
  (segment (start 84.15 122.8) (end 84.815 122.8) (width 0.182) (layer "B.Cu") (net 225))
  (segment (start 116.810189 120.549811) (end 116.2946 120.549811) (width 0.182) (layer "F.Cu") (net 226))
  (segment (start 129.215 116.9) (end 129.28 116.835) (width 0.182) (layer "F.Cu") (net 226))
  (segment (start 117 119.696) (end 117 120.36) (width 0.182) (layer "F.Cu") (net 226))
  (segment (start 117 120.36) (end 116.810189 120.549811) (width 0.182) (layer "F.Cu") (net 226))
  (segment (start 128.4 116.9) (end 129.215 116.9) (width 0.182) (layer "F.Cu") (net 226))
  (via (at 117 119.696) (size 0.45) (drill 0.1) (layers "F.Cu" "B.Cu") (net 226))
  (via (at 128.4 116.9) (size 0.45) (drill 0.1) (layers "F.Cu" "B.Cu") (net 226))
  (segment (start 116.984 117.516) (end 117.36 117.14) (width 0.182) (layer "In4.Cu") (net 226))
  (segment (start 117.36 117.14) (end 128.16 117.14) (width 0.182) (layer "In4.Cu") (net 226))
  (segment (start 128.16 117.14) (end 128.4 116.9) (width 0.182) (layer "In4.Cu") (net 226))
  (segment (start 116.984 119.68) (end 116.984 117.516) (width 0.182) (layer "In4.Cu") (net 226))
  (segment (start 117 119.696) (end 116.984 119.68) (width 0.182) (layer "In4.Cu") (net 226))
  (segment (start 132.285 117) (end 132.7 117) (width 0.182) (layer "F.Cu") (net 227))
  (segment (start 133.1 117.8) (end 133.7 117.8) (width 0.182) (layer "F.Cu") (net 227))
  (segment (start 132.8 117.1) (end 132.8 117.5) (width 0.182) (layer "F.Cu") (net 227))
  (segment (start 134.025 117.475) (end 134.025 117.05) (width 0.182) (layer "F.Cu") (net 227))
  (segment (start 132.7 117) (end 132.8 117.1) (width 0.182) (layer "F.Cu") (net 227))
  (segment (start 133.7 117.8) (end 134.025 117.475) (width 0.182) (layer "F.Cu") (net 227))
  (segment (start 134.2758 116.7992) (end 134.725 116.7992) (width 0.182) (layer "F.Cu") (net 227))
  (segment (start 134.025 117.05) (end 134.2758 116.7992) (width 0.182) (layer "F.Cu") (net 227))
  (segment (start 132.8 117.5) (end 133.1 117.8) (width 0.182) (layer "F.Cu") (net 227))
  (via (at 133.7 117.8) (size 0.45) (drill 0.1) (layers "F.Cu" "B.Cu") (net 227))
  (segment (start 133.674723 117.774723) (end 133.7 117.8) (width 0.182) (layer "B.Cu") (net 227))
  (segment (start 132.288559 117.774723) (end 133.674723 117.774723) (width 0.182) (layer "B.Cu") (net 227))
  (segment (start 147.775001 65.249999) (end 146.9704 65.249999) (width 0.2) (layer "F.Cu") (net 228))
  (segment (start 148.45 65) (end 148.025 65) (width 0.2) (layer "F.Cu") (net 228))
  (segment (start 148.025 65) (end 147.775001 65.249999) (width 0.2) (layer "F.Cu") (net 228))
  (segment (start 150.661 113.811) (end 150.65 113.8) (width 0.182) (layer "F.Cu") (net 229))
  (segment (start 150.661 114.398) (end 150.661 113.811) (width 0.182) (layer "F.Cu") (net 229))
  (segment (start 150.525 70.125) (end 150.235 70.415) (width 0.182) (layer "F.Cu") (net 229))
  (segment (start 151.85 68.2) (end 151.85 68.8) (width 0.182) (layer "F.Cu") (net 229))
  (segment (start 150.5258 70.125) (end 150.525 70.125) (width 0.182) (layer "F.Cu") (net 229))
  (segment (start 151 70.5992) (end 150.5258 70.125) (width 0.182) (layer "F.Cu") (net 229))
  (segment (start 151.85 68.8) (end 150.525 70.125) (width 0.182) (layer "F.Cu") (net 229))
  (segment (start 150.235 70.415) (end 143.205 70.415) (width 0.182) (layer "F.Cu") (net 229))
  (via (at 150.65 113.8) (size 0.45) (drill 0.1) (layers "F.Cu" "B.Cu") (net 229))
  (via (at 143.205 70.415) (size 0.45) (drill 0.1) (layers "F.Cu" "B.Cu") (net 229))
  (segment (start 150.874999 113.575001) (end 150.874999 112.731661) (width 0.109) (layer "In6.Cu") (net 229))
  (segment (start 134.218022 81.831978) (end 142.65 73.4) (width 0.109) (layer "In6.Cu") (net 229))
  (segment (start 142.65 73.4) (end 142.65 70.97) (width 0.109) (layer "In6.Cu") (net 229))
  (segment (start 150.65 113.8) (end 150.874999 113.575001) (width 0.109) (layer "In6.Cu") (net 229))
  (segment (start 139.3 103.2) (end 134.020489 97.920489) (width 0.109) (layer "In6.Cu") (net 229))
  (segment (start 149.9 104.8) (end 148.3 103.2) (width 0.109) (layer "In6.Cu") (net 229))
  (segment (start 134.218022 90.443044) (end 134.218022 81.831978) (width 0.109) (layer "In6.Cu") (net 229))
  (segment (start 142.65 70.97) (end 143.205 70.415) (width 0.109) (layer "In6.Cu") (net 229))
  (segment (start 133.920488 91.359422) (end 133.920488 90.740578) (width 0.109) (layer "In6.Cu") (net 229))
  (segment (start 134.020489 97.920489) (end 134.020488 91.459422) (width 0.109) (layer "In6.Cu") (net 229))
  (segment (start 150.3 112.156662) (end 150.3 108.5) (width 0.109) (layer "In6.Cu") (net 229))
  (segment (start 149.9 108.1) (end 149.9 104.8) (width 0.109) (layer "In6.Cu") (net 229))
  (segment (start 150.874999 112.731661) (end 150.3 112.156662) (width 0.109) (layer "In6.Cu") (net 229))
  (segment (start 150.3 108.5) (end 149.9 108.1) (width 0.109) (layer "In6.Cu") (net 229))
  (segment (start 133.920488 90.740578) (end 134.218022 90.443044) (width 0.109) (layer "In6.Cu") (net 229))
  (segment (start 148.3 103.2) (end 139.3 103.2) (width 0.109) (layer "In6.Cu") (net 229))
  (segment (start 134.020488 91.459422) (end 133.920488 91.359422) (width 0.109) (layer "In6.Cu") (net 229))
  (segment (start 144.975 115.325) (end 144.975 114.975) (width 0.182) (layer "F.Cu") (net 230))
  (segment (start 144.3625 114.7375) (end 144.075 114.45) (width 0.182) (layer "F.Cu") (net 230))
  (segment (start 144.8 115.5) (end 144.975 115.325) (width 0.182) (layer "F.Cu") (net 230))
  (segment (start 143.580908 112.180908) (end 144.075 112.675) (width 0.182) (layer "F.Cu") (net 230))
  (segment (start 144.075 114.45) (end 144.075 112.675) (width 0.182) (layer "F.Cu") (net 230))
  (segment (start 144.7375 114.7375) (end 144.3625 114.7375) (width 0.182) (layer "F.Cu") (net 230))
  (segment (start 142.520209 112.329791) (end 142.669092 112.180908) (width 0.182) (layer "F.Cu") (net 230))
  (segment (start 142.504791 112.329791) (end 142.520209 112.329791) (width 0.182) (layer "F.Cu") (net 230))
  (segment (start 142.504791 112.329791) (end 141.95176 112.329791) (width 0.182) (layer "F.Cu") (net 230))
  (segment (start 144.975 114.975) (end 144.7375 114.7375) (width 0.182) (layer "F.Cu") (net 230))
  (segment (start 142.669092 112.180908) (end 143.153411 112.180908) (width 0.182) (layer "F.Cu") (net 230))
  (segment (start 144.385 115.5) (end 144.8 115.5) (width 0.182) (layer "F.Cu") (net 230))
  (segment (start 143.153411 112.180908) (end 143.580908 112.180908) (width 0.182) (layer "F.Cu") (net 230))
  (segment (start 143.705586 113.422983) (end 143.705586 114.880586) (width 0.182) (layer "F.Cu") (net 231))
  (segment (start 141.95176 112.829792) (end 142.792395 112.829792) (width 0.182) (layer "F.Cu") (net 231))
  (segment (start 143.4027 113.120097) (end 143.705586 113.422983) (width 0.182) (layer "F.Cu") (net 231))
  (segment (start 143.925 115.1) (end 143.705586 114.880586) (width 0.182) (layer "F.Cu") (net 231))
  (segment (start 142.792395 112.829792) (end 143.0827 113.120097) (width 0.182) (layer "F.Cu") (net 231))
  (segment (start 143.0827 113.120097) (end 143.4027 113.120097) (width 0.182) (layer "F.Cu") (net 231))
  (segment (start 144.359 115.1) (end 143.925 115.1) (width 0.182) (layer "F.Cu") (net 231))
  (segment (start 145.06 114.425) (end 144.778 114.425) (width 0.182) (layer "F.Cu") (net 232))
  (segment (start 144.5 114.147) (end 144.5 113.775) (width 0.182) (layer "F.Cu") (net 232))
  (segment (start 144.778 114.425) (end 144.5 114.147) (width 0.182) (layer "F.Cu") (net 232))
  (segment (start 142.29 115.07) (end 142.49 115.27) (width 0.182) (layer "F.Cu") (net 232))
  (segment (start 141.962834 113.318718) (end 142.471052 113.318718) (width 0.182) (layer "F.Cu") (net 232))
  (segment (start 142.571689 113.419355) (end 142.571689 114.443311) (width 0.182) (layer "F.Cu") (net 232))
  (segment (start 141.945 115.07) (end 142.29 115.07) (width 0.182) (layer "F.Cu") (net 232))
  (segment (start 141.95176 113.329792) (end 141.962834 113.318718) (width 0.182) (layer "F.Cu") (net 232))
  (segment (start 142.571689 114.443311) (end 141.945 115.07) (width 0.182) (layer "F.Cu") (net 232))
  (segment (start 142.471052 113.318718) (end 142.571689 113.419355) (width 0.182) (layer "F.Cu") (net 232))
  (via (at 142.49 115.27) (size 0.45) (drill 0.1) (layers "F.Cu" "B.Cu") (net 232))
  (via (at 144.5 113.775) (size 0.45) (drill 0.1) (layers "F.Cu" "B.Cu") (net 232))
  (segment (start 142.49 115.27) (end 142.49 114.697701) (width 0.109) (layer "In6.Cu") (net 232))
  (segment (start 143.412701 113.775) (end 144.5 113.775) (width 0.109) (layer "In6.Cu") (net 232))
  (segment (start 142.49 114.697701) (end 143.412701 113.775) (width 0.109) (layer "In6.Cu") (net 232))
  (segment (start 147.4 108.8) (end 147.412 108.8) (width 0.182) (layer "F.Cu") (net 233))
  (segment (start 148.560999 113.428287) (end 148.036 112.903288) (width 0.182) (layer "F.Cu") (net 233))
  (segment (start 148.66 114.15) (end 148.671 114.139) (width 0.182) (layer "F.Cu") (net 233))
  (segment (start 147.51 109.305) (end 147.51 108.898) (width 0.182) (layer "F.Cu") (net 233))
  (segment (start 147.3 108.085) (end 147.49 108.275) (width 0.182) (layer "F.Cu") (net 233))
  (segment (start 148.036 112.903288) (end 148.036 112.459) (width 0.182) (layer "F.Cu") (net 233))
  (segment (start 148.671 113.739287) (end 148.560999 113.629286) (width 0.182) (layer "F.Cu") (net 233))
  (segment (start 148.036 112.459) (end 147.927 112.35) (width 0.182) (layer "F.Cu") (net 233))
  (segment (start 148.560999 113.629286) (end 148.560999 113.428287) (width 0.182) (layer "F.Cu") (net 233))
  (segment (start 148.671 114.139) (end 148.671 113.739287) (width 0.182) (layer "F.Cu") (net 233))
  (segment (start 148.66 114.425) (end 148.66 114.15) (width 0.182) (layer "F.Cu") (net 233))
  (segment (start 147.412 108.8) (end 147.51 108.898) (width 0.182) (layer "F.Cu") (net 233))
  (segment (start 147.49 108.275) (end 147.49 108.722) (width 0.182) (layer "F.Cu") (net 233))
  (segment (start 147.3 109.515) (end 147.51 109.305) (width 0.182) (layer "F.Cu") (net 233))
  (segment (start 147.412 108.8) (end 147.49 108.722) (width 0.182) (layer "F.Cu") (net 233))
  (via (at 147.4 108.8) (size 0.45) (drill 0.1) (layers "F.Cu" "B.Cu") (net 233))
  (via (at 147.927 112.35) (size 0.45) (drill 0.1) (layers "F.Cu" "B.Cu") (net 233))
  (segment (start 148.0975 111.822186) (end 148.0975 112.1795) (width 0.109) (layer "In2.Cu") (net 233))
  (segment (start 149.0225 110.877814) (end 147.5575 109.412814) (width 0.109) (layer "In2.Cu") (net 233))
  (segment (start 148.0975 112.1795) (end 147.927 112.35) (width 0.109) (layer "In2.Cu") (net 233))
  (segment (start 147.412 108.8) (end 147.5575 108.9455) (width 0.109) (layer "In2.Cu") (net 233))
  (segment (start 148.347186 111.5725) (end 148.0975 111.822186) (width 0.109) (layer "In2.Cu") (net 233))
  (segment (start 149.0225 110.877814) (end 149.0225 111.322186) (width 0.109) (layer "In2.Cu") (net 233))
  (segment (start 147.5575 109.412814) (end 147.5575 108.9455) (width 0.109) (layer "In2.Cu") (net 233))
  (segment (start 147.4 108.8) (end 147.412 108.8) (width 0.109) (layer "In2.Cu") (net 233))
  (segment (start 148.772186 111.5725) (end 148.347186 111.5725) (width 0.109) (layer "In2.Cu") (net 233))
  (segment (start 149.0225 111.322186) (end 148.772186 111.5725) (width 0.109) (layer "In2.Cu") (net 233))
  (segment (start 148.15 109.515) (end 147.9 109.265) (width 0.182) (layer "F.Cu") (net 234))
  (segment (start 147.97 108.8) (end 147.958 108.8) (width 0.182) (layer "F.Cu") (net 234))
  (segment (start 147.9 109.265) (end 147.9 108.858) (width 0.182) (layer "F.Cu") (net 234))
  (segment (start 147.914 108.321) (end 147.914 108.756) (width 0.182) (layer "F.Cu") (net 234))
  (segment (start 148.93899 113.472718) (end 148.93899 113.271702) (width 0.182) (layer "F.Cu") (net 234))
  (segment (start 147.958 108.8) (end 147.9 108.858) (width 0.182) (layer "F.Cu") (net 234))
  (segment (start 148.93899 113.271702) (end 148.414 112.746712) (width 0.182) (layer "F.Cu") (net 234))
  (segment (start 149.06 114.15) (end 149.049 114.139) (width 0.182) (layer "F.Cu") (net 234))
  (segment (start 148.414 112.459) (end 148.523 112.35) (width 0.182) (layer "F.Cu") (net 234))
  (segment (start 148.414 112.746712) (end 148.414 112.459) (width 0.182) (layer "F.Cu") (net 234))
  (segment (start 149.049 113.582728) (end 148.93899 113.472718) (width 0.182) (layer "F.Cu") (net 234))
  (segment (start 147.914 108.321) (end 148.15 108.085) (width 0.182) (layer "F.Cu") (net 234))
  (segment (start 147.958 108.8) (end 147.914 108.756) (width 0.182) (layer "F.Cu") (net 234))
  (segment (start 149.06 114.425) (end 149.06 114.15) (width 0.182) (layer "F.Cu") (net 234))
  (segment (start 149.049 114.139) (end 149.049 113.582728) (width 0.182) (layer "F.Cu") (net 234))
  (via (at 147.97 108.8) (size 0.45) (drill 0.1) (layers "F.Cu" "B.Cu") (net 234))
  (via (at 148.523 112.35) (size 0.45) (drill 0.1) (layers "F.Cu" "B.Cu") (net 234))
  (segment (start 148.3525 111.927814) (end 148.3525 112.1795) (width 0.109) (layer "In2.Cu") (net 234))
  (segment (start 148.877814 111.8275) (end 148.452814 111.8275) (width 0.109) (layer "In2.Cu") (net 234))
  (segment (start 147.97 108.8) (end 147.958 108.8) (width 0.109) (layer "In2.Cu") (net 234))
  (segment (start 149.2775 111.427814) (end 148.877814 111.8275) (width 0.109) (layer "In2.Cu") (net 234))
  (segment (start 149.2775 110.772186) (end 149.2775 111.427814) (width 0.109) (layer "In2.Cu") (net 234))
  (segment (start 148.452814 111.8275) (end 148.3525 111.927814) (width 0.109) (layer "In2.Cu") (net 234))
  (segment (start 149.2775 110.772186) (end 147.8125 109.307186) (width 0.109) (layer "In2.Cu") (net 234))
  (segment (start 148.3525 112.1795) (end 148.523 112.35) (width 0.109) (layer "In2.Cu") (net 234))
  (segment (start 147.958 108.8) (end 147.8125 108.9455) (width 0.109) (layer "In2.Cu") (net 234))
  (segment (start 147.8125 109.307186) (end 147.8125 108.9455) (width 0.109) (layer "In2.Cu") (net 234))
  (via (at 174.199999 70.4) (size 0.6) (drill 0.25) (layers "F.Cu" "B.Cu") (net 235))
  (segment (start 167.16 65.46) (end 167.16 65.61) (width 0.4) (layer "In2.Cu") (net 235))
  (segment (start 167.16 65.61) (end 169.275 67.725) (width 0.4) (layer "In2.Cu") (net 235))
  (segment (start 173.375 70.4) (end 174.199999 70.4) (width 0.4) (layer "In2.Cu") (net 235))
  (segment (start 169.275 67.725) (end 170.7 67.725) (width 0.4) (layer "In2.Cu") (net 235))
  (segment (start 170.7 67.725) (end 173.375 70.4) (width 0.4) (layer "In2.Cu") (net 235))
  (segment (start 174.855 68.9) (end 174.94 68.985) (width 0.4) (layer "F.Cu") (net 236))
  (segment (start 169.7 66.72) (end 171.48 68.5) (width 0.4) (layer "F.Cu") (net 236))
  (segment (start 171.48 68.5) (end 171.5 68.5) (width 0.4) (layer "F.Cu") (net 236))
  (segment (start 171.9 68.9) (end 174.855 68.9) (width 0.4) (layer "F.Cu") (net 236))
  (segment (start 171.5 68.5) (end 171.9 68.9) (width 0.4) (layer "F.Cu") (net 236))
  (segment (start 173.599999 76.649999) (end 174.664999 76.649999) (width 0.2) (layer "F.Cu") (net 237))
  (segment (start 173.599999 76.3) (end 173.599999 76.649999) (width 0.2) (layer "F.Cu") (net 237))
  (segment (start 174.664999 76.649999) (end 174.94 76.925) (width 0.2) (layer "F.Cu") (net 237))
  (via (at 173.599999 76.3) (size 0.6) (drill 0.25) (layers "F.Cu" "B.Cu") (net 237))
  (segment (start 173 69.9625) (end 173 76) (width 0.4) (layer "In6.Cu") (net 237))
  (segment (start 158.275 66.725) (end 168.275 66.725) (width 0.4) (layer "In6.Cu") (net 237))
  (segment (start 173 76) (end 173.3 76.3) (width 0.4) (layer "In6.Cu") (net 237))
  (segment (start 170.7625 67.725) (end 173 69.9625) (width 0.4) (layer "In6.Cu") (net 237))
  (segment (start 173.3 76.3) (end 173.599999 76.3) (width 0.4) (layer "In6.Cu") (net 237))
  (segment (start 169.275 67.725) (end 170.7625 67.725) (width 0.4) (layer "In6.Cu") (net 237))
  (segment (start 168.275 66.725) (end 169.275 67.725) (width 0.4) (layer "In6.Cu") (net 237))
  (segment (start 173.6 73.8) (end 173.6 74.2) (width 0.2) (layer "F.Cu") (net 238))
  (segment (start 174.665 74.2) (end 173.6 74.2) (width 0.2) (layer "F.Cu") (net 238))
  (segment (start 174.94 74.475) (end 174.665 74.2) (width 0.2) (layer "F.Cu") (net 238))
  (segment (start 173.6 73.8) (end 174.199999 73.200001) (width 0.2) (layer "F.Cu") (net 238))
  (via (at 174.199999 73.200001) (size 0.6) (drill 0.25) (layers "F.Cu" "B.Cu") (net 238))
  (segment (start 173.600001 73.200001) (end 174.199999 73.200001) (width 0.4) (layer "In4.Cu") (net 238))
  (segment (start 162.0875 66.6875) (end 168.2125 66.6875) (width 0.4) (layer "In4.Cu") (net 238))
  (segment (start 173 72.6) (end 173.600001 73.200001) (width 0.4) (layer "In4.Cu") (net 238))
  (segment (start 170.725 67.725) (end 173 70) (width 0.4) (layer "In4.Cu") (net 238))
  (segment (start 169.25 67.725) (end 170.725 67.725) (width 0.4) (layer "In4.Cu") (net 238))
  (segment (start 168.2125 66.6875) (end 169.25 67.725) (width 0.4) (layer "In4.Cu") (net 238))
  (segment (start 173 70) (end 173 72.6) (width 0.4) (layer "In4.Cu") (net 238))
  (segment (start 160.81 65.46) (end 160.86 65.46) (width 0.4) (layer "In4.Cu") (net 238))
  (segment (start 160.86 65.46) (end 162.0875 66.6875) (width 0.4) (layer "In4.Cu") (net 238))
  (segment (start 169.1 131.3) (end 170.25 131.3) (width 0.182) (layer "F.Cu") (net 239))
  (segment (start 170.25 131.3) (end 170.35 131.2) (width 0.182) (layer "F.Cu") (net 239))
  (segment (start 142.44 84.07) (end 142.43 84.06) (width 0.182) (layer "F.Cu") (net 240))
  (segment (start 143.029999 84.07) (end 142.44 84.07) (width 0.182) (layer "F.Cu") (net 240))
  (segment (start 143.2 83.899999) (end 143.029999 84.07) (width 0.182) (layer "F.Cu") (net 240))
  (via (at 142.43 84.06) (size 0.45) (drill 0.1) (layers "F.Cu" "B.Cu") (net 240))
  (segment (start 141.8 84.19) (end 142.3 84.19) (width 0.182) (layer "B.Cu") (net 240))
  (segment (start 142.3 84.19) (end 142.43 84.06) (width 0.182) (layer "B.Cu") (net 240))
  (segment (start 179.725 115.875) (end 180.175 115.425) (width 0.182) (layer "F.Cu") (net 241))
  (segment (start 178.985 115.875) (end 179.725 115.875) (width 0.182) (layer "F.Cu") (net 241))
  (segment (start 169.385 115.575) (end 169.875 115.575) (width 0.182) (layer "F.Cu") (net 242))
  (segment (start 170.2 115.575) (end 170.35 115.425) (width 0.182) (layer "F.Cu") (net 242))
  (segment (start 169.875 115.575) (end 170.225 115.575) (width 0.182) (layer "F.Cu") (net 242))
  (segment (start 169.875 115.575) (end 170.2 115.575) (width 0.182) (layer "F.Cu") (net 242))
  (segment (start 104.85 89.45) (end 105.3 89.9) (width 0.4) (layer "B.Cu") (net 243))
  (segment (start 104.85 88.4) (end 104.85 89.45) (width 0.4) (layer "B.Cu") (net 243))
  (segment (start 107.485 89.315) (end 107.485 88.6) (width 0.4) (layer "B.Cu") (net 243))
  (segment (start 108.4 86.485) (end 108.465 86.55) (width 0.4) (layer "B.Cu") (net 243))
  (segment (start 106.35 89.9) (end 106.9 89.9) (width 0.4) (layer "B.Cu") (net 243))
  (segment (start 106.9 89.9) (end 107.485 89.315) (width 0.4) (layer "B.Cu") (net 243))
  (segment (start 105.6 86.485) (end 108.4 86.485) (width 0.4) (layer "B.Cu") (net 243))
  (segment (start 106.35 89.9) (end 106.95 89.9) (width 0.4) (layer "B.Cu") (net 243))
  (segment (start 105.3 89.9) (end 106.35 89.9) (width 0.4) (layer "B.Cu") (net 243))
  (segment (start 105.6 85.515) (end 105.815 85.3) (width 0.4) (layer "B.Cu") (net 244))
  (segment (start 105.815 85.3) (end 106.6 85.3) (width 0.4) (layer "B.Cu") (net 244))
  (segment (start 106.86 83.9) (end 106.86 85.04) (width 0.4) (layer "B.Cu") (net 244))
  (segment (start 106.86 85.04) (end 106.6 85.3) (width 0.4) (layer "B.Cu") (net 244))
  (segment (start 109.574999 85.3) (end 110.385 85.3) (width 0.4) (layer "B.Cu") (net 245))
  (segment (start 110.385 85.3) (end 110.6 85.515) (width 0.4) (layer "B.Cu") (net 245))
  (segment (start 109.4 85.125001) (end 109.4 83.9) (width 0.4) (layer "B.Cu") (net 245))
  (segment (start 109.574999 85.3) (end 109.4 85.125001) (width 0.4) (layer "B.Cu") (net 245))
  (segment (start 96.725 140.325001) (end 96.725 139.425) (width 0.4) (layer "F.Cu") (net 246))
  (segment (start 96.725 139.425) (end 96.7 139.4) (width 0.4) (layer "F.Cu") (net 246))
  (via (at 96.7 139.4) (size 0.45) (drill 0.1) (layers "F.Cu" "B.Cu") (net 246))
  (segment (start 96.7 140.065001) (end 96.725 140.090001) (width 0.4) (layer "B.Cu") (net 246))
  (segment (start 96.7 139.4) (end 96.7 140.065001) (width 0.4) (layer "B.Cu") (net 246))
  (segment (start 101.475 141.875) (end 100.675 141.875) (width 0.182) (layer "F.Cu") (net 247))
  (via (at 100.65 141.9) (size 0.45) (drill 0.1) (layers "F.Cu" "B.Cu") (net 247))
  (segment (start 100.65 141.9) (end 101.265 141.9) (width 0.182) (layer "B.Cu") (net 247))
  (segment (start 127.8 139.95) (end 126.325334 141.424666) (width 0.178) (layer "F.Cu") (net 259))
  (segment (start 128.175 138.925) (end 127.8 139.3) (width 0.178) (layer "F.Cu") (net 259))
  (segment (start 126.325334 141.424666) (end 126.325334 150.604218) (width 0.178) (layer "F.Cu") (net 259))
  (segment (start 127.8 139.3) (end 127.8 139.95) (width 0.178) (layer "F.Cu") (net 259))
  (segment (start 128.825 138.925) (end 128.175 138.925) (width 0.178) (layer "F.Cu") (net 259))
  (segment (start 129.325 138.425) (end 128.825 138.925) (width 0.178) (layer "F.Cu") (net 259))
  (segment (start 129.325 137.6) (end 129.325 138.425) (width 0.182) (layer "F.Cu") (net 259))
  (segment (start 128.60401 140.990102) (end 128.652155 141.028497) (width 0.182) (layer "F.Cu") (net 260))
  (segment (start 128.652155 141.028497) (end 128.707638 141.055215) (width 0.182) (layer "F.Cu") (net 260))
  (segment (start 128.588908 140.975) (end 128.60401 140.990102) (width 0.182) (layer "F.Cu") (net 260))
  (segment (start 128.992919 140.990102) (end 129.031313 140.941956) (width 0.182) (layer "F.Cu") (net 260))
  (segment (start 128.303627 140.909886) (end 128.363664 140.896183) (width 0.182) (layer "F.Cu") (net 260))
  (segment (start 128.425244 140.896183) (end 128.485281 140.909886) (width 0.182) (layer "F.Cu") (net 260))
  (segment (start 129.058032 140.70482) (end 129.031313 140.649338) (width 0.182) (layer "F.Cu") (net 260))
  (segment (start 128.707638 141.055215) (end 128.767674 141.068918) (width 0.182) (layer "F.Cu") (net 260))
  (segment (start 129.725 137.6) (end 129.725 139.45) (width 0.178) (layer "F.Cu") (net 260))
  (segment (start 128.363664 140.896183) (end 128.425244 140.896183) (width 0.182) (layer "F.Cu") (net 260))
  (segment (start 128.912703 140.300809) (end 128.939421 140.245327) (width 0.182) (layer "F.Cu") (net 260))
  (segment (start 127.425 141.75) (end 128.2 140.975) (width 0.182) (layer "F.Cu") (net 260))
  (segment (start 128.485281 140.909886) (end 128.540763 140.936605) (width 0.182) (layer "F.Cu") (net 260))
  (segment (start 128.2 140.975) (end 128.248145 140.936605) (width 0.182) (layer "F.Cu") (net 260))
  (segment (start 128.912703 140.482462) (end 128.899 140.422426) (width 0.182) (layer "F.Cu") (net 260))
  (segment (start 128.977817 140.197182) (end 129.725 139.45) (width 0.182) (layer "F.Cu") (net 260))
  (segment (start 128.944773 141.028497) (end 128.992919 140.990102) (width 0.182) (layer "F.Cu") (net 260))
  (segment (start 128.992919 140.601193) (end 128.977816 140.58609) (width 0.182) (layer "F.Cu") (net 260))
  (segment (start 128.899 140.422426) (end 128.899 140.360846) (width 0.182) (layer "F.Cu") (net 260))
  (segment (start 129.031313 140.941956) (end 129.058032 140.886474) (width 0.182) (layer "F.Cu") (net 260))
  (segment (start 128.889291 141.055215) (end 128.944773 141.028497) (width 0.182) (layer "F.Cu") (net 260))
  (segment (start 128.767674 141.068918) (end 128.829254 141.068918) (width 0.182) (layer "F.Cu") (net 260))
  (segment (start 128.829254 141.068918) (end 128.889291 141.055215) (width 0.182) (layer "F.Cu") (net 260))
  (segment (start 129.071735 140.826437) (end 129.071735 140.764857) (width 0.182) (layer "F.Cu") (net 260))
  (segment (start 128.248145 140.936605) (end 128.303627 140.909886) (width 0.182) (layer "F.Cu") (net 260))
  (segment (start 129.071735 140.764857) (end 129.058032 140.70482) (width 0.182) (layer "F.Cu") (net 260))
  (segment (start 128.939421 140.245327) (end 128.977817 140.197182) (width 0.182) (layer "F.Cu") (net 260))
  (segment (start 129.058032 140.886474) (end 129.071735 140.826437) (width 0.182) (layer "F.Cu") (net 260))
  (segment (start 128.899 140.360846) (end 128.912703 140.300809) (width 0.182) (layer "F.Cu") (net 260))
  (segment (start 127.425 141.75) (end 127.425 150.603884) (width 0.178) (layer "F.Cu") (net 260))
  (segment (start 129.031313 140.649338) (end 128.992919 140.601193) (width 0.182) (layer "F.Cu") (net 260))
  (segment (start 128.540763 140.936605) (end 128.588908 140.975) (width 0.182) (layer "F.Cu") (net 260))
  (segment (start 128.977816 140.58609) (end 128.939421 140.537945) (width 0.182) (layer "F.Cu") (net 260))
  (segment (start 128.939421 140.537945) (end 128.912703 140.482462) (width 0.182) (layer "F.Cu") (net 260))
  (segment (start 129.625334 149.325334) (end 129.625 149.325) (width 0.182) (layer "F.Cu") (net 261))
  (segment (start 129.625334 150.604218) (end 129.625334 149.325334) (width 0.182) (layer "F.Cu") (net 261))
  (segment (start 128.226554 137.773446) (end 127.796163 137.773446) (width 0.182) (layer "F.Cu") (net 261))
  (segment (start 128.75 137.575) (end 128.425 137.575) (width 0.182) (layer "F.Cu") (net 261))
  (segment (start 128.425 137.575) (end 128.226554 137.773446) (width 0.182) (layer "F.Cu") (net 261))
  (via (at 129.625 149.325) (size 0.45) (drill 0.1) (layers "F.Cu" "B.Cu") (net 261))
  (via (at 127.796163 137.773446) (size 0.45) (drill 0.1) (layers "F.Cu" "B.Cu") (net 261))
  (segment (start 129.625 149.325) (end 127.796163 147.496163) (width 0.109) (layer "In4.Cu") (net 261))
  (segment (start 127.796163 147.496163) (end 127.796163 137.773446) (width 0.109) (layer "In4.Cu") (net 261))
  (segment (start 131.42951 137.575) (end 131.85 137.99549) (width 0.182) (layer "F.Cu") (net 262))
  (segment (start 131.825334 149.325334) (end 131.825 149.325) (width 0.182) (layer "F.Cu") (net 262))
  (segment (start 131.1 137.575) (end 131.42951 137.575) (width 0.182) (layer "F.Cu") (net 262))
  (segment (start 131.825334 150.604218) (end 131.825334 149.325334) (width 0.182) (layer "F.Cu") (net 262))
  (via (at 131.85 137.99549) (size 0.45) (drill 0.1) (layers "F.Cu" "B.Cu") (net 262))
  (via (at 131.825 149.325) (size 0.45) (drill 0.1) (layers "F.Cu" "B.Cu") (net 262))
  (segment (start 131.817478 139.041756) (end 131.79529 139.105165) (width 0.109) (layer "In4.Cu") (net 262))
  (segment (start 131.325188 139.875) (end 131.525 139.875) (width 0.109) (layer "In4.Cu") (net 262))
  (segment (start 131.825 140.175) (end 131.825 149.325) (width 0.109) (layer "In4.Cu") (net 262))
  (segment (start 131.195022 139.84529) (end 131.258431 139.867478) (width 0.109) (layer "In4.Cu") (net 262))
  (segment (start 131.85 137.99549) (end 131.825 138.02049) (width 0.109) (layer "In4.Cu") (net 262))
  (segment (start 131.138141 139.34045) (end 131.090638 139.387953) (width 0.109) (layer "In4.Cu") (net 262))
  (segment (start 131.712046 139.209549) (end 131.655165 139.24529) (width 0.109) (layer "In4.Cu") (net 262))
  (segment (start 131.79529 139.105165) (end 131.759549 139.162046) (width 0.109) (layer "In4.Cu") (net 262))
  (segment (start 131.79529 140.044834) (end 131.817478 140.108243) (width 0.109) (layer "In4.Cu") (net 262))
  (segment (start 131.759549 139.162046) (end 131.712046 139.209549) (width 0.109) (layer "In4.Cu") (net 262))
  (segment (start 131.032709 139.641756) (end 131.054897 139.705165) (width 0.109) (layer "In4.Cu") (net 262))
  (segment (start 131.090638 139.387953) (end 131.054897 139.444834) (width 0.109) (layer "In4.Cu") (net 262))
  (segment (start 131.195022 139.304709) (end 131.138141 139.34045) (width 0.109) (layer "In4.Cu") (net 262))
  (segment (start 131.258431 139.282521) (end 131.195022 139.304709) (width 0.109) (layer "In4.Cu") (net 262))
  (segment (start 131.817478 140.108243) (end 131.825 140.175) (width 0.109) (layer "In4.Cu") (net 262))
  (segment (start 131.525 139.275) (end 131.325188 139.275) (width 0.109) (layer "In4.Cu") (net 262))
  (segment (start 131.325188 139.275) (end 131.258431 139.282521) (width 0.109) (layer "In4.Cu") (net 262))
  (segment (start 131.591756 139.267478) (end 131.525 139.275) (width 0.109) (layer "In4.Cu") (net 262))
  (segment (start 131.138141 139.809549) (end 131.195022 139.84529) (width 0.109) (layer "In4.Cu") (net 262))
  (segment (start 131.054897 139.705165) (end 131.090638 139.762046) (width 0.109) (layer "In4.Cu") (net 262))
  (segment (start 131.090638 139.762046) (end 131.138141 139.809549) (width 0.109) (layer "In4.Cu") (net 262))
  (segment (start 131.655165 139.904709) (end 131.712046 139.94045) (width 0.109) (layer "In4.Cu") (net 262))
  (segment (start 131.655165 139.24529) (end 131.591756 139.267478) (width 0.109) (layer "In4.Cu") (net 262))
  (segment (start 131.712046 139.94045) (end 131.759549 139.987953) (width 0.109) (layer "In4.Cu") (net 262))
  (segment (start 131.825 138.975) (end 131.817478 139.041756) (width 0.109) (layer "In4.Cu") (net 262))
  (segment (start 131.525 139.875) (end 131.591756 139.882521) (width 0.109) (layer "In4.Cu") (net 262))
  (segment (start 131.054897 139.444834) (end 131.032709 139.508243) (width 0.109) (layer "In4.Cu") (net 262))
  (segment (start 131.759549 139.987953) (end 131.79529 140.044834) (width 0.109) (layer "In4.Cu") (net 262))
  (segment (start 131.258431 139.867478) (end 131.325188 139.875) (width 0.109) (layer "In4.Cu") (net 262))
  (segment (start 131.591756 139.882521) (end 131.655165 139.904709) (width 0.109) (layer "In4.Cu") (net 262))
  (segment (start 131.825 138.02049) (end 131.825 138.975) (width 0.109) (layer "In4.Cu") (net 262))
  (segment (start 131.025188 139.575) (end 131.032709 139.641756) (width 0.109) (layer "In4.Cu") (net 262))
  (segment (start 131.032709 139.508243) (end 131.025188 139.575) (width 0.109) (layer "In4.Cu") (net 262))
  (segment (start 130.77658 140.566251) (end 130.766391 140.610894) (width 0.182) (layer "F.Cu") (net 263))
  (segment (start 131.285234 140.723326) (end 131.329877 140.733515) (width 0.182) (layer "F.Cu") (net 263))
  (segment (start 130.77658 140.701329) (end 130.796448 140.742586) (width 0.182) (layer "F.Cu") (net 263))
  (segment (start 130.950248 140.840543) (end 130.996039 140.840543) (width 0.182) (layer "F.Cu") (net 263))
  (segment (start 131.239442 140.723326) (end 131.285234 140.723326) (width 0.182) (layer "F.Cu") (net 263))
  (segment (start 130.864348 140.810485) (end 130.905605 140.830353) (width 0.182) (layer "F.Cu") (net 263))
  (segment (start 130.883608 140.367492) (end 130.873418 140.412136) (width 0.182) (layer "F.Cu") (net 263))
  (segment (start 132.925 142.3) (end 132.925 150.603884) (width 0.178) (layer "F.Cu") (net 263))
  (segment (start 131.406935 140.781934) (end 131.410484 140.785484) (width 0.182) (layer "F.Cu") (net 263))
  (segment (start 130.824999 140.778387) (end 130.828547 140.781935) (width 0.182) (layer "F.Cu") (net 263))
  (segment (start 130.125 139.5) (end 130.825 140.2) (width 0.182) (layer "F.Cu") (net 263))
  (segment (start 131.371134 140.753383) (end 131.406935 140.781934) (width 0.182) (layer "F.Cu") (net 263))
  (segment (start 131.08194 140.810485) (end 131.153542 140.753383) (width 0.182) (layer "F.Cu") (net 263))
  (segment (start 130.85355 140.235801) (end 130.873418 140.277057) (width 0.182) (layer "F.Cu") (net 263))
  (segment (start 130.766391 140.610894) (end 130.766391 140.656686) (width 0.182) (layer "F.Cu") (net 263))
  (segment (start 130.125 137.6) (end 130.125 139.5) (width 0.182) (layer "F.Cu") (net 263))
  (segment (start 130.85355 140.453392) (end 130.796448 140.524994) (width 0.182) (layer "F.Cu") (net 263))
  (segment (start 130.828547 140.781935) (end 130.864348 140.810485) (width 0.182) (layer "F.Cu") (net 263))
  (segment (start 130.873418 140.277057) (end 130.883608 140.321701) (width 0.182) (layer "F.Cu") (net 263))
  (segment (start 130.796448 140.742586) (end 130.824999 140.778387) (width 0.182) (layer "F.Cu") (net 263))
  (segment (start 130.766391 140.656686) (end 130.77658 140.701329) (width 0.182) (layer "F.Cu") (net 263))
  (segment (start 130.883608 140.321701) (end 130.883608 140.367492) (width 0.182) (layer "F.Cu") (net 263))
  (segment (start 130.873418 140.412136) (end 130.85355 140.453392) (width 0.182) (layer "F.Cu") (net 263))
  (segment (start 130.825 140.2) (end 130.85355 140.235801) (width 0.182) (layer "F.Cu") (net 263))
  (segment (start 131.194799 140.733515) (end 131.239442 140.723326) (width 0.182) (layer "F.Cu") (net 263))
  (segment (start 130.796448 140.524994) (end 130.77658 140.566251) (width 0.182) (layer "F.Cu") (net 263))
  (segment (start 131.410484 140.785484) (end 132.925 142.3) (width 0.182) (layer "F.Cu") (net 263))
  (segment (start 131.040683 140.830353) (end 131.08194 140.810485) (width 0.182) (layer "F.Cu") (net 263))
  (segment (start 131.329877 140.733515) (end 131.371134 140.753383) (width 0.182) (layer "F.Cu") (net 263))
  (segment (start 130.905605 140.830353) (end 130.950248 140.840543) (width 0.182) (layer "F.Cu") (net 263))
  (segment (start 130.996039 140.840543) (end 131.040683 140.830353) (width 0.182) (layer "F.Cu") (net 263))
  (segment (start 131.153542 140.753383) (end 131.194799 140.733515) (width 0.182) (layer "F.Cu") (net 263))
  (segment (start 134.225 142.575) (end 134.025334 142.774666) (width 0.178) (layer "F.Cu") (net 264))
  (segment (start 134.025 141.8) (end 130.525 138.3) (width 0.182) (layer "F.Cu") (net 264))
  (segment (start 130.525 138.3) (end 130.525 137.6) (width 0.182) (layer "F.Cu") (net 264))
  (segment (start 134.025 141.8) (end 134.225 142) (width 0.178) (layer "F.Cu") (net 264))
  (segment (start 134.025334 150.604218) (end 134.025334 142.774666) (width 0.178) (layer "F.Cu") (net 264))
  (segment (start 134.225 142) (end 134.225 142.575) (width 0.178) (layer "F.Cu") (net 264))
  (segment (start 149.0625 63.5375) (end 149.575 64.05) (width 0.4) (layer "F.Cu") (net 265))
  (segment (start 144.301 59.355) (end 144.299 59.353) (width 0.4) (layer "F.Cu") (net 265))
  (segment (start 148.67 62.2) (end 148.67 63.145) (width 0.4) (layer "F.Cu") (net 265))
  (segment (start 151.9 65.015) (end 151.9 64.25) (width 0.182) (layer "F.Cu") (net 265))
  (segment (start 149.015 61.855) (end 148.67 62.2) (width 0.4) (layer "F.Cu") (net 265))
  (segment (start 149.099 60.516) (end 149.015 60.6) (width 0.4) (layer "F.Cu") (net 265))
  (segment (start 144.584001 57.985999) (end 144.584001 58.555) (width 0.4) (layer "F.Cu") (net 265))
  (segment (start 149.015 60.6) (end 149.015 61.855) (width 0.4) (layer "F.Cu") (net 265))
  (segment (start 154.2 106.75) (end 153.6 106.75) (width 0.4) (layer "F.Cu") (net 265))
  (segment (start 145.975 108.95) (end 145.975 109.565) (width 0.2) (layer "F.Cu") (net 265))
  (segment (start 151.7 64.05) (end 150.55 64.05) (width 0.182) (layer "F.Cu") (net 265))
  (segment (start 144.5 59.156) (end 144.301 59.355) (width 0.4) (layer "F.Cu") (net 265))
  (segment (start 148.813999 58.173999) (end 148.215 57.575) (width 0.4) (layer "F.Cu") (net 265))
  (segment (start 149.575 64.05) (end 150.55 64.05) (width 0.4) (layer "F.Cu") (net 265))
  (segment (start 149.099 59.355) (end 149.099 58.89967) (width 0.4) (layer "F.Cu") (net 265))
  (segment (start 149.099 59.349) (end 149.099 60.516) (width 0.4) (layer "F.Cu") (net 265))
  (segment (start 148.813999 58.614669) (end 148.813999 58.173999) (width 0.4) (layer "F.Cu") (net 265))
  (segment (start 144.5 58.639001) (end 144.5 59.156) (width 0.4) (layer "F.Cu") (net 265))
  (segment (start 149.099 58.89967) (end 148.813999 58.614669) (width 0.4) (layer "F.Cu") (net 265))
  (segment (start 144.299 59.353) (end 144.299 59.349) (width 0.4) (layer "F.Cu") (net 265))
  (segment (start 144.995 57.575) (end 144.584001 57.985999) (width 0.4) (layer "F.Cu") (net 265))
  (segment (start 151.9 64.25) (end 151.7 64.05) (width 0.182) (layer "F.Cu") (net 265))
  (segment (start 148.67 63.145) (end 149.0625 63.5375) (width 0.4) (layer "F.Cu") (net 265))
  (segment (start 148.215 57.575) (end 144.995 57.575) (width 0.4) (layer "F.Cu") (net 265))
  (segment (start 145.975 109.565) (end 145.985 109.575) (width 0.2) (layer "F.Cu") (net 265))
  (segment (start 144.584001 58.555) (end 144.5 58.639001) (width 0.4) (layer "F.Cu") (net 265))
  (via (at 149.0625 63.5375) (size 0.5) (drill 0.15) (layers "F.Cu" "B.Cu") (net 265))
  (via (at 145.975 108.95) (size 0.5) (drill 0.15) (layers "F.Cu" "B.Cu") (net 265))
  (via (at 153.6 106.75) (size 0.5) (drill 0.15) (layers "F.Cu" "B.Cu") (net 265))
  (segment (start 145.975 108.475) (end 146.3 108.15) (width 0.2) (layer "In2.Cu") (net 265))
  (segment (start 148.65 108.15) (end 150.55 106.25) (width 0.2) (layer "In2.Cu") (net 265))
  (segment (start 153.1 106.25) (end 153.6 106.75) (width 0.2) (layer "In2.Cu") (net 265))
  (segment (start 150.55 106.25) (end 153.1 106.25) (width 0.2) (layer "In2.Cu") (net 265))
  (segment (start 145.975 108.95) (end 145.975 108.475) (width 0.2) (layer "In2.Cu") (net 265))
  (segment (start 146.3 108.15) (end 148.65 108.15) (width 0.2) (layer "In2.Cu") (net 265))
  (segment (start 148.075 64.525) (end 144.55 64.525) (width 0.2) (layer "In6.Cu") (net 265))
  (segment (start 134.472533 90.548465) (end 134.174999 90.845999) (width 0.2) (layer "In6.Cu") (net 265))
  (segment (start 142.975 71.425) (end 142.975 73.545998) (width 0.2) (layer "In6.Cu") (net 265))
  (segment (start 142.975 73.545998) (end 134.472533 82.048465) (width 0.2) (layer "In6.Cu") (net 265))
  (segment (start 134.174999 91.254001) (end 134.274999 91.354001) (width 0.2) (layer "In6.Cu") (net 265))
  (segment (start 150.4 104.6) (end 150.4 106.05) (width 0.2) (layer "In6.Cu") (net 265))
  (segment (start 150.4 106.05) (end 151.1 106.75) (width 0.2) (layer "In6.Cu") (net 265))
  (segment (start 143.65 65.425) (end 143.65 70.75) (width 0.2) (layer "In6.Cu") (net 265))
  (segment (start 143.65 70.75) (end 142.975 71.425) (width 0.2) (layer "In6.Cu") (net 265))
  (segment (start 134.274999 91.354001) (end 134.274999 97.474999) (width 0.2) (layer "In6.Cu") (net 265))
  (segment (start 134.472533 82.048465) (end 134.472533 90.548465) (width 0.2) (layer "In6.Cu") (net 265))
  (segment (start 139.6 102.8) (end 148.6 102.8) (width 0.2) (layer "In6.Cu") (net 265))
  (segment (start 134.274999 97.474999) (end 139.6 102.8) (width 0.2) (layer "In6.Cu") (net 265))
  (segment (start 149.0625 63.5375) (end 148.075 64.525) (width 0.2) (layer "In6.Cu") (net 265))
  (segment (start 148.6 102.8) (end 150.4 104.6) (width 0.2) (layer "In6.Cu") (net 265))
  (segment (start 151.1 106.75) (end 153.6 106.75) (width 0.2) (layer "In6.Cu") (net 265))
  (segment (start 144.55 64.525) (end 143.65 65.425) (width 0.2) (layer "In6.Cu") (net 265))
  (segment (start 134.174999 90.845999) (end 134.174999 91.254001) (width 0.2) (layer "In6.Cu") (net 265))
  (segment (start 142.925 141.65) (end 143.134998 141.859998) (width 0.2) (layer "F.Cu") (net 266))
  (segment (start 146.745 141.445) (end 146.745 142.18) (width 0.2) (layer "F.Cu") (net 266))
  (segment (start 145.160002 141.859998) (end 145.5 141.52) (width 0.2) (layer "F.Cu") (net 266))
  (segment (start 145.5 141.32) (end 145.74 141.08) (width 0.2) (layer "F.Cu") (net 266))
  (segment (start 141.95 144.325) (end 141.95 143.94) (width 0.2) (layer "F.Cu") (net 266))
  (segment (start 141.50137 143.239712) (end 141.22 142.958342) (width 0.2) (layer "F.Cu") (net 266))
  (segment (start 154.2 112.1) (end 154.7 112.6) (width 0.182) (layer "F.Cu") (net 266))
  (segment (start 147.015 142.45) (end 146.745 142.18) (width 0.4) (layer "F.Cu") (net 266))
  (segment (start 145.5 141.52) (end 145.5 141.32) (width 0.2) (layer "F.Cu") (net 266))
  (segment (start 143.134998 141.859998) (end 145.160002 141.859998) (width 0.2) (layer "F.Cu") (net 266))
  (segment (start 141.22 142) (end 141.57 141.65) (width 0.2) (layer "F.Cu") (net 266))
  (segment (start 146.38 141.08) (end 146.745 141.445) (width 0.2) (layer "F.Cu") (net 266))
  (segment (start 141.22 142.958342) (end 141.22 142) (width 0.2) (layer "F.Cu") (net 266))
  (segment (start 141.95 143.94) (end 141.50137 143.49137) (width 0.2) (layer "F.Cu") (net 266))
  (segment (start 141.50137 143.49137) (end 141.50137 143.239712) (width 0.2) (layer "F.Cu") (net 266))
  (segment (start 146.75 143.215) (end 147.015 142.95) (width 0.4) (layer "F.Cu") (net 266))
  (segment (start 141.57 141.65) (end 142.925 141.65) (width 0.2) (layer "F.Cu") (net 266))
  (segment (start 147.015 142.95) (end 147.015 142.45) (width 0.4) (layer "F.Cu") (net 266))
  (segment (start 145.74 141.08) (end 146.38 141.08) (width 0.2) (layer "F.Cu") (net 266))
  (segment (start 146.75 144.325) (end 146.75 143.215) (width 0.4) (layer "F.Cu") (net 266))
  (via (at 154.7 112.6) (size 0.5) (drill 0.15) (layers "F.Cu" "B.Cu") (net 266))
  (via (at 146.745 142.18) (size 0.5) (drill 0.15) (layers "F.Cu" "B.Cu") (net 266))
  (segment (start 154.95 127.825) (end 150.65 132.125) (width 0.4) (layer "In4.Cu") (net 266))
  (segment (start 154.95 112.85) (end 154.95 127.825) (width 0.4) (layer "In4.Cu") (net 266))
  (segment (start 146.745 134.805) (end 146.745 142.18) (width 0.4) (layer "In4.Cu") (net 266))
  (segment (start 150.65 132.125) (end 149.425 132.125) (width 0.4) (layer "In4.Cu") (net 266))
  (segment (start 154.7 112.6) (end 154.95 112.85) (width 0.4) (layer "In4.Cu") (net 266))
  (segment (start 149.425 132.125) (end 146.745 134.805) (width 0.4) (layer "In4.Cu") (net 266))
  (segment (start 151.534911 85.176911) (end 151.534911 84.209683) (width 0.182) (layer "F.Cu") (net 267))
  (segment (start 151.596 85.238) (end 151.534911 85.176911) (width 0.182) (layer "F.Cu") (net 267))
  (segment (start 151.534911 84.209683) (end 151.643911 84.100684) (width 0.182) (layer "F.Cu") (net 267))
  (via (at 151.643911 84.100684) (size 0.45) (drill 0.1) (layers "F.Cu" "B.Cu") (net 267))
  (segment (start 168.183669 74.077205) (end 168.211156 74.099125) (width 0.107) (layer "In6.Cu") (net 267))
  (segment (start 168.411266 73.682547) (end 168.433188 73.655061) (width 0.107) (layer "In6.Cu") (net 267))
  (segment (start 151.89175 83.4965) (end 155.93675 83.4965) (width 0.107) (layer "In6.Cu") (net 267))
  (segment (start 168.396012 73.81793) (end 168.388189 73.783655) (width 0.107) (layer "In6.Cu") (net 267))
  (segment (start 168.471703 74.337684) (end 168.505978 74.345507) (width 0.107) (layer "In6.Cu") (net 267))
  (segment (start 165.18675 74.2465) (end 167.84175 74.2465) (width 0.107) (layer "In6.Cu") (net 267))
  (segment (start 168.388189 73.748498) (end 168.396012 73.714222) (width 0.107) (layer "In6.Cu") (net 267))
  (segment (start 168.016611 74.077205) (end 168.048286 74.061951) (width 0.107) (layer "In6.Cu") (net 267))
  (segment (start 168.671745 74.13764) (end 168.656491 74.105965) (width 0.107) (layer "In6.Cu") (net 267))
  (segment (start 168.8 71.2) (end 169.1 71.2) (width 0.109) (layer "In6.Cu") (net 267))
  (segment (start 168.396012 73.714222) (end 168.411266 73.682547) (width 0.107) (layer "In6.Cu") (net 267))
  (segment (start 168.117719 74.054127) (end 168.151994 74.061951) (width 0.107) (layer "In6.Cu") (net 267))
  (segment (start 168.6715 71.3285) (end 168.8 71.2) (width 0.109) (layer "In6.Cu") (net 267))
  (segment (start 168.656491 74.105965) (end 168.634572 74.078478) (width 0.107) (layer "In6.Cu") (net 267))
  (segment (start 168.048286 74.061951) (end 168.082562 74.054127) (width 0.107) (layer "In6.Cu") (net 267))
  (segment (start 168.211156 74.099125) (end 168.412541 74.30051) (width 0.107) (layer "In6.Cu") (net 267))
  (segment (start 151.643911 84.100684) (end 151.567411 84.024184) (width 0.107) (layer "In6.Cu") (net 267))
  (segment (start 168.679569 74.171915) (end 168.671745 74.13764) (width 0.107) (layer "In6.Cu") (net 267))
  (segment (start 168.433188 73.655061) (end 168.6715 73.41675) (width 0.107) (layer "In6.Cu") (net 267))
  (segment (start 168.412541 74.30051) (end 168.440028 74.32243) (width 0.107) (layer "In6.Cu") (net 267))
  (segment (start 168.433186 73.877092) (end 168.411266 73.849605) (width 0.107) (layer "In6.Cu") (net 267))
  (segment (start 155.93675 83.4965) (end 165.18675 74.2465) (width 0.107) (layer "In6.Cu") (net 267))
  (segment (start 167.989125 74.099125) (end 168.016611 74.077205) (width 0.107) (layer "In6.Cu") (net 267))
  (segment (start 151.567411 83.820839) (end 151.89175 83.4965) (width 0.107) (layer "In6.Cu") (net 267))
  (segment (start 168.411266 73.849605) (end 168.396012 73.81793) (width 0.107) (layer "In6.Cu") (net 267))
  (segment (start 169.1 71.2) (end 169.7 71.8) (width 0.109) (layer "In6.Cu") (net 267))
  (segment (start 168.541135 74.345507) (end 168.575411 74.337684) (width 0.107) (layer "In6.Cu") (net 267))
  (segment (start 168.575411 74.337684) (end 168.607086 74.32243) (width 0.107) (layer "In6.Cu") (net 267))
  (segment (start 168.440028 74.32243) (end 168.471703 74.337684) (width 0.107) (layer "In6.Cu") (net 267))
  (segment (start 168.151994 74.061951) (end 168.183669 74.077205) (width 0.107) (layer "In6.Cu") (net 267))
  (segment (start 151.567411 84.024184) (end 151.567411 83.820839) (width 0.107) (layer "In6.Cu") (net 267))
  (segment (start 168.6715 73.41675) (end 168.6715 71.3285) (width 0.109) (layer "In6.Cu") (net 267))
  (segment (start 168.505978 74.345507) (end 168.541135 74.345507) (width 0.107) (layer "In6.Cu") (net 267))
  (segment (start 167.84175 74.2465) (end 167.989125 74.099125) (width 0.107) (layer "In6.Cu") (net 267))
  (segment (start 168.388189 73.783655) (end 168.388189 73.748498) (width 0.107) (layer "In6.Cu") (net 267))
  (segment (start 168.671745 74.241348) (end 168.679569 74.207072) (width 0.107) (layer "In6.Cu") (net 267))
  (segment (start 168.679569 74.207072) (end 168.679569 74.171915) (width 0.107) (layer "In6.Cu") (net 267))
  (segment (start 168.656491 74.273023) (end 168.671745 74.241348) (width 0.107) (layer "In6.Cu") (net 267))
  (segment (start 168.634572 74.30051) (end 168.656491 74.273023) (width 0.107) (layer "In6.Cu") (net 267))
  (segment (start 168.634572 74.078478) (end 168.433186 73.877092) (width 0.107) (layer "In6.Cu") (net 267))
  (segment (start 168.607086 74.32243) (end 168.634572 74.30051) (width 0.107) (layer "In6.Cu") (net 267))
  (segment (start 168.082562 74.054127) (end 168.117719 74.054127) (width 0.107) (layer "In6.Cu") (net 267))
  (segment (start 151.15691 84.209683) (end 151.047911 84.100684) (width 0.182) (layer "F.Cu") (net 268))
  (segment (start 151.15691 85.17709) (end 151.15691 84.209683) (width 0.182) (layer "F.Cu") (net 268))
  (segment (start 151.096 85.238) (end 151.15691 85.17709) (width 0.182) (layer "F.Cu") (net 268))
  (via (at 151.047911 84.100684) (size 0.45) (drill 0.1) (layers "F.Cu" "B.Cu") (net 268))
  (segment (start 168.555875 70.605875) (end 168.2285 70.93325) (width 0.107) (layer "In6.Cu") (net 268))
  (segment (start 165.00325 73.8035) (end 155.75325 83.0535) (width 0.107) (layer "In6.Cu") (net 268))
  (segment (start 151.124411 84.024184) (end 151.047911 84.100684) (width 0.107) (layer "In6.Cu") (net 268))
  (segment (start 151.124411 83.637339) (end 151.124411 84.024184) (width 0.107) (layer "In6.Cu") (net 268))
  (segment (start 151.70825 83.0535) (end 151.124411 83.637339) (width 0.107) (layer "In6.Cu") (net 268))
  (segment (start 167.65825 73.8035) (end 165.00325 73.8035) (width 0.107) (layer "In6.Cu") (net 268))
  (segment (start 168.555875 69.385875) (end 168.43 69.26) (width 0.109) (layer "In6.Cu") (net 268))
  (segment (start 168.2285 73.23325) (end 167.65825 73.8035) (width 0.107) (layer "In6.Cu") (net 268))
  (segment (start 155.75325 83.0535) (end 151.70825 83.0535) (width 0.107) (layer "In6.Cu") (net 268))
  (segment (start 168.555875 70.605875) (end 168.555875 69.385875) (width 0.109) (layer "In6.Cu") (net 268))
  (segment (start 168.2285 70.93325) (end 168.2285 73.23325) (width 0.107) (layer "In6.Cu") (net 268))
  (segment (start 150.034908 84.209684) (end 150.143908 84.100684) (width 0.182) (layer "F.Cu") (net 269))
  (segment (start 150.034908 85.176908) (end 150.034908 84.209684) (width 0.182) (layer "F.Cu") (net 269))
  (segment (start 150.096 85.238) (end 150.034908 85.176908) (width 0.182) (layer "F.Cu") (net 269))
  (via (at 150.143908 84.100684) (size 0.45) (drill 0.1) (layers "F.Cu" "B.Cu") (net 269))
  (segment (start 162.546939 74.243057) (end 162.160505 73.856623) (width 0.107) (layer "In6.Cu") (net 269))
  (segment (start 165.960874 72.579074) (end 165.938333 72.532267) (width 0.107) (layer "In6.Cu") (net 269))
  (segment (start 162.160505 73.710253) (end 162.20576 73.664999) (width 0.107) (layer "In6.Cu") (net 269))
  (segment (start 163.103284 74.958277) (end 163.077627 74.845861) (width 0.107) (layer "In6.Cu") (net 269))
  (segment (start 161.95863 75.290993) (end 162.115254 75.447617) (width 0.107) (layer "In6.Cu") (net 269))
  (segment (start 165.905942 72.49165) (end 165.896193 72.481901) (width 0.107) (layer "In6.Cu") (net 269))
  (segment (start 150.143908 84.100684) (end 150.067408 84.024184) (width 0.107) (layer "In6.Cu") (net 269))
  (segment (start 154.906753 82.196497) (end 160.927612 76.175638) (width 0.107) (layer "In6.Cu") (net 269))
  (segment (start 165.829701 72.343828) (end 165.829701 72.291877) (width 0.107) (layer "In6.Cu") (net 269))
  (segment (start 162.559341 75.617526) (end 162.671755 75.591869) (width 0.107) (layer "In6.Cu") (net 269))
  (segment (start 162.725122 73.965875) (end 162.837537 73.991533) (width 0.107) (layer "In6.Cu") (net 269))
  (segment (start 161.897032 75.26133) (end 161.919628 75.266487) (width 0.107) (layer "In6.Cu") (net 269))
  (segment (start 165.280617 72.777608) (end 165.327424 72.755067) (width 0.107) (layer "In6.Cu") (net 269))
  (segment (start 162.313128 73.640493) (end 162.33401 73.650548) (width 0.107) (layer "In6.Cu") (net 269))
  (segment (start 162.531085 73.843954) (end 162.621235 73.915846) (width 0.107) (layer "In6.Cu") (net 269))
  (segment (start 162.621235 73.915846) (end 162.725122 73.965875) (width 0.107) (layer "In6.Cu") (net 269))
  (segment (start 162.20576 73.664999) (end 162.22388 73.650548) (width 0.107) (layer "In6.Cu") (net 269))
  (segment (start 162.267357 73.635335) (end 162.290533 73.635335) (width 0.107) (layer "In6.Cu") (net 269))
  (segment (start 162.952843 73.991533) (end 163.065258 73.965875) (width 0.107) (layer "In6.Cu") (net 269))
  (segment (start 162.955704 74.651825) (end 162.933376 74.629494) (width 0.107) (layer "In6.Cu") (net 269))
  (segment (start 162.146054 73.838503) (end 162.135999 73.817622) (width 0.107) (layer "In6.Cu") (net 269))
  (segment (start 165.378073 72.743507) (end 165.430024 72.743507) (width 0.107) (layer "In6.Cu") (net 269))
  (segment (start 162.620126 74.316244) (end 162.54694 74.243061) (width 0.107) (layer "In6.Cu") (net 269))
  (segment (start 165.972434 72.681674) (end 165.972434 72.629723) (width 0.107) (layer "In6.Cu") (net 269))
  (segment (start 165.327424 72.755067) (end 165.378073 72.743507) (width 0.107) (layer "In6.Cu") (net 269))
  (segment (start 161.81226 75.290993) (end 161.830379 75.276543) (width 0.107) (layer "In6.Cu") (net 269))
  (segment (start 162.160505 73.856623) (end 162.146054 73.838503) (width 0.107) (layer "In6.Cu") (net 269))
  (segment (start 162.244761 73.640493) (end 162.267357 73.635335) (width 0.107) (layer "In6.Cu") (net 269))
  (segment (start 162.955706 75.380033) (end 163.027598 75.289884) (width 0.107) (layer "In6.Cu") (net 269))
  (segment (start 162.33401 73.650548) (end 162.35213 73.664999) (width 0.107) (layer "In6.Cu") (net 269))
  (segment (start 154.906753 82.1965) (end 154.906753 82.196497) (width 0.107) (layer "In6.Cu") (net 269))
  (segment (start 165.829701 72.291877) (end 165.841261 72.241228) (width 0.107) (layer "In6.Cu") (net 269))
  (segment (start 162.290533 73.635335) (end 162.313128 73.640493) (width 0.107) (layer "In6.Cu") (net 269))
  (segment (start 162.837537 73.991533) (end 162.952843 73.991533) (width 0.107) (layer "In6.Cu") (net 269))
  (segment (start 165.863802 72.441284) (end 165.841261 72.394477) (width 0.107) (layer "In6.Cu") (net 269))
  (segment (start 163.78825 72.95) (end 165.100001 72.949999) (width 0.107) (layer "In6.Cu") (net 269))
  (segment (start 161.940509 75.276543) (end 161.95863 75.290993) (width 0.107) (layer "In6.Cu") (net 269))
  (segment (start 165.577845 72.819748) (end 165.618462 72.852139) (width 0.107) (layer "In6.Cu") (net 269))
  (segment (start 161.919628 75.266487) (end 161.940509 75.276543) (width 0.107) (layer "In6.Cu") (net 269))
  (segment (start 163.027598 74.741974) (end 162.955704 74.651825) (width 0.107) (layer "In6.Cu") (net 269))
  (segment (start 163.5715 73.16675) (end 163.78825 72.95) (width 0.107) (layer "In6.Cu") (net 269))
  (segment (start 162.671755 75.591869) (end 162.775642 75.54184) (width 0.107) (layer "In6.Cu") (net 269))
  (segment (start 165.52748 72.777608) (end 165.568097 72.81) (width 0.107) (layer "In6.Cu") (net 269))
  (segment (start 161.85126 75.266488) (end 161.873856 75.26133) (width 0.107) (layer "In6.Cu") (net 269))
  (segment (start 162.54694 74.243061) (end 162.546939 74.243057) (width 0.107) (layer "In6.Cu") (net 269))
  (segment (start 165.905942 72.819748) (end 165.938333 72.77913) (width 0.107) (layer "In6.Cu") (net 269))
  (segment (start 165.863802 72.194421) (end 165.896195 72.153804) (width 0.107) (layer "In6.Cu") (net 269))
  (segment (start 165.938333 72.532267) (end 165.905942 72.49165) (width 0.107) (layer "In6.Cu") (net 269))
  (segment (start 162.933376 74.629494) (end 162.620126 74.316244) (width 0.107) (layer "In6.Cu") (net 269))
  (segment (start 163.5715 73.53175) (end 163.5715 73.16675) (width 0.107) (layer "In6.Cu") (net 269))
  (segment (start 165.665269 72.87468) (end 165.715918 72.88624) (width 0.107) (layer "In6.Cu") (net 269))
  (segment (start 166.25 71.8) (end 167.16 71.8) (width 0.107) (layer "In6.Cu") (net 269))
  (segment (start 165.24 72.81) (end 165.280617 72.777608) (width 0.107) (layer "In6.Cu") (net 269))
  (segment (start 162.135999 73.749255) (end 162.146054 73.728373) (width 0.107) (layer "In6.Cu") (net 269))
  (segment (start 162.775642 75.54184) (end 162.865792 75.469948) (width 0.107) (layer "In6.Cu") (net 269))
  (segment (start 165.972434 72.629723) (end 165.960874 72.579074) (width 0.107) (layer "In6.Cu") (net 269))
  (segment (start 162.135999 73.817622) (end 162.130841 73.795026) (width 0.107) (layer "In6.Cu") (net 269))
  (segment (start 165.430024 72.743507) (end 165.480673 72.755067) (width 0.107) (layer "In6.Cu") (net 269))
  (segment (start 163.027598 75.289884) (end 163.077627 75.185997) (width 0.107) (layer "In6.Cu") (net 269))
  (segment (start 161.873856 75.26133) (end 161.897032 75.26133) (width 0.107) (layer "In6.Cu") (net 269))
  (segment (start 165.841261 72.394477) (end 165.829701 72.343828) (width 0.107) (layer "In6.Cu") (net 269))
  (segment (start 162.130841 73.77185) (end 162.135999 73.749255) (width 0.107) (layer "In6.Cu") (net 269))
  (segment (start 163.169145 73.915846) (end 163.259295 73.843954) (width 0.107) (layer "In6.Cu") (net 269))
  (segment (start 150.067408 83.420842) (end 151.29175 82.1965) (width 0.107) (layer "In6.Cu") (net 269))
  (segment (start 162.115254 75.447617) (end 162.137582 75.469948) (width 0.107) (layer "In6.Cu") (net 269))
  (segment (start 165.896195 72.153804) (end 166.25 71.8) (width 0.107) (layer "In6.Cu") (net 269))
  (segment (start 163.077627 74.845861) (end 163.027598 74.741974) (width 0.107) (layer "In6.Cu") (net 269))
  (segment (start 163.259295 73.843954) (end 163.5715 73.53175) (width 0.107) (layer "In6.Cu") (net 269))
  (segment (start 165.480673 72.755067) (end 165.52748 72.777608) (width 0.107) (layer "In6.Cu") (net 269))
  (segment (start 163.103284 75.073583) (end 163.103284 74.958277) (width 0.107) (layer "In6.Cu") (net 269))
  (segment (start 165.841261 72.241228) (end 165.863802 72.194421) (width 0.107) (layer "In6.Cu") (net 269))
  (segment (start 165.938333 72.77913) (end 165.960874 72.732323) (width 0.107) (layer "In6.Cu") (net 269))
  (segment (start 165.715918 72.88624) (end 165.767869 72.88624) (width 0.107) (layer "In6.Cu") (net 269))
  (segment (start 165.818518 72.87468) (end 165.865325 72.852139) (width 0.107) (layer "In6.Cu") (net 269))
  (segment (start 163.065258 73.965875) (end 163.169145 73.915846) (width 0.107) (layer "In6.Cu") (net 269))
  (segment (start 162.35213 73.664999) (end 162.531085 73.843954) (width 0.107) (layer "In6.Cu") (net 269))
  (segment (start 150.067408 84.024184) (end 150.067408 83.420842) (width 0.107) (layer "In6.Cu") (net 269))
  (segment (start 165.100001 72.949999) (end 165.24 72.81) (width 0.107) (layer "In6.Cu") (net 269))
  (segment (start 151.29175 82.1965) (end 154.906753 82.1965) (width 0.107) (layer "In6.Cu") (net 269))
  (segment (start 165.568097 72.81) (end 165.577845 72.819748) (width 0.107) (layer "In6.Cu") (net 269))
  (segment (start 160.927612 76.175638) (end 161.81226 75.290993) (width 0.107) (layer "In6.Cu") (net 269))
  (segment (start 165.767869 72.88624) (end 165.818518 72.87468) (width 0.107) (layer "In6.Cu") (net 269))
  (segment (start 162.130841 73.795026) (end 162.130841 73.77185) (width 0.107) (layer "In6.Cu") (net 269))
  (segment (start 162.137582 75.469948) (end 162.227732 75.54184) (width 0.107) (layer "In6.Cu") (net 269))
  (segment (start 162.444035 75.617526) (end 162.559341 75.617526) (width 0.107) (layer "In6.Cu") (net 269))
  (segment (start 161.830379 75.276543) (end 161.85126 75.266488) (width 0.107) (layer "In6.Cu") (net 269))
  (segment (start 162.331619 75.591869) (end 162.444035 75.617526) (width 0.107) (layer "In6.Cu") (net 269))
  (segment (start 162.227732 75.54184) (end 162.331619 75.591869) (width 0.107) (layer "In6.Cu") (net 269))
  (segment (start 165.865325 72.852139) (end 165.905942 72.819748) (width 0.107) (layer "In6.Cu") (net 269))
  (segment (start 165.896193 72.481901) (end 165.863802 72.441284) (width 0.107) (layer "In6.Cu") (net 269))
  (segment (start 163.077627 75.185997) (end 163.103284 75.073583) (width 0.107) (layer "In6.Cu") (net 269))
  (segment (start 162.146054 73.728373) (end 162.160505 73.710253) (width 0.107) (layer "In6.Cu") (net 269))
  (segment (start 165.960874 72.732323) (end 165.972434 72.681674) (width 0.107) (layer "In6.Cu") (net 269))
  (segment (start 165.618462 72.852139) (end 165.665269 72.87468) (width 0.107) (layer "In6.Cu") (net 269))
  (segment (start 162.865792 75.469948) (end 162.955706 75.380033) (width 0.107) (layer "In6.Cu") (net 269))
  (segment (start 162.22388 73.650548) (end 162.244761 73.640493) (width 0.107) (layer "In6.Cu") (net 269))
  (segment (start 149.656907 85.177093) (end 149.656907 84.209684) (width 0.182) (layer "F.Cu") (net 270))
  (segment (start 149.656907 84.209684) (end 149.547907 84.100684) (width 0.182) (layer "F.Cu") (net 270))
  (segment (start 149.596 85.238) (end 149.656907 85.177093) (width 0.182) (layer "F.Cu") (net 270))
  (via (at 149.547907 84.100684) (size 0.45) (drill 0.1) (layers "F.Cu" "B.Cu") (net 270))
  (segment (start 161.611489 74.883522) (end 161.521339 74.955414) (width 0.107) (layer "In6.Cu") (net 270))
  (segment (start 161.892511 73.35175) (end 161.824926 73.419334) (width 0.107) (layer "In6.Cu") (net 270))
  (segment (start 161.715376 74.833493) (end 161.611489 74.883522) (width 0.107) (layer "In6.Cu") (net 270))
  (segment (start 162.64305 73.32942) (end 162.5529 73.257528) (width 0.107) (layer "In6.Cu") (net 270))
  (segment (start 162.649791 75.00434) (end 162.649791 75.027516) (width 0.107) (layer "In6.Cu") (net 270))
  (segment (start 161.677347 73.725786) (end 161.677347 73.841092) (width 0.107) (layer "In6.Cu") (net 270))
  (segment (start 162.249549 74.955414) (end 162.159399 74.883522) (width 0.107) (layer "In6.Cu") (net 270))
  (segment (start 162.968375 73.508375) (end 162.950255 73.522825) (width 0.107) (layer "In6.Cu") (net 270))
  (segment (start 162.634576 74.960864) (end 162.644633 74.981744) (width 0.107) (layer "In6.Cu") (net 270))
  (segment (start 162.535871 75.158874) (end 162.513275 75.164033) (width 0.107) (layer "In6.Cu") (net 270))
  (segment (start 162.00499 73.257528) (end 161.91484 73.32942) (width 0.107) (layer "In6.Cu") (net 270))
  (segment (start 162.5529 73.257528) (end 162.449013 73.207499) (width 0.107) (layer "In6.Cu") (net 270))
  (segment (start 162.883602 73.538038) (end 162.861006 73.532881) (width 0.107) (layer "In6.Cu") (net 270))
  (segment (start 163.1285 73.34825) (end 162.968375 73.508375) (width 0.107) (layer "In6.Cu") (net 270))
  (segment (start 149.624408 84.024184) (end 149.547908 84.100684) (width 0.107) (layer "In6.Cu") (net 270))
  (segment (start 161.824926 74.147544) (end 161.847256 74.169873) (width 0.107) (layer "In6.Cu") (net 270))
  (segment (start 161.521339 74.955414) (end 161.499009 74.977745) (width 0.107) (layer "In6.Cu") (net 270))
  (segment (start 162.644632 75.050112) (end 162.634576 75.070994) (width 0.107) (layer "In6.Cu") (net 270))
  (segment (start 161.703005 73.953507) (end 161.753034 74.057394) (width 0.107) (layer "In6.Cu") (net 270))
  (segment (start 162.336598 73.181841) (end 162.221292 73.181841) (width 0.107) (layer "In6.Cu") (net 270))
  (segment (start 162.634576 75.070994) (end 162.620126 75.089114) (width 0.107) (layer "In6.Cu") (net 270))
  (segment (start 162.556752 75.14882) (end 162.535871 75.158874) (width 0.107) (layer "In6.Cu") (net 270))
  (segment (start 162.574873 75.134368) (end 162.556752 75.14882) (width 0.107) (layer "In6.Cu") (net 270))
  (segment (start 162.649791 75.027516) (end 162.644632 75.050112) (width 0.107) (layer "In6.Cu") (net 270))
  (segment (start 162.840125 73.522825) (end 162.822005 73.508375) (width 0.107) (layer "In6.Cu") (net 270))
  (segment (start 149.547908 84.100684) (end 149.547907 84.100684) (width 0.107) (layer "In6.Cu") (net 270))
  (segment (start 162.055512 74.833493) (end 161.943096 74.807836) (width 0.107) (layer "In6.Cu") (net 270))
  (segment (start 163.35 69.26) (end 164.2 70.11) (width 0.109) (layer "In6.Cu") (net 270))
  (segment (start 164.2 70.6) (end 163.55 71.25) (width 0.109) (layer "In6.Cu") (net 270))
  (segment (start 163.1285 72.98325) (end 163.1285 73.34825) (width 0.107) (layer "In6.Cu") (net 270))
  (segment (start 161.847256 74.169873) (end 162.620126 74.942744) (width 0.107) (layer "In6.Cu") (net 270))
  (segment (start 160.614362 75.862388) (end 154.723253 81.753497) (width 0.107) (layer "In6.Cu") (net 270))
  (segment (start 162.906778 73.538038) (end 162.883602 73.538038) (width 0.107) (layer "In6.Cu") (net 270))
  (segment (start 161.753034 74.057394) (end 161.824926 74.147544) (width 0.107) (layer "In6.Cu") (net 270))
  (segment (start 161.82779 74.807836) (end 161.715376 74.833493) (width 0.107) (layer "In6.Cu") (net 270))
  (segment (start 162.620126 74.942744) (end 162.634576 74.960864) (width 0.107) (layer "In6.Cu") (net 270))
  (segment (start 161.824926 73.419334) (end 161.753034 73.509484) (width 0.107) (layer "In6.Cu") (net 270))
  (segment (start 161.677347 73.841092) (end 161.703005 73.953507) (width 0.107) (layer "In6.Cu") (net 270))
  (segment (start 163.55 71.25) (end 163.55 72.56175) (width 0.107) (layer "In6.Cu") (net 270))
  (segment (start 149.624408 83.237342) (end 149.624408 84.024184) (width 0.107) (layer "In6.Cu") (net 270))
  (segment (start 162.446622 75.14882) (end 162.428503 75.134368) (width 0.107) (layer "In6.Cu") (net 270))
  (segment (start 162.159399 74.883522) (end 162.055512 74.833493) (width 0.107) (layer "In6.Cu") (net 270))
  (segment (start 161.703005 73.613371) (end 161.677347 73.725786) (width 0.107) (layer "In6.Cu") (net 270))
  (segment (start 162.950255 73.522825) (end 162.929373 73.532881) (width 0.107) (layer "In6.Cu") (net 270))
  (segment (start 162.108877 73.207499) (end 162.00499 73.257528) (width 0.107) (layer "In6.Cu") (net 270))
  (segment (start 162.822005 73.508375) (end 162.64305 73.32942) (width 0.107) (layer "In6.Cu") (net 270))
  (segment (start 162.449013 73.207499) (end 162.336598 73.181841) (width 0.107) (layer "In6.Cu") (net 270))
  (segment (start 162.620126 75.089114) (end 162.574873 75.134368) (width 0.107) (layer "In6.Cu") (net 270))
  (segment (start 162.929373 73.532881) (end 162.906778 73.538038) (width 0.107) (layer "In6.Cu") (net 270))
  (segment (start 162.490099 75.164033) (end 162.467503 75.158875) (width 0.107) (layer "In6.Cu") (net 270))
  (segment (start 162.221292 73.181841) (end 162.108877 73.207499) (width 0.107) (layer "In6.Cu") (net 270))
  (segment (start 162.513275 75.164033) (end 162.490099 75.164033) (width 0.107) (layer "In6.Cu") (net 270))
  (segment (start 161.91484 73.32942) (end 161.892511 73.35175) (width 0.107) (layer "In6.Cu") (net 270))
  (segment (start 162.644633 74.981744) (end 162.649791 75.00434) (width 0.107) (layer "In6.Cu") (net 270))
  (segment (start 151.10825 81.7535) (end 149.624408 83.237342) (width 0.107) (layer "In6.Cu") (net 270))
  (segment (start 162.428503 75.134368) (end 162.249549 74.955414) (width 0.107) (layer "In6.Cu") (net 270))
  (segment (start 161.753034 73.509484) (end 161.703005 73.613371) (width 0.107) (layer "In6.Cu") (net 270))
  (segment (start 161.499009 74.977745) (end 160.614362 75.862388) (width 0.107) (layer "In6.Cu") (net 270))
  (segment (start 162.861006 73.532881) (end 162.840125 73.522825) (width 0.107) (layer "In6.Cu") (net 270))
  (segment (start 163.55 72.56175) (end 163.1285 72.98325) (width 0.107) (layer "In6.Cu") (net 270))
  (segment (start 162.467503 75.158875) (end 162.446622 75.14882) (width 0.107) (layer "In6.Cu") (net 270))
  (segment (start 154.723253 81.7535) (end 151.10825 81.7535) (width 0.107) (layer "In6.Cu") (net 270))
  (segment (start 154.723253 81.753497) (end 154.723253 81.7535) (width 0.107) (layer "In6.Cu") (net 270))
  (segment (start 164.2 70.11) (end 164.2 70.6) (width 0.109) (layer "In6.Cu") (net 270))
  (segment (start 161.943096 74.807836) (end 161.82779 74.807836) (width 0.107) (layer "In6.Cu") (net 270))
  (segment (start 148.534909 85.174909) (end 148.534909 84.209683) (width 0.182) (layer "F.Cu") (net 271))
  (segment (start 148.598 85.238) (end 148.534909 85.174909) (width 0.182) (layer "F.Cu") (net 271))
  (segment (start 148.534909 84.209683) (end 148.643909 84.100684) (width 0.182) (layer "F.Cu") (net 271))
  (via (at 148.643909 84.100684) (size 0.45) (drill 0.1) (layers "F.Cu" "B.Cu") (net 271))
  (segment (start 161.169125 71.069125) (end 161.349125 71.069125) (width 0.109) (layer "In6.Cu") (net 271))
  (segment (start 159.325473 73.298889) (end 159.348832 73.304221) (width 0.107) (layer "In6.Cu") (net 271))
  (segment (start 160.410952 75.639838) (end 160.501679 75.567485) (width 0.107) (layer "In6.Cu") (net 271))
  (segment (start 160.378403 74.158915) (end 160.494447 74.158915) (width 0.107) (layer "In6.Cu") (net 271))
  (segment (start 159.564213 75.366686) (end 159.582946 75.381625) (width 0.107) (layer "In6.Cu") (net 271))
  (segment (start 161.3607 73.169605) (end 161.418825 73.149266) (width 0.107) (layer "In6.Cu") (net 271))
  (segment (start 161.299507 73.1765) (end 161.3607 73.169605) (width 0.107) (layer "In6.Cu") (net 271))
  (segment (start 161.048733 72.470818) (end 161.028394 72.412693) (width 0.107) (layer "In6.Cu") (net 271))
  (segment (start 160.069989 74.010391) (end 160.160715 74.082744) (width 0.107) (layer "In6.Cu") (net 271))
  (segment (start 160.193265 75.71601) (end 160.3064 75.690187) (width 0.107) (layer "In6.Cu") (net 271))
  (segment (start 159.519265 75.350958) (end 159.542625 75.35629) (width 0.107) (layer "In6.Cu") (net 271))
  (segment (start 161.028394 73.390306) (end 161.048733 73.332181) (width 0.107) (layer "In6.Cu") (net 271))
  (segment (start 148.643909 84.100684) (end 148.567409 84.024184) (width 0.107) (layer "In6.Cu") (net 271))
  (segment (start 161.567612 72.840306) (end 161.547273 72.782181) (width 0.107) (layer "In6.Cu") (net 271))
  (segment (start 161.235306 72.619605) (end 161.177181 72.599266) (width 0.107) (layer "In6.Cu") (net 271))
  (segment (start 159.207165 73.417195) (end 159.207165 73.393235) (width 0.107) (layer "In6.Cu") (net 271))
  (segment (start 161.470966 73.116503) (end 161.51451 73.072959) (width 0.107) (layer "In6.Cu") (net 271))
  (segment (start 161.028394 72.412693) (end 161.0215 72.3515) (width 0.107) (layer "In6.Cu") (net 271))
  (segment (start 160.695147 75.214126) (end 160.695147 75.098082) (width 0.107) (layer "In6.Cu") (net 271))
  (segment (start 160.501679 75.567485) (end 160.546623 75.52254) (width 0.107) (layer "In6.Cu") (net 271))
  (segment (start 161.0215 71.21675) (end 161.169125 71.069125) (width 0.107) (layer "In6.Cu") (net 271))
  (segment (start 159.471945 75.35629) (end 159.495305 75.350958) (width 0.107) (layer "In6.Cu") (net 271))
  (segment (start 159.278152 73.304221) (end 159.301513 73.298889) (width 0.107) (layer "In6.Cu") (net 271))
  (segment (start 161.12504 73.236496) (end 161.177181 73.203733) (width 0.107) (layer "In6.Cu") (net 271))
  (segment (start 159.495305 75.350958) (end 159.519265 75.350958) (width 0.107) (layer "In6.Cu") (net 271))
  (segment (start 160.618975 75.431813) (end 160.669325 75.327261) (width 0.107) (layer "In6.Cu") (net 271))
  (segment (start 161.081496 72.522959) (end 161.048733 72.470818) (width 0.107) (layer "In6.Cu") (net 271))
  (segment (start 160.669325 75.327261) (end 160.695147 75.214126) (width 0.107) (layer "In6.Cu") (net 271))
  (segment (start 161.12504 72.566503) (end 161.081496 72.522959) (width 0.107) (layer "In6.Cu") (net 271))
  (segment (start 161.0215 72.3515) (end 161.0215 71.21675) (width 0.107) (layer "In6.Cu") (net 271))
  (segment (start 160.669325 74.984947) (end 160.618975 74.880395) (width 0.107) (layer "In6.Cu") (net 271))
  (segment (start 161.235306 73.183394) (end 161.2965 73.1765) (width 0.107) (layer "In6.Cu") (net 271))
  (segment (start 161.567612 72.962693) (end 161.574507 72.9015) (width 0.107) (layer "In6.Cu") (net 271))
  (segment (start 159.37042 73.314616) (end 159.389153 73.329555) (width 0.107) (layer "In6.Cu") (net 271))
  (segment (start 161.547273 73.020818) (end 161.567612 72.962693) (width 0.107) (layer "In6.Cu") (net 271))
  (segment (start 161.048733 73.332181) (end 161.054725 73.322646) (width 0.107) (layer "In6.Cu") (net 271))
  (segment (start 161.2965 73.1765) (end 161.299507 73.1765) (width 0.107) (layer "In6.Cu") (net 271))
  (segment (start 148.567409 83.170841) (end 150.84175 80.8965) (width 0.107) (layer "In6.Cu") (net 271))
  (segment (start 159.212497 73.369875) (end 159.222892 73.348289) (width 0.107) (layer "In6.Cu") (net 271))
  (segment (start 160.607581 74.133094) (end 160.712135 74.082743) (width 0.107) (layer "In6.Cu") (net 271))
  (segment (start 160.712135 74.082743) (end 160.802861 74.010392) (width 0.107) (layer "In6.Cu") (net 271))
  (segment (start 161.0215 73.791752) (end 161.0215 73.4515) (width 0.107) (layer "In6.Cu") (net 271))
  (segment (start 161.418825 72.653733) (end 161.3607 72.633394) (width 0.107) (layer "In6.Cu") (net 271))
  (segment (start 161.51451 72.73004) (end 161.470966 72.686496) (width 0.107) (layer "In6.Cu") (net 271))
  (segment (start 159.348832 73.304221) (end 159.37042 73.314616) (width 0.107) (layer "In6.Cu") (net 271))
  (segment (start 159.542625 75.35629) (end 159.564213 75.366686) (width 0.107) (layer "In6.Cu") (net 271))
  (segment (start 150.84175 80.8965) (end 153.916752 80.8965) (width 0.107) (layer "In6.Cu") (net 271))
  (segment (start 160.546623 74.789667) (end 159.237832 73.480876) (width 0.107) (layer "In6.Cu") (net 271))
  (segment (start 160.546623 75.52254) (end 160.618975 75.431813) (width 0.107) (layer "In6.Cu") (net 271))
  (segment (start 159.859533 75.639838) (end 159.964086 75.690187) (width 0.107) (layer "In6.Cu") (net 271))
  (segment (start 160.160715 74.082744) (end 160.265267 74.133094) (width 0.107) (layer "In6.Cu") (net 271))
  (segment (start 159.389153 73.329555) (end 160.069989 74.010391) (width 0.107) (layer "In6.Cu") (net 271))
  (segment (start 153.916752 80.8965) (end 159.431625 75.381625) (width 0.107) (layer "In6.Cu") (net 271))
  (segment (start 160.3064 75.690187) (end 160.410952 75.639838) (width 0.107) (layer "In6.Cu") (net 271))
  (segment (start 160.618975 74.880395) (end 160.546623 74.789667) (width 0.107) (layer "In6.Cu") (net 271))
  (segment (start 161.418825 73.149266) (end 161.470966 73.116503) (width 0.107) (layer "In6.Cu") (net 271))
  (segment (start 161.547273 72.782181) (end 161.51451 72.73004) (width 0.107) (layer "In6.Cu") (net 271))
  (segment (start 161.177181 73.203733) (end 161.235306 73.183394) (width 0.107) (layer "In6.Cu") (net 271))
  (segment (start 161.470966 72.686496) (end 161.418825 72.653733) (width 0.107) (layer "In6.Cu") (net 271))
  (segment (start 161.2965 72.6265) (end 161.235306 72.619605) (width 0.107) (layer "In6.Cu") (net 271))
  (segment (start 160.802861 74.010392) (end 161.0215 73.791752) (width 0.107) (layer "In6.Cu") (net 271))
  (segment (start 159.212497 73.440555) (end 159.207165 73.417195) (width 0.107) (layer "In6.Cu") (net 271))
  (segment (start 159.301513 73.298889) (end 159.325473 73.298889) (width 0.107) (layer "In6.Cu") (net 271))
  (segment (start 161.0215 73.4515) (end 161.028394 73.390306) (width 0.107) (layer "In6.Cu") (net 271))
  (segment (start 161.177181 72.599266) (end 161.12504 72.566503) (width 0.107) (layer "In6.Cu") (net 271))
  (segment (start 161.3607 72.633394) (end 161.299507 72.6265) (width 0.107) (layer "In6.Cu") (net 271))
  (segment (start 159.582946 75.381625) (end 159.768806 75.567485) (width 0.107) (layer "In6.Cu") (net 271))
  (segment (start 159.222892 73.348289) (end 159.237831 73.329556) (width 0.107) (layer "In6.Cu") (net 271))
  (segment (start 159.768806 75.567485) (end 159.859533 75.639838) (width 0.107) (layer "In6.Cu") (net 271))
  (segment (start 160.494447 74.158915) (end 160.607581 74.133094) (width 0.107) (layer "In6.Cu") (net 271))
  (segment (start 161.054725 73.322646) (end 161.081496 73.28004) (width 0.107) (layer "In6.Cu") (net 271))
  (segment (start 159.431625 75.381625) (end 159.450358 75.366686) (width 0.107) (layer "In6.Cu") (net 271))
  (segment (start 159.237832 73.480876) (end 159.222893 73.462143) (width 0.107) (layer "In6.Cu") (net 271))
  (segment (start 160.07722 75.71601) (end 160.193265 75.71601) (width 0.107) (layer "In6.Cu") (net 271))
  (segment (start 159.207165 73.393235) (end 159.212497 73.369875) (width 0.107) (layer "In6.Cu") (net 271))
  (segment (start 159.256564 73.314617) (end 159.278152 73.304221) (width 0.107) (layer "In6.Cu") (net 271))
  (segment (start 159.964086 75.690187) (end 160.07722 75.71601) (width 0.107) (layer "In6.Cu") (net 271))
  (segment (start 159.450358 75.366686) (end 159.471945 75.35629) (width 0.107) (layer "In6.Cu") (net 271))
  (segment (start 161.574507 72.9015) (end 161.567612 72.840306) (width 0.107) (layer "In6.Cu") (net 271))
  (segment (start 161.51451 73.072959) (end 161.547273 73.020818) (width 0.107) (layer "In6.Cu") (net 271))
  (segment (start 161.299507 72.6265) (end 161.2965 72.6265) (width 0.107) (layer "In6.Cu") (net 271))
  (segment (start 159.222893 73.462143) (end 159.212497 73.440555) (width 0.107) (layer "In6.Cu") (net 271))
  (segment (start 160.265267 74.133094) (end 160.378403 74.158915) (width 0.107) (layer "In6.Cu") (net 271))
  (segment (start 159.237831 73.329556) (end 159.256564 73.314617) (width 0.107) (layer "In6.Cu") (net 271))
  (segment (start 148.567409 84.024184) (end 148.567409 83.170841) (width 0.107) (layer "In6.Cu") (net 271))
  (segment (start 160.695147 75.098082) (end 160.669325 74.984947) (width 0.107) (layer "In6.Cu") (net 271))
  (segment (start 161.349125 71.069125) (end 162.08 71.8) (width 0.109) (layer "In6.Cu") (net 271))
  (segment (start 161.081496 73.28004) (end 161.12504 73.236496) (width 0.107) (layer "In6.Cu") (net 271))
  (segment (start 148.098 85.238) (end 148.156908 85.179092) (width 0.182) (layer "F.Cu") (net 272))
  (segment (start 148.156908 85.179092) (end 148.156908 84.209683) (width 0.182) (layer "F.Cu") (net 272))
  (segment (start 148.156908 84.209683) (end 148.047908 84.100684) (width 0.182) (layer "F.Cu") (net 272))
  (via (at 148.047908 84.100684) (size 0.45) (drill 0.1) (layers "F.Cu" "B.Cu") (net 272))
  (segment (start 159.782994 74.973551) (end 159.873721 75.045904) (width 0.107) (layer "In6.Cu") (net 272))
  (segment (start 160.19217 75.246703) (end 160.210903 75.231764) (width 0.107) (layer "In6.Cu") (net 272))
  (segment (start 160.123262 75.262431) (end 160.147222 75.262431) (width 0.107) (layer "In6.Cu") (net 272))
  (segment (start 159.255471 72.845311) (end 159.371515 72.845311) (width 0.107) (layer "In6.Cu") (net 272))
  (segment (start 150.65825 80.4535) (end 153.733253 80.4535) (width 0.107) (layer "In6.Cu") (net 272))
  (segment (start 160.512085 73.674672) (end 160.5785 73.608253) (width 0.107) (layer "In6.Cu") (net 272))
  (segment (start 153.733253 80.4535) (end 159.140849 75.045904) (width 0.107) (layer "In6.Cu") (net 272))
  (segment (start 160.147222 75.262431) (end 160.170582 75.257099) (width 0.107) (layer "In6.Cu") (net 272))
  (segment (start 158.947057 72.993835) (end 159.037783 72.921484) (width 0.107) (layer "In6.Cu") (net 272))
  (segment (start 158.902111 73.038779) (end 158.947057 72.993835) (width 0.107) (layer "In6.Cu") (net 272))
  (segment (start 160.236238 75.191443) (end 160.241569 75.168083) (width 0.107) (layer "In6.Cu") (net 272))
  (segment (start 159.484649 72.871134) (end 159.589201 72.921484) (width 0.107) (layer "In6.Cu") (net 272))
  (segment (start 159.873721 75.045904) (end 159.896194 75.068376) (width 0.107) (layer "In6.Cu") (net 272))
  (segment (start 160.210903 75.231764) (end 160.225842 75.213031) (width 0.107) (layer "In6.Cu") (net 272))
  (segment (start 160.225842 75.099176) (end 160.210903 75.080443) (width 0.107) (layer "In6.Cu") (net 272))
  (segment (start 160.401086 73.700006) (end 160.424445 73.705338) (width 0.107) (layer "In6.Cu") (net 272))
  (segment (start 158.779408 73.234059) (end 158.829758 73.129507) (width 0.107) (layer "In6.Cu") (net 272))
  (segment (start 160.078315 75.246703) (end 160.099902 75.257099) (width 0.107) (layer "In6.Cu") (net 272))
  (segment (start 148.047909 84.100684) (end 148.124409 84.024184) (width 0.107) (layer "In6.Cu") (net 272))
  (segment (start 148.124409 84.024184) (end 148.124409 82.987341) (width 0.107) (layer "In6.Cu") (net 272))
  (segment (start 159.140849 75.045904) (end 159.231576 74.973551) (width 0.107) (layer "In6.Cu") (net 272))
  (segment (start 160.805875 70.805875) (end 160.805875 69.264125) (width 0.109) (layer "In6.Cu") (net 272))
  (segment (start 159.565307 74.897379) (end 159.678442 74.923202) (width 0.107) (layer "In6.Cu") (net 272))
  (segment (start 159.371515 72.845311) (end 159.484649 72.871134) (width 0.107) (layer "In6.Cu") (net 272))
  (segment (start 160.225842 75.213031) (end 160.236238 75.191443) (width 0.107) (layer "In6.Cu") (net 272))
  (segment (start 159.142335 72.871134) (end 159.255471 72.845311) (width 0.107) (layer "In6.Cu") (net 272))
  (segment (start 160.448405 73.705338) (end 160.471766 73.700006) (width 0.107) (layer "In6.Cu") (net 272))
  (segment (start 148.047908 84.100684) (end 148.047909 84.100684) (width 0.107) (layer "In6.Cu") (net 272))
  (segment (start 158.82976 73.680923) (end 158.77941 73.576371) (width 0.107) (layer "In6.Cu") (net 272))
  (segment (start 160.493352 73.689611) (end 160.512085 73.674672) (width 0.107) (layer "In6.Cu") (net 272))
  (segment (start 160.5785 71.03325) (end 160.805875 70.805875) (width 0.107) (layer "In6.Cu") (net 272))
  (segment (start 160.241569 75.144123) (end 160.236238 75.120763) (width 0.107) (layer "In6.Cu") (net 272))
  (segment (start 158.77941 73.576371) (end 158.753587 73.463237) (width 0.107) (layer "In6.Cu") (net 272))
  (segment (start 160.5785 73.608253) (end 160.5785 71.03325) (width 0.107) (layer "In6.Cu") (net 272))
  (segment (start 160.236238 75.120763) (end 160.225842 75.099176) (width 0.107) (layer "In6.Cu") (net 272))
  (segment (start 159.037783 72.921484) (end 159.142335 72.871134) (width 0.107) (layer "In6.Cu") (net 272))
  (segment (start 160.379498 73.689611) (end 160.401086 73.700006) (width 0.107) (layer "In6.Cu") (net 272))
  (segment (start 160.360765 73.674672) (end 160.379498 73.689611) (width 0.107) (layer "In6.Cu") (net 272))
  (segment (start 159.589201 72.921484) (end 159.679929 72.993836) (width 0.107) (layer "In6.Cu") (net 272))
  (segment (start 160.241569 75.168083) (end 160.241569 75.144123) (width 0.107) (layer "In6.Cu") (net 272))
  (segment (start 160.424445 73.705338) (end 160.448405 73.705338) (width 0.107) (layer "In6.Cu") (net 272))
  (segment (start 159.896194 75.068376) (end 160.059582 75.231764) (width 0.107) (layer "In6.Cu") (net 272))
  (segment (start 159.449263 74.897379) (end 159.565307 74.897379) (width 0.107) (layer "In6.Cu") (net 272))
  (segment (start 158.829758 73.129507) (end 158.902111 73.038779) (width 0.107) (layer "In6.Cu") (net 272))
  (segment (start 160.059582 75.231764) (end 160.078315 75.246703) (width 0.107) (layer "In6.Cu") (net 272))
  (segment (start 148.124409 82.987341) (end 150.65825 80.4535) (width 0.107) (layer "In6.Cu") (net 272))
  (segment (start 158.753587 73.347193) (end 158.779408 73.234059) (width 0.107) (layer "In6.Cu") (net 272))
  (segment (start 158.902112 73.771651) (end 158.82976 73.680923) (width 0.107) (layer "In6.Cu") (net 272))
  (segment (start 160.099902 75.257099) (end 160.123262 75.262431) (width 0.107) (layer "In6.Cu") (net 272))
  (segment (start 160.471766 73.700006) (end 160.493352 73.689611) (width 0.107) (layer "In6.Cu") (net 272))
  (segment (start 159.678442 74.923202) (end 159.782994 74.973551) (width 0.107) (layer "In6.Cu") (net 272))
  (segment (start 159.336128 74.923202) (end 159.449263 74.897379) (width 0.107) (layer "In6.Cu") (net 272))
  (segment (start 159.231576 74.973551) (end 159.336128 74.923202) (width 0.107) (layer "In6.Cu") (net 272))
  (segment (start 160.210903 75.080443) (end 158.902112 73.771651) (width 0.107) (layer "In6.Cu") (net 272))
  (segment (start 158.753587 73.463237) (end 158.753587 73.347193) (width 0.107) (layer "In6.Cu") (net 272))
  (segment (start 160.170582 75.257099) (end 160.19217 75.246703) (width 0.107) (layer "In6.Cu") (net 272))
  (segment (start 159.679929 72.993836) (end 160.360765 73.674672) (width 0.107) (layer "In6.Cu") (net 272))
  (segment (start 147.097 85.238) (end 147.05 85.191) (width 0.182) (layer "F.Cu") (net 273))
  (segment (start 147.05 85.191) (end 147.05 84.206648) (width 0.182) (layer "F.Cu") (net 273))
  (segment (start 147.05 84.206648) (end 147.159 84.097649) (width 0.182) (layer "F.Cu") (net 273))
  (via (at 147.159 84.097649) (size 0.45) (drill 0.1) (layers "F.Cu" "B.Cu") (net 273))
  (segment (start 156.886255 73.218357) (end 156.998536 73.147806) (width 0.107) (layer "In6.Cu") (net 273))
  (segment (start 157.162855 72.941757) (end 157.206652 72.816591) (width 0.107) (layer "In6.Cu") (net 273))
  (segment (start 157.2215 75.29175) (end 157.2215 75.090502) (width 0.107) (layer "In6.Cu") (net 273))
  (segment (start 157.98552 71.870925) (end 157.954106 71.831533) (width 0.107) (layer "In6.Cu") (net 273))
  (segment (start 148.2315 82.24175) (end 148.2315 81.23175) (width 0.107) (layer "In6.Cu") (net 273))
  (segment (start 158.059528 72.014354) (end 158.048316 71.965234) (width 0.107) (layer "In6.Cu") (net 273))
  (segment (start 157.910256 72.251921) (end 157.955651 72.23006) (width 0.107) (layer "In6.Cu") (net 273))
  (segment (start 158.026455 71.919839) (end 157.995042 71.880447) (width 0.107) (layer "In6.Cu") (net 273))
  (segment (start 157.349125 72.189125) (end 157.388516 72.157711) (width 0.107) (layer "In6.Cu") (net 273))
  (segment (start 157.954106 71.831533) (end 157.932245 71.786138) (width 0.107) (layer "In6.Cu") (net 273))
  (segment (start 158.396294 73.777197) (end 158.284013 73.706646) (width 0.107) (layer "In6.Cu") (net 273))
  (segment (start 157.226151 75.049224) (end 157.239871 75.010016) (width 0.107) (layer "In6.Cu") (net 273))
  (segment (start 157.326515 74.923372) (end 157.365723 74.909652) (width 0.107) (layer "In6.Cu") (net 273))
  (segment (start 157.433911 72.13585) (end 157.483032 72.124638) (width 0.107) (layer "In6.Cu") (net 273))
  (segment (start 155.842113 73.542987) (end 155.828393 73.503779) (width 0.107) (layer "In6.Cu") (net 273))
  (segment (start 158.284013 74.846357) (end 158.396294 74.775806) (width 0.107) (layer "In6.Cu") (net 273))
  (segment (start 157.365723 74.909652) (end 157.407 74.905002) (width 0.107) (layer "In6.Cu") (net 273))
  (segment (start 152.59175 79.9215) (end 157.2215 75.29175) (width 0.107) (layer "In6.Cu") (net 273))
  (segment (start 158.490062 73.870965) (end 158.396294 73.777197) (width 0.107) (layer "In6.Cu") (net 273))
  (segment (start 156.761089 73.262154) (end 156.886255 73.218357) (width 0.107) (layer "In6.Cu") (net 273))
  (segment (start 155.893585 73.317472) (end 155.928757 73.295372) (width 0.107) (layer "In6.Cu") (net 273))
  (segment (start 157.995042 72.198646) (end 158.026455 72.159254) (width 0.107) (layer "In6.Cu") (net 273))
  (segment (start 157.239871 75.010016) (end 157.261971 74.974844) (width 0.107) (layer "In6.Cu") (net 273))
  (segment (start 158.048316 71.965234) (end 158.026455 71.919839) (width 0.107) (layer "In6.Cu") (net 273))
  (segment (start 158.396294 74.775806) (end 158.490062 74.682038) (width 0.107) (layer "In6.Cu") (net 273))
  (segment (start 155.928757 73.295372) (end 155.967965 73.281652) (width 0.107) (layer "In6.Cu") (net 273))
  (segment (start 157.861135 72.263133) (end 157.910256 72.251921) (width 0.107) (layer "In6.Cu") (net 273))
  (segment (start 158.048316 72.113859) (end 158.059528 72.064738) (width 0.107) (layer "In6.Cu") (net 273))
  (segment (start 155.967965 73.643351) (end 155.928757 73.629631) (width 0.107) (layer "In6.Cu") (net 273))
  (segment (start 156.998536 73.147806) (end 157.092304 73.054038) (width 0.107) (layer "In6.Cu") (net 273))
  (segment (start 158.027074 73.648002) (end 156.009243 73.648002) (width 0.107) (layer "In6.Cu") (net 273))
  (segment (start 157.995042 71.880447) (end 157.98552 71.870925) (width 0.107) (layer "In6.Cu") (net 273))
  (segment (start 155.864213 73.578159) (end 155.842113 73.542987) (width 0.107) (layer "In6.Cu") (net 273))
  (segment (start 157.667323 72.189125) (end 157.676844 72.198646) (width 0.107) (layer "In6.Cu") (net 273))
  (segment (start 156.629316 73.277002) (end 156.761089 73.262154) (width 0.107) (layer "In6.Cu") (net 273))
  (segment (start 157.676844 72.198646) (end 157.716236 72.23006) (width 0.107) (layer "In6.Cu") (net 273))
  (segment (start 157.206652 72.816591) (end 157.2215 72.684818) (width 0.107) (layer "In6.Cu") (net 273))
  (segment (start 158.027074 74.905002) (end 158.158847 74.890154) (width 0.107) (layer "In6.Cu") (net 273))
  (segment (start 156.009243 73.277002) (end 156.629316 73.277002) (width 0.107) (layer "In6.Cu") (net 273))
  (segment (start 157.810751 72.263133) (end 157.861135 72.263133) (width 0.107) (layer "In6.Cu") (net 273))
  (segment (start 147.0825 83.39075) (end 148.2315 82.24175) (width 0.107) (layer "In6.Cu") (net 273))
  (segment (start 155.823743 73.462502) (end 155.828393 73.421224) (width 0.107) (layer "In6.Cu") (net 273))
  (segment (start 158.059528 72.064738) (end 158.059528 72.014354) (width 0.107) (layer "In6.Cu") (net 273))
  (segment (start 148.2315 81.23175) (end 149.54175 79.9215) (width 0.107) (layer "In6.Cu") (net 273))
  (segment (start 158.158847 73.662849) (end 158.027074 73.648002) (width 0.107) (layer "In6.Cu") (net 273))
  (segment (start 157.627931 72.157711) (end 157.667323 72.189125) (width 0.107) (layer "In6.Cu") (net 273))
  (segment (start 156.009243 73.648002) (end 155.967965 73.643351) (width 0.107) (layer "In6.Cu") (net 273))
  (segment (start 147.0825 84.021149) (end 147.0825 83.39075) (width 0.107) (layer "In6.Cu") (net 273))
  (segment (start 157.2215 75.090502) (end 157.226151 75.049224) (width 0.107) (layer "In6.Cu") (net 273))
  (segment (start 155.842113 73.382016) (end 155.864213 73.346844) (width 0.107) (layer "In6.Cu") (net 273))
  (segment (start 158.60441 74.444591) (end 158.619257 74.312818) (width 0.107) (layer "In6.Cu") (net 273))
  (segment (start 157.761631 72.251921) (end 157.810751 72.263133) (width 0.107) (layer "In6.Cu") (net 273))
  (segment (start 155.828393 73.503779) (end 155.823743 73.462502) (width 0.107) (layer "In6.Cu") (net 273))
  (segment (start 157.716236 72.23006) (end 157.761631 72.251921) (width 0.107) (layer "In6.Cu") (net 273))
  (segment (start 158.284013 73.706646) (end 158.158847 73.662849) (width 0.107) (layer "In6.Cu") (net 273))
  (segment (start 155.967965 73.281652) (end 156.009243 73.277002) (width 0.107) (layer "In6.Cu") (net 273))
  (segment (start 157.954106 71.592118) (end 157.985521 71.552728) (width 0.107) (layer "In6.Cu") (net 273))
  (segment (start 157.483032 72.124638) (end 157.533416 72.124638) (width 0.107) (layer "In6.Cu") (net 273))
  (segment (start 157.221501 72.316749) (end 157.349125 72.189125) (width 0.107) (layer "In6.Cu") (net 273))
  (segment (start 155.928757 73.629631) (end 155.893585 73.607531) (width 0.107) (layer "In6.Cu") (net 273))
  (segment (start 157.955651 72.23006) (end 157.995042 72.198646) (width 0.107) (layer "In6.Cu") (net 273))
  (segment (start 157.092304 73.054038) (end 157.162855 72.941757) (width 0.107) (layer "In6.Cu") (net 273))
  (segment (start 157.291343 74.945472) (end 157.326515 74.923372) (width 0.107) (layer "In6.Cu") (net 273))
  (segment (start 157.932245 71.637513) (end 157.954106 71.592118) (width 0.107) (layer "In6.Cu") (net 273))
  (segment (start 158.79 71.05) (end 159.54 71.8) (width 0.109) (layer "In6.Cu") (net 273))
  (segment (start 158.60441 74.108412) (end 158.560613 73.983246) (width 0.107) (layer "In6.Cu") (net 273))
  (segment (start 158.490062 74.682038) (end 158.560613 74.569757) (width 0.107) (layer "In6.Cu") (net 273))
  (segment (start 157.388516 72.157711) (end 157.433911 72.13585) (width 0.107) (layer "In6.Cu") (net 273))
  (segment (start 155.893585 73.607531) (end 155.864213 73.578159) (width 0.107) (layer "In6.Cu") (net 273))
  (segment (start 157.261971 74.974844) (end 157.291343 74.945472) (width 0.107) (layer "In6.Cu") (net 273))
  (segment (start 157.533416 72.124638) (end 157.582536 72.13585) (width 0.107) (layer "In6.Cu") (net 273))
  (segment (start 157.2215 72.684818) (end 157.221501 72.316749) (width 0.107) (layer "In6.Cu") (net 273))
  (segment (start 158.619257 74.312818) (end 158.619257 74.240185) (width 0.107) (layer "In6.Cu") (net 273))
  (segment (start 149.54175 79.9215) (end 152.59175 79.9215) (width 0.107) (layer "In6.Cu") (net 273))
  (segment (start 157.985521 71.552728) (end 158.48825 71.05) (width 0.107) (layer "In6.Cu") (net 273))
  (segment (start 158.560613 74.569757) (end 158.60441 74.444591) (width 0.107) (layer "In6.Cu") (net 273))
  (segment (start 157.921033 71.686634) (end 157.932245 71.637513) (width 0.107) (layer "In6.Cu") (net 273))
  (segment (start 147.159 84.097649) (end 147.0825 84.021149) (width 0.107) (layer "In6.Cu") (net 273))
  (segment (start 158.48825 71.05) (end 158.79 71.05) (width 0.109) (layer "In6.Cu") (net 273))
  (segment (start 158.619257 74.240185) (end 158.60441 74.108412) (width 0.107) (layer "In6.Cu") (net 273))
  (segment (start 158.560613 73.983246) (end 158.490062 73.870965) (width 0.107) (layer "In6.Cu") (net 273))
  (segment (start 155.828393 73.421224) (end 155.842113 73.382016) (width 0.107) (layer "In6.Cu") (net 273))
  (segment (start 157.582536 72.13585) (end 157.627931 72.157711) (width 0.107) (layer "In6.Cu") (net 273))
  (segment (start 157.932245 71.786138) (end 157.921033 71.737018) (width 0.107) (layer "In6.Cu") (net 273))
  (segment (start 157.407 74.905002) (end 158.027074 74.905002) (width 0.107) (layer "In6.Cu") (net 273))
  (segment (start 155.864213 73.346844) (end 155.893585 73.317472) (width 0.107) (layer "In6.Cu") (net 273))
  (segment (start 157.921033 71.737018) (end 157.921033 71.686634) (width 0.107) (layer "In6.Cu") (net 273))
  (segment (start 158.158847 74.890154) (end 158.284013 74.846357) (width 0.107) (layer "In6.Cu") (net 273))
  (segment (start 158.026455 72.159254) (end 158.048316 72.113859) (width 0.107) (layer "In6.Cu") (net 273))
  (segment (start 146.671999 84.206648) (end 146.562999 84.097649) (width 0.182) (layer "F.Cu") (net 274))
  (segment (start 146.671999 85.163001) (end 146.671999 84.206648) (width 0.182) (layer "F.Cu") (net 274))
  (segment (start 146.597 85.238) (end 146.671999 85.163001) (width 0.182) (layer "F.Cu") (net 274))
  (via (at 146.562999 84.097649) (size 0.45) (drill 0.1) (layers "F.Cu" "B.Cu") (net 274))
  (segment (start 158.135787 74.392159) (end 158.106415 74.421531) (width 0.107) (layer "In6.Cu") (net 274))
  (segment (start 155.439387 73.755757) (end 155.509938 73.868038) (width 0.107) (layer "In6.Cu") (net 274))
  (segment (start 155.380743 73.498818) (end 155.39559 73.630591) (width 0.107) (layer "In6.Cu") (net 274))
  (segment (start 156.907696 74.684965) (end 156.837145 74.797246) (width 0.107) (layer "In6.Cu") (net 274))
  (segment (start 158.171607 74.317779) (end 158.157887 74.356987) (width 0.107) (layer "In6.Cu") (net 274))
  (segment (start 158.071243 74.109372) (end 158.106415 74.131472) (width 0.107) (layer "In6.Cu") (net 274))
  (segment (start 155.39559 73.294412) (end 155.380743 73.426185) (width 0.107) (layer "In6.Cu") (net 274))
  (segment (start 155.509938 73.056965) (end 155.439387 73.169246) (width 0.107) (layer "In6.Cu") (net 274))
  (segment (start 156.793348 74.922412) (end 156.7785 75.054185) (width 0.107) (layer "In6.Cu") (net 274))
  (segment (start 158.171607 74.235224) (end 158.176257 74.276502) (width 0.107) (layer "In6.Cu") (net 274))
  (segment (start 158.176257 74.276502) (end 158.171607 74.317779) (width 0.107) (layer "In6.Cu") (net 274))
  (segment (start 155.39559 73.630591) (end 155.439387 73.755757) (width 0.107) (layer "In6.Cu") (net 274))
  (segment (start 146.563 84.097649) (end 146.562999 84.097649) (width 0.107) (layer "In6.Cu") (net 274))
  (segment (start 156.673485 72.815631) (end 156.634277 72.829351) (width 0.107) (layer "In6.Cu") (net 274))
  (segment (start 149.35825 79.4785) (end 147.7885 81.04825) (width 0.107) (layer "In6.Cu") (net 274))
  (segment (start 158.032035 74.095652) (end 158.071243 74.109372) (width 0.107) (layer "In6.Cu") (net 274))
  (segment (start 158.157887 74.196016) (end 158.171607 74.235224) (width 0.107) (layer "In6.Cu") (net 274))
  (segment (start 156.7785 72.648502) (end 156.773849 72.689779) (width 0.107) (layer "In6.Cu") (net 274))
  (segment (start 156.634277 72.829351) (end 156.593 72.834002) (width 0.107) (layer "In6.Cu") (net 274))
  (segment (start 158.106415 74.421531) (end 158.071243 74.443631) (width 0.107) (layer "In6.Cu") (net 274))
  (segment (start 146.6395 84.021149) (end 146.563 84.097649) (width 0.107) (layer "In6.Cu") (net 274))
  (segment (start 158.157887 74.356987) (end 158.135787 74.392159) (width 0.107) (layer "In6.Cu") (net 274))
  (segment (start 157.990757 74.091002) (end 158.032035 74.095652) (width 0.107) (layer "In6.Cu") (net 274))
  (segment (start 146.6395 83.20725) (end 146.6395 84.021149) (width 0.107) (layer "In6.Cu") (net 274))
  (segment (start 157.001464 74.591197) (end 156.907696 74.684965) (width 0.107) (layer "In6.Cu") (net 274))
  (segment (start 158.3 70.61175) (end 158.3 69.275) (width 0.109) (layer "In6.Cu") (net 274))
  (segment (start 155.439387 73.169246) (end 155.39559 73.294412) (width 0.107) (layer "In6.Cu") (net 274))
  (segment (start 155.603706 72.963197) (end 155.509938 73.056965) (width 0.107) (layer "In6.Cu") (net 274))
  (segment (start 157.238911 74.476849) (end 157.113745 74.520646) (width 0.107) (layer "In6.Cu") (net 274))
  (segment (start 155.603706 73.961806) (end 155.715987 74.032357) (width 0.107) (layer "In6.Cu") (net 274))
  (segment (start 156.7785 75.054185) (end 156.7785 75.10825) (width 0.107) (layer "In6.Cu") (net 274))
  (segment (start 157.113745 74.520646) (end 157.001464 74.591197) (width 0.107) (layer "In6.Cu") (net 274))
  (segment (start 158.106415 74.131472) (end 158.135787 74.160844) (width 0.107) (layer "In6.Cu") (net 274))
  (segment (start 156.837145 74.797246) (end 156.793348 74.922412) (width 0.107) (layer "In6.Cu") (net 274))
  (segment (start 147.7885 81.04825) (end 147.7885 82.05825) (width 0.107) (layer "In6.Cu") (net 274))
  (segment (start 156.7785 72.13325) (end 156.7785 72.648502) (width 0.107) (layer "In6.Cu") (net 274))
  (segment (start 155.715987 72.892646) (end 155.603706 72.963197) (width 0.107) (layer "In6.Cu") (net 274))
  (segment (start 157.370684 74.462002) (end 157.238911 74.476849) (width 0.107) (layer "In6.Cu") (net 274))
  (segment (start 155.972926 72.834002) (end 155.841153 72.848849) (width 0.107) (layer "In6.Cu") (net 274))
  (segment (start 155.972926 74.091002) (end 157.990757 74.091002) (width 0.107) (layer "In6.Cu") (net 274))
  (segment (start 155.380743 73.426185) (end 155.380743 73.498818) (width 0.107) (layer "In6.Cu") (net 274))
  (segment (start 155.509938 73.868038) (end 155.603706 73.961806) (width 0.107) (layer "In6.Cu") (net 274))
  (segment (start 155.841153 74.076154) (end 155.972926 74.091002) (width 0.107) (layer "In6.Cu") (net 274))
  (segment (start 155.715987 74.032357) (end 155.841153 74.076154) (width 0.107) (layer "In6.Cu") (net 274))
  (segment (start 157.990757 74.462002) (end 157.370684 74.462002) (width 0.107) (layer "In6.Cu") (net 274))
  (segment (start 147.7885 82.05825) (end 146.6395 83.20725) (width 0.107) (layer "In6.Cu") (net 274))
  (segment (start 156.593 72.834002) (end 155.972926 72.834002) (width 0.107) (layer "In6.Cu") (net 274))
  (segment (start 156.7785 75.10825) (end 152.40825 79.4785) (width 0.107) (layer "In6.Cu") (net 274))
  (segment (start 158.135787 74.160844) (end 158.157887 74.196016) (width 0.107) (layer "In6.Cu") (net 274))
  (segment (start 158.3 70.61175) (end 156.7785 72.13325) (width 0.107) (layer "In6.Cu") (net 274))
  (segment (start 156.760129 72.728987) (end 156.738029 72.764159) (width 0.107) (layer "In6.Cu") (net 274))
  (segment (start 152.40825 79.4785) (end 149.35825 79.4785) (width 0.107) (layer "In6.Cu") (net 274))
  (segment (start 156.708657 72.793531) (end 156.673485 72.815631) (width 0.107) (layer "In6.Cu") (net 274))
  (segment (start 158.032035 74.457351) (end 157.990757 74.462002) (width 0.107) (layer "In6.Cu") (net 274))
  (segment (start 156.738029 72.764159) (end 156.708657 72.793531) (width 0.107) (layer "In6.Cu") (net 274))
  (segment (start 158.071243 74.443631) (end 158.032035 74.457351) (width 0.107) (layer "In6.Cu") (net 274))
  (segment (start 156.773849 72.689779) (end 156.760129 72.728987) (width 0.107) (layer "In6.Cu") (net 274))
  (segment (start 155.841153 72.848849) (end 155.715987 72.892646) (width 0.107) (layer "In6.Cu") (net 274))
  (segment (start 118.918943 90.882622) (end 119.437034 91.400713) (width 0.182) (layer "F.Cu") (net 275))
  (segment (start 118.6 92.2992) (end 119.437034 91.462166) (width 0.182) (layer "F.Cu") (net 275))
  (segment (start 118.918943 90.323661) (end 118.918943 90.882622) (width 0.182) (layer "F.Cu") (net 275))
  (segment (start 119.437034 91.462166) (end 119.437034 91.400713) (width 0.182) (layer "F.Cu") (net 275))
  (via (at 119.437034 91.400713) (size 0.5) (drill 0.15) (layers "F.Cu" "B.Cu") (net 275))
  (segment (start 117.9 92.215) (end 118.8 92.215) (width 0.182) (layer "B.Cu") (net 275))
  (segment (start 119.437034 91.577966) (end 119.437034 91.400713) (width 0.4) (layer "B.Cu") (net 275))
  (segment (start 118.8 92.215) (end 119.437034 91.577966) (width 0.4) (layer "B.Cu") (net 275))
  (segment (start 123.1151 97.967) (end 124.767 97.967) (width 0.182) (layer "F.Cu") (net 277))
  (segment (start 126.29 97.935) (end 126.405002 97.935) (width 0.182) (layer "F.Cu") (net 277))
  (segment (start 125.1 98.3) (end 125.925 98.3) (width 0.182) (layer "F.Cu") (net 277))
  (segment (start 124.767 97.967) (end 125.1 98.3) (width 0.182) (layer "F.Cu") (net 277))
  (segment (start 125.925 98.3) (end 126.29 97.935) (width 0.182) (layer "F.Cu") (net 277))
  (segment (start 130.250001 73.667499) (end 130.250001 74.09125) (width 0.182) (layer "B.Cu") (net 278))
  (segment (start 130.250001 74.09125) (end 130.311001 74.15225) (width 0.182) (layer "B.Cu") (net 278))
  (segment (start 132.480001 67.2375) (end 131.75 67.2375) (width 0.182) (layer "B.Cu") (net 278))
  (segment (start 132.561 67.3185) (end 132.480001 67.2375) (width 0.182) (layer "B.Cu") (net 278))
  (segment (start 132.371712 71.360999) (end 132.584187 71.148524) (width 0.182) (layer "B.Cu") (net 278))
  (segment (start 132.584187 71.148524) (end 132.584187 70.058975) (width 0.182) (layer "B.Cu") (net 278))
  (segment (start 130.311 72.347748) (end 130.310999 71.821711) (width 0.182) (layer "B.Cu") (net 278))
  (segment (start 132.011 69.485788) (end 132.011 68.319472) (width 0.182) (layer "B.Cu") (net 278))
  (segment (start 130.310999 71.821711) (end 130.771711 71.360999) (width 0.182) (layer "B.Cu") (net 278))
  (segment (start 130.771711 71.360999) (end 132.371712 71.360999) (width 0.182) (layer "B.Cu") (net 278))
  (segment (start 132.561 67.769471) (end 132.561 67.3185) (width 0.182) (layer "B.Cu") (net 278))
  (segment (start 132.011 68.319472) (end 132.561 67.769471) (width 0.182) (layer "B.Cu") (net 278))
  (segment (start 130.25 72.408749) (end 130.311 72.347748) (width 0.182) (layer "B.Cu") (net 278))
  (segment (start 132.584187 70.058975) (end 132.011 69.485788) (width 0.182) (layer "B.Cu") (net 278))
  (segment (start 130.25 72.8325) (end 130.25 72.408749) (width 0.182) (layer "B.Cu") (net 278))
  (segment (start 130.248 72.863) (end 130.248 73.635) (width 0.182) (layer "B.Cu") (net 278))
  (segment (start 130.311001 74.358999) (end 130.311001 74.15225) (width 0.182) (layer "B.Cu") (net 278))
  (segment (start 130.05 74.62) (end 130.311001 74.358999) (width 0.182) (layer "B.Cu") (net 278))
  (segment (start 130.750001 74.09125) (end 130.689001 74.15225) (width 0.182) (layer "B.Cu") (net 279))
  (segment (start 130.75 73.667499) (end 130.750001 74.09125) (width 0.182) (layer "B.Cu") (net 279))
  (segment (start 132.528288 71.739) (end 132.962187 71.305101) (width 0.182) (layer "B.Cu") (net 279))
  (segment (start 132.962187 71.305101) (end 132.962187 69.902399) (width 0.182) (layer "B.Cu") (net 279))
  (segment (start 132.939 67.926047) (end 132.389 68.476047) (width 0.182) (layer "B.Cu") (net 279))
  (segment (start 133.75 67.2375) (end 133.070001 67.2375) (width 0.182) (layer "B.Cu") (net 279))
  (segment (start 132.389 68.476047) (end 132.389 69.329212) (width 0.182) (layer "B.Cu") (net 279))
  (segment (start 130.689 71.978288) (end 130.688999 72.347748) (width 0.182) (layer "B.Cu") (net 279))
  (segment (start 132.962187 69.902399) (end 132.389 69.329212) (width 0.182) (layer "B.Cu") (net 279))
  (segment (start 133.070001 67.2375) (end 132.939001 67.3685) (width 0.182) (layer "B.Cu") (net 279))
  (segment (start 130.688999 72.347748) (end 130.749999 72.408748) (width 0.182) (layer "B.Cu") (net 279))
  (segment (start 132.939001 67.3685) (end 132.939 67.926047) (width 0.182) (layer "B.Cu") (net 279))
  (segment (start 130.749999 72.408748) (end 130.75 72.832499) (width 0.182) (layer "B.Cu") (net 279))
  (segment (start 132.528288 71.739) (end 130.928288 71.738999) (width 0.182) (layer "B.Cu") (net 279))
  (segment (start 130.928288 71.738999) (end 130.689 71.978288) (width 0.182) (layer "B.Cu") (net 279))
  (segment (start 130.95 74.62) (end 130.689001 74.359001) (width 0.182) (layer "B.Cu") (net 279))
  (segment (start 130.689001 74.359001) (end 130.689001 74.15225) (width 0.182) (layer "B.Cu") (net 279))
  (segment (start 130.748 72.863) (end 130.748 73.635) (width 0.182) (layer "B.Cu") (net 279))
  (segment (start 130.25 74.091251) (end 130.311 74.152251) (width 0.182) (layer "F.Cu") (net 280))
  (segment (start 130.25 73.6675) (end 130.25 74.091251) (width 0.182) (layer "F.Cu") (net 280))
  (segment (start 130.771712 71.361) (end 130.311 71.821712) (width 0.182) (layer "F.Cu") (net 280))
  (segment (start 131.75 70.43) (end 132.43 70.43) (width 0.182) (layer "F.Cu") (net 280))
  (segment (start 130.311 72.347749) (end 130.25 72.408749) (width 0.182) (layer "F.Cu") (net 280))
  (segment (start 132.371712 71.361) (end 130.771712 71.361) (width 0.182) (layer "F.Cu") (net 280))
  (segment (start 130.311 71.821712) (end 130.311 72.347749) (width 0.182) (layer "F.Cu") (net 280))
  (segment (start 132.43 70.43) (end 132.561 70.561) (width 0.182) (layer "F.Cu") (net 280))
  (segment (start 132.561 71.171712) (end 132.371712 71.361) (width 0.182) (layer "F.Cu") (net 280))
  (segment (start 130.25 72.408749) (end 130.25 72.8325) (width 0.182) (layer "F.Cu") (net 280))
  (segment (start 132.561 70.561) (end 132.561 71.171712) (width 0.182) (layer "F.Cu") (net 280))
  (segment (start 130.25 72.8955) (end 130.25 73.6675) (width 0.182) (layer "F.Cu") (net 280))
  (segment (start 130.311 74.152251) (end 130.311 74.364) (width 0.182) (layer "F.Cu") (net 280))
  (segment (start 130.05 74.625) (end 130.311 74.364) (width 0.182) (layer "F.Cu") (net 280))
  (segment (start 130.75 73.6675) (end 130.75 74.091251) (width 0.182) (layer "F.Cu") (net 281))
  (segment (start 130.689 72.347749) (end 130.75 72.408749) (width 0.182) (layer "F.Cu") (net 281))
  (segment (start 133.75 70.43) (end 133.07 70.43) (width 0.182) (layer "F.Cu") (net 281))
  (segment (start 133.07 70.43) (end 132.939 70.561) (width 0.182) (layer "F.Cu") (net 281))
  (segment (start 132.939 71.328288) (end 132.528288 71.739) (width 0.182) (layer "F.Cu") (net 281))
  (segment (start 132.528288 71.739) (end 130.928288 71.739) (width 0.182) (layer "F.Cu") (net 281))
  (segment (start 132.939 70.561) (end 132.939 71.328288) (width 0.182) (layer "F.Cu") (net 281))
  (segment (start 130.928288 71.739) (end 130.689 71.978288) (width 0.182) (layer "F.Cu") (net 281))
  (segment (start 130.75 72.408749) (end 130.75 72.8325) (width 0.182) (layer "F.Cu") (net 281))
  (segment (start 130.689 71.978288) (end 130.689 72.347749) (width 0.182) (layer "F.Cu") (net 281))
  (segment (start 130.689 74.364) (end 130.689 74.152251) (width 0.182) (layer "F.Cu") (net 281))
  (segment (start 130.95 74.625) (end 130.689 74.364) (width 0.182) (layer "F.Cu") (net 281))
  (segment (start 130.75 72.8955) (end 130.75 73.6675) (width 0.182) (layer "F.Cu") (net 281))
  (segment (start 130.75 74.091251) (end 130.689 74.152251) (width 0.182) (layer "F.Cu") (net 281))
  (segment (start 110.9 73.7) (end 110.9 74.123751) (width 0.182) (layer "B.Cu") (net 282))
  (segment (start 110.9 74.123751) (end 110.961 74.184751) (width 0.182) (layer "B.Cu") (net 282))
  (segment (start 113.130001 67.2875) (end 112.4 67.2875) (width 0.182) (layer "B.Cu") (net 282))
  (segment (start 113.211 67.3685) (end 113.130001 67.2875) (width 0.182) (layer "B.Cu") (net 282))
  (segment (start 113.021712 71.410999) (end 113.234187 71.198524) (width 0.182) (layer "B.Cu") (net 282))
  (segment (start 113.211 67.819471) (end 113.211 67.3685) (width 0.182) (layer "B.Cu") (net 282))
  (segment (start 112.661 68.369472) (end 113.211 67.819471) (width 0.182) (layer "B.Cu") (net 282))
  (segment (start 110.9 72.458749) (end 110.961 72.397748) (width 0.182) (layer "B.Cu") (net 282))
  (segment (start 110.9 72.8825) (end 110.9 72.458749) (width 0.182) (layer "B.Cu") (net 282))
  (segment (start 110.960999 71.871711) (end 111.421711 71.410999) (width 0.182) (layer "B.Cu") (net 282))
  (segment (start 111.421711 71.410999) (end 113.021712 71.410999) (width 0.182) (layer "B.Cu") (net 282))
  (segment (start 113.234187 71.198524) (end 113.234187 70.108975) (width 0.182) (layer "B.Cu") (net 282))
  (segment (start 113.234187 70.108975) (end 112.661 69.535788) (width 0.182) (layer "B.Cu") (net 282))
  (segment (start 112.661 69.535788) (end 112.661 68.369472) (width 0.182) (layer "B.Cu") (net 282))
  (segment (start 110.961 72.397748) (end 110.960999 71.871711) (width 0.182) (layer "B.Cu") (net 282))
  (segment (start 110.898 72.913) (end 110.898 73.685) (width 0.182) (layer "B.Cu") (net 282))
  (segment (start 110.675 74.648) (end 110.961 74.362) (width 0.182) (layer "B.Cu") (net 282))
  (segment (start 110.961 74.362) (end 110.961 74.184751) (width 0.182) (layer "B.Cu") (net 282))
  (segment (start 111.399999 73.7) (end 111.4 74.123751) (width 0.182) (layer "B.Cu") (net 283))
  (segment (start 111.4 74.123751) (end 111.339 74.184751) (width 0.182) (layer "B.Cu") (net 283))
  (segment (start 113.178288 71.789) (end 113.612187 71.355101) (width 0.182) (layer "B.Cu") (net 283))
  (segment (start 113.612187 69.952399) (end 113.039 69.379212) (width 0.182) (layer "B.Cu") (net 283))
  (segment (start 113.612187 71.355101) (end 113.612187 69.952399) (width 0.182) (layer "B.Cu") (net 283))
  (segment (start 113.720001 67.2875) (end 113.589001 67.4185) (width 0.182) (layer "B.Cu") (net 283))
  (segment (start 113.589 67.976047) (end 113.039 68.526047) (width 0.182) (layer "B.Cu") (net 283))
  (segment (start 113.178288 71.789) (end 111.578288 71.788999) (width 0.182) (layer "B.Cu") (net 283))
  (segment (start 111.399999 72.458748) (end 111.4 72.882499) (width 0.182) (layer "B.Cu") (net 283))
  (segment (start 111.339 72.028288) (end 111.338999 72.397748) (width 0.182) (layer "B.Cu") (net 283))
  (segment (start 111.578288 71.788999) (end 111.339 72.028288) (width 0.182) (layer "B.Cu") (net 283))
  (segment (start 113.589001 67.4185) (end 113.589 67.976047) (width 0.182) (layer "B.Cu") (net 283))
  (segment (start 111.338999 72.397748) (end 111.399999 72.458748) (width 0.182) (layer "B.Cu") (net 283))
  (segment (start 113.039 68.526047) (end 113.039 69.379212) (width 0.182) (layer "B.Cu") (net 283))
  (segment (start 114.4 67.2875) (end 113.720001 67.2875) (width 0.182) (layer "B.Cu") (net 283))
  (segment (start 111.339 74.372) (end 111.339 74.184751) (width 0.182) (layer "B.Cu") (net 283))
  (segment (start 111.398 72.913) (end 111.398 73.685) (width 0.182) (layer "B.Cu") (net 283))
  (segment (start 111.62 74.653) (end 111.339 74.372) (width 0.182) (layer "B.Cu") (net 283))
  (segment (start 110.961 71.871712) (end 110.961 72.397749) (width 0.182) (layer "F.Cu") (net 284))
  (segment (start 113.021712 71.411) (end 111.421712 71.411) (width 0.182) (layer "F.Cu") (net 284))
  (segment (start 112.4 70.48) (end 113.08 70.48) (width 0.182) (layer "F.Cu") (net 284))
  (segment (start 110.9 73.7175) (end 110.9 72.9455) (width 0.182) (layer "F.Cu") (net 284))
  (segment (start 111.421712 71.411) (end 110.961 71.871712) (width 0.182) (layer "F.Cu") (net 284))
  (segment (start 110.9 72.458749) (end 110.9 72.8825) (width 0.182) (layer "F.Cu") (net 284))
  (segment (start 110.9 73.7175) (end 110.9 74.141251) (width 0.182) (layer "F.Cu") (net 284))
  (segment (start 113.211 70.611) (end 113.211 71.221712) (width 0.182) (layer "F.Cu") (net 284))
  (segment (start 110.7 74.66) (end 110.961 74.399) (width 0.182) (layer "F.Cu") (net 284))
  (segment (start 110.9 74.141251) (end 110.961 74.202251) (width 0.182) (layer "F.Cu") (net 284))
  (segment (start 110.961 72.397749) (end 110.9 72.458749) (width 0.182) (layer "F.Cu") (net 284))
  (segment (start 110.961 74.399) (end 110.961 74.202251) (width 0.182) (layer "F.Cu") (net 284))
  (segment (start 113.08 70.48) (end 113.211 70.611) (width 0.182) (layer "F.Cu") (net 284))
  (segment (start 113.211 71.221712) (end 113.021712 71.411) (width 0.182) (layer "F.Cu") (net 284))
  (segment (start 111.4 72.458749) (end 111.4 72.8825) (width 0.182) (layer "F.Cu") (net 285))
  (segment (start 114.4 70.48) (end 113.72 70.48) (width 0.182) (layer "F.Cu") (net 285))
  (segment (start 111.4 73.7175) (end 111.4 74.141251) (width 0.182) (layer "F.Cu") (net 285))
  (segment (start 111.339 74.399) (end 111.339 74.202251) (width 0.182) (layer "F.Cu") (net 285))
  (segment (start 111.578288 71.789) (end 111.339 72.028288) (width 0.182) (layer "F.Cu") (net 285))
  (segment (start 111.4 73.7175) (end 111.4 72.9455) (width 0.182) (layer "F.Cu") (net 285))
  (segment (start 111.339 72.028288) (end 111.339 72.397749) (width 0.182) (layer "F.Cu") (net 285))
  (segment (start 113.72 70.48) (end 113.589 70.611) (width 0.182) (layer "F.Cu") (net 285))
  (segment (start 111.4 74.141251) (end 111.339 74.202251) (width 0.182) (layer "F.Cu") (net 285))
  (segment (start 111.6 74.66) (end 111.339 74.399) (width 0.182) (layer "F.Cu") (net 285))
  (segment (start 113.178288 71.789) (end 111.578288 71.789) (width 0.182) (layer "F.Cu") (net 285))
  (segment (start 113.589 70.611) (end 113.589 71.378288) (width 0.182) (layer "F.Cu") (net 285))
  (segment (start 113.589 71.378288) (end 113.178288 71.789) (width 0.182) (layer "F.Cu") (net 285))
  (segment (start 111.339 72.397749) (end 111.4 72.458749) (width 0.182) (layer "F.Cu") (net 285))
  (via (at 135.401449 72.47775) (size 0.45) (drill 0.1) (layers "F.Cu" "B.Cu") (net 286))
  (segment (start 130.8775 67.497186) (end 132.2275 68.847186) (width 0.109) (layer "In2.Cu") (net 286))
  (segment (start 130.8775 66.947186) (end 130.8775 67.497186) (width 0.109) (layer "In2.Cu") (net 286))
  (segment (start 135.230949 72.30725) (end 135.401449 72.47775) (width 0.109) (layer "In2.Cu") (net 286))
  (segment (start 132.2275 68.847186) (end 132.2275 69.247186) (width 0.109) (layer "In2.Cu") (net 286))
  (segment (start 134.652814 71.2725) (end 135.230949 71.850635) (width 0.109) (layer "In2.Cu") (net 286))
  (segment (start 135.230949 71.850635) (end 135.230949 72.30725) (width 0.109) (layer "In2.Cu") (net 286))
  (segment (start 132.8275 69.847186) (end 132.8275 70.947186) (width 0.109) (layer "In2.Cu") (net 286))
  (segment (start 130.75 65.73) (end 129.97 65.73) (width 0.109) (layer "In2.Cu") (net 286))
  (segment (start 129.8775 65.947186) (end 130.8775 66.947186) (width 0.109) (layer "In2.Cu") (net 286))
  (segment (start 132.8275 70.947186) (end 133.152814 71.2725) (width 0.109) (layer "In2.Cu") (net 286))
  (segment (start 132.2275 69.247186) (end 132.8275 69.847186) (width 0.109) (layer "In2.Cu") (net 286))
  (segment (start 129.97 65.73) (end 129.8775 65.8225) (width 0.109) (layer "In2.Cu") (net 286))
  (segment (start 133.152814 71.2725) (end 134.652814 71.2725) (width 0.109) (layer "In2.Cu") (net 286))
  (segment (start 129.8775 65.8225) (end 129.8775 65.947186) (width 0.109) (layer "In2.Cu") (net 286))
  (segment (start 135.603449 73.143449) (end 135.292449 72.832449) (width 0.182) (layer "B.Cu") (net 286))
  (segment (start 135.603449 73.421573) (end 135.603449 73.143449) (width 0.182) (layer "B.Cu") (net 286))
  (segment (start 135.292449 72.832449) (end 135.292449 72.58675) (width 0.182) (layer "B.Cu") (net 286))
  (segment (start 135.292449 72.58675) (end 135.401449 72.47775) (width 0.182) (layer "B.Cu") (net 286))
  (via (at 134.805449 72.47775) (size 0.45) (drill 0.1) (layers "F.Cu" "B.Cu") (net 287))
  (segment (start 130.6225 67.052814) (end 130.6225 67.602814) (width 0.109) (layer "In2.Cu") (net 287))
  (segment (start 134.975949 72.30725) (end 134.805449 72.47775) (width 0.109) (layer "In2.Cu") (net 287))
  (segment (start 133.047186 71.5275) (end 134.547186 71.5275) (width 0.109) (layer "In2.Cu") (net 287))
  (segment (start 132.5725 71.052814) (end 133.047186 71.5275) (width 0.109) (layer "In2.Cu") (net 287))
  (segment (start 129.6225 66.052814) (end 130.6225 67.052814) (width 0.109) (layer "In2.Cu") (net 287))
  (segment (start 132.5725 69.952814) (end 132.5725 71.052814) (width 0.109) (layer "In2.Cu") (net 287))
  (segment (start 129.6225 65.8275) (end 129.6225 66.052814) (width 0.109) (layer "In2.Cu") (net 287))
  (segment (start 134.975949 71.956263) (end 134.975949 72.30725) (width 0.109) (layer "In2.Cu") (net 287))
  (segment (start 129.525 65.73) (end 129.6225 65.8275) (width 0.109) (layer "In2.Cu") (net 287))
  (segment (start 131.9725 68.952814) (end 131.9725 69.352814) (width 0.109) (layer "In2.Cu") (net 287))
  (segment (start 131.9725 69.352814) (end 132.5725 69.952814) (width 0.109) (layer "In2.Cu") (net 287))
  (segment (start 130.6225 67.602814) (end 131.9725 68.952814) (width 0.109) (layer "In2.Cu") (net 287))
  (segment (start 134.547186 71.5275) (end 134.975949 71.956263) (width 0.109) (layer "In2.Cu") (net 287))
  (segment (start 128.75 65.73) (end 129.525 65.73) (width 0.109) (layer "In2.Cu") (net 287))
  (segment (start 134.603449 73.421573) (end 134.603449 73.146551) (width 0.182) (layer "B.Cu") (net 287))
  (segment (start 134.914449 72.835551) (end 134.914449 72.58675) (width 0.182) (layer "B.Cu") (net 287))
  (segment (start 134.603449 73.146551) (end 134.914449 72.835551) (width 0.182) (layer "B.Cu") (net 287))
  (segment (start 134.914449 72.58675) (end 134.805449 72.47775) (width 0.182) (layer "B.Cu") (net 287))
  (segment (start 133.06 73.191876) (end 132.749 72.880876) (width 0.182) (layer "F.Cu") (net 288))
  (segment (start 132.749 72.635177) (end 132.858 72.526177) (width 0.182) (layer "F.Cu") (net 288))
  (segment (start 133.06 73.47) (end 133.06 73.191876) (width 0.182) (layer "F.Cu") (net 288))
  (segment (start 132.749 72.880876) (end 132.749 72.635177) (width 0.182) (layer "F.Cu") (net 288))
  (via (at 132.858 72.526177) (size 0.45) (drill 0.1) (layers "F.Cu" "B.Cu") (net 288))
  (segment (start 129.8775 69.0575) (end 129.8775 69.147186) (width 0.109) (layer "In2.Cu") (net 288))
  (segment (start 132.6875 72.355677) (end 132.858 72.526177) (width 0.109) (layer "In2.Cu") (net 288))
  (segment (start 130.8775 70.147186) (end 130.8775 70.897186) (width 0.109) (layer "In2.Cu") (net 288))
  (segment (start 131.352814 71.3725) (end 132.152814 71.3725) (width 0.109) (layer "In2.Cu") (net 288))
  (segment (start 132.6875 71.907186) (end 132.6875 72.355677) (width 0.109) (layer "In2.Cu") (net 288))
  (segment (start 129.8775 69.147186) (end 130.8775 70.147186) (width 0.109) (layer "In2.Cu") (net 288))
  (segment (start 130.75 68.93) (end 130.005 68.93) (width 0.109) (layer "In2.Cu") (net 288))
  (segment (start 130.8775 70.897186) (end 131.352814 71.3725) (width 0.109) (layer "In2.Cu") (net 288))
  (segment (start 132.152814 71.3725) (end 132.6875 71.907186) (width 0.109) (layer "In2.Cu") (net 288))
  (segment (start 130.005 68.93) (end 129.8775 69.0575) (width 0.109) (layer "In2.Cu") (net 288))
  (segment (start 132.371 72.883978) (end 132.371 72.635177) (width 0.182) (layer "F.Cu") (net 289))
  (segment (start 132.371 72.635177) (end 132.262 72.526177) (width 0.182) (layer "F.Cu") (net 289))
  (segment (start 132.06 73.47) (end 132.06 73.194978) (width 0.182) (layer "F.Cu") (net 289))
  (segment (start 132.06 73.194978) (end 132.371 72.883978) (width 0.182) (layer "F.Cu") (net 289))
  (via (at 132.262 72.526177) (size 0.45) (drill 0.1) (layers "F.Cu" "B.Cu") (net 289))
  (segment (start 130.6225 70.252814) (end 130.6225 71.002814) (width 0.109) (layer "In2.Cu") (net 289))
  (segment (start 128.75 68.93) (end 129.5 68.93) (width 0.109) (layer "In2.Cu") (net 289))
  (segment (start 130.6225 71.002814) (end 131.247186 71.6275) (width 0.109) (layer "In2.Cu") (net 289))
  (segment (start 129.5 68.93) (end 129.6225 69.0525) (width 0.109) (layer "In2.Cu") (net 289))
  (segment (start 132.4325 72.355677) (end 132.262 72.526177) (width 0.109) (layer "In2.Cu") (net 289))
  (segment (start 132.047186 71.6275) (end 132.4325 72.012814) (width 0.109) (layer "In2.Cu") (net 289))
  (segment (start 129.6225 69.0525) (end 129.6225 69.252814) (width 0.109) (layer "In2.Cu") (net 289))
  (segment (start 131.247186 71.6275) (end 132.047186 71.6275) (width 0.109) (layer "In2.Cu") (net 289))
  (segment (start 129.6225 69.252814) (end 130.6225 70.252814) (width 0.109) (layer "In2.Cu") (net 289))
  (segment (start 132.4325 72.012814) (end 132.4325 72.355677) (width 0.109) (layer "In2.Cu") (net 289))
  (via (at 116.051449 72.52775) (size 0.45) (drill 0.1) (layers "F.Cu" "B.Cu") (net 290))
  (segment (start 113.4775 70.997186) (end 113.802814 71.3225) (width 0.109) (layer "In2.Cu") (net 290))
  (segment (start 113.802814 71.3225) (end 115.302814 71.3225) (width 0.109) (layer "In2.Cu") (net 290))
  (segment (start 112.8775 68.897186) (end 112.8775 69.297186) (width 0.109) (layer "In2.Cu") (net 290))
  (segment (start 115.302814 71.3225) (end 115.880949 71.900635) (width 0.109) (layer "In2.Cu") (net 290))
  (segment (start 111.5275 66.997186) (end 111.5275 67.547186) (width 0.109) (layer "In2.Cu") (net 290))
  (segment (start 110.5275 65.997186) (end 111.5275 66.997186) (width 0.109) (layer "In2.Cu") (net 290))
  (segment (start 115.880949 72.35725) (end 116.051449 72.52775) (width 0.109) (layer "In2.Cu") (net 290))
  (segment (start 110.62 65.78) (end 110.5275 65.8725) (width 0.109) (layer "In2.Cu") (net 290))
  (segment (start 111.4 65.78) (end 110.62 65.78) (width 0.109) (layer "In2.Cu") (net 290))
  (segment (start 110.5275 65.8725) (end 110.5275 65.997186) (width 0.109) (layer "In2.Cu") (net 290))
  (segment (start 115.880949 71.900635) (end 115.880949 72.35725) (width 0.109) (layer "In2.Cu") (net 290))
  (segment (start 113.4775 69.897186) (end 113.4775 70.997186) (width 0.109) (layer "In2.Cu") (net 290))
  (segment (start 111.5275 67.547186) (end 112.8775 68.897186) (width 0.109) (layer "In2.Cu") (net 290))
  (segment (start 112.8775 69.297186) (end 113.4775 69.897186) (width 0.109) (layer "In2.Cu") (net 290))
  (segment (start 116.224449 73.467572) (end 116.224449 73.189448) (width 0.182) (layer "B.Cu") (net 290))
  (segment (start 116.224449 73.189448) (end 115.913449 72.878448) (width 0.182) (layer "B.Cu") (net 290))
  (segment (start 115.913449 72.878448) (end 115.913449 72.66575) (width 0.182) (layer "B.Cu") (net 290))
  (segment (start 115.913449 72.66575) (end 116.051449 72.52775) (width 0.182) (layer "B.Cu") (net 290))
  (via (at 115.455449 72.52775) (size 0.45) (drill 0.1) (layers "F.Cu" "B.Cu") (net 291))
  (segment (start 115.625949 72.006263) (end 115.625949 72.35725) (width 0.109) (layer "In2.Cu") (net 291))
  (segment (start 111.2725 67.652814) (end 112.6225 69.002814) (width 0.109) (layer "In2.Cu") (net 291))
  (segment (start 112.6225 69.002814) (end 112.6225 69.402814) (width 0.109) (layer "In2.Cu") (net 291))
  (segment (start 113.2225 70.002814) (end 113.2225 71.102814) (width 0.109) (layer "In2.Cu") (net 291))
  (segment (start 112.6225 69.402814) (end 113.2225 70.002814) (width 0.109) (layer "In2.Cu") (net 291))
  (segment (start 113.2225 71.102814) (end 113.697186 71.5775) (width 0.109) (layer "In2.Cu") (net 291))
  (segment (start 109.4 65.78) (end 110.175 65.78) (width 0.109) (layer "In2.Cu") (net 291))
  (segment (start 113.697186 71.5775) (end 115.197186 71.5775) (width 0.109) (layer "In2.Cu") (net 291))
  (segment (start 110.2725 66.102814) (end 111.2725 67.102814) (width 0.109) (layer "In2.Cu") (net 291))
  (segment (start 115.625949 72.35725) (end 115.455449 72.52775) (width 0.109) (layer "In2.Cu") (net 291))
  (segment (start 111.2725 67.102814) (end 111.2725 67.652814) (width 0.109) (layer "In2.Cu") (net 291))
  (segment (start 115.197186 71.5775) (end 115.625949 72.006263) (width 0.109) (layer "In2.Cu") (net 291))
  (segment (start 110.175 65.78) (end 110.2725 65.8775) (width 0.109) (layer "In2.Cu") (net 291))
  (segment (start 110.2725 65.8775) (end 110.2725 66.102814) (width 0.109) (layer "In2.Cu") (net 291))
  (segment (start 115.224449 73.467572) (end 115.224449 73.19255) (width 0.182) (layer "B.Cu") (net 291))
  (segment (start 115.224449 73.19255) (end 115.535449 72.88155) (width 0.182) (layer "B.Cu") (net 291))
  (segment (start 115.535449 72.60775) (end 115.535449 72.88155) (width 0.182) (layer "B.Cu") (net 291))
  (segment (start 115.455449 72.52775) (end 115.535449 72.60775) (width 0.182) (layer "B.Cu") (net 291))
  (segment (start 113.69 73.514) (end 113.69 73.235876) (width 0.182) (layer "F.Cu") (net 292))
  (segment (start 113.69 73.235876) (end 113.379 72.924876) (width 0.182) (layer "F.Cu") (net 292))
  (segment (start 113.379 72.705177) (end 113.508 72.576177) (width 0.182) (layer "F.Cu") (net 292))
  (segment (start 113.379 72.924876) (end 113.379 72.705177) (width 0.182) (layer "F.Cu") (net 292))
  (via (at 113.508 72.576177) (size 0.45) (drill 0.1) (layers "F.Cu" "B.Cu") (net 292))
  (segment (start 111.5275 70.947186) (end 112.002814 71.4225) (width 0.109) (layer "In2.Cu") (net 292))
  (segment (start 111.4 68.98) (end 110.655 68.98) (width 0.109) (layer "In2.Cu") (net 292))
  (segment (start 112.802814 71.4225) (end 113.3375 71.957186) (width 0.109) (layer "In2.Cu") (net 292))
  (segment (start 112.002814 71.4225) (end 112.802814 71.4225) (width 0.109) (layer "In2.Cu") (net 292))
  (segment (start 113.3375 72.405677) (end 113.508 72.576177) (width 0.109) (layer "In2.Cu") (net 292))
  (segment (start 111.5275 70.197186) (end 111.5275 70.947186) (width 0.109) (layer "In2.Cu") (net 292))
  (segment (start 110.5275 69.1075) (end 110.5275 69.197186) (width 0.109) (layer "In2.Cu") (net 292))
  (segment (start 110.655 68.98) (end 110.5275 69.1075) (width 0.109) (layer "In2.Cu") (net 292))
  (segment (start 113.3375 71.957186) (end 113.3375 72.405677) (width 0.109) (layer "In2.Cu") (net 292))
  (segment (start 110.5275 69.197186) (end 111.5275 70.197186) (width 0.109) (layer "In2.Cu") (net 292))
  (segment (start 112.69 73.238978) (end 113.001 72.927978) (width 0.182) (layer "F.Cu") (net 293))
  (segment (start 112.69 73.514) (end 112.69 73.238978) (width 0.182) (layer "F.Cu") (net 293))
  (segment (start 113.001 72.665177) (end 112.912 72.576177) (width 0.182) (layer "F.Cu") (net 293))
  (segment (start 113.001 72.927978) (end 113.001 72.665177) (width 0.182) (layer "F.Cu") (net 293))
  (via (at 112.912 72.576177) (size 0.45) (drill 0.1) (layers "F.Cu" "B.Cu") (net 293))
  (segment (start 110.2725 69.302814) (end 111.2725 70.302814) (width 0.109) (layer "In2.Cu") (net 293))
  (segment (start 113.0825 72.405677) (end 112.912 72.576177) (width 0.109) (layer "In2.Cu") (net 293))
  (segment (start 111.2725 71.052814) (end 111.897186 71.6775) (width 0.109) (layer "In2.Cu") (net 293))
  (segment (start 110.15 68.98) (end 110.2725 69.1025) (width 0.109) (layer "In2.Cu") (net 293))
  (segment (start 112.697186 71.6775) (end 113.0825 72.062814) (width 0.109) (layer "In2.Cu") (net 293))
  (segment (start 109.4 68.98) (end 110.15 68.98) (width 0.109) (layer "In2.Cu") (net 293))
  (segment (start 113.0825 72.062814) (end 113.0825 72.405677) (width 0.109) (layer "In2.Cu") (net 293))
  (segment (start 110.2725 69.1025) (end 110.2725 69.302814) (width 0.109) (layer "In2.Cu") (net 293))
  (segment (start 111.2725 70.302814) (end 111.2725 71.052814) (width 0.109) (layer "In2.Cu") (net 293))
  (segment (start 111.897186 71.6775) (end 112.697186 71.6775) (width 0.109) (layer "In2.Cu") (net 293))
  (segment (start 126.118942 91.908942) (end 126.8125 92.6025) (width 0.182) (layer "F.Cu") (net 294))
  (segment (start 126.118942 90.323661) (end 126.118942 91.908942) (width 0.182) (layer "F.Cu") (net 294))
  (segment (start 145.034036 86.964036) (end 143.940722 85.870722) (width 0.182) (layer "F.Cu") (net 295))
  (segment (start 143.940722 85.870722) (end 143.357453 85.870722) (width 0.182) (layer "F.Cu") (net 295))
  (segment (start 145.44591 86.964036) (end 145.034036 86.964036) (width 0.182) (layer "F.Cu") (net 295))
  (segment (start 111.411 121.589) (end 113.466463 121.589) (width 0.178) (layer "F.Cu") (net 296))
  (segment (start 111.126 121.589) (end 111.411 121.589) (width 0.178) (layer "F.Cu") (net 296))
  (segment (start 111.411 121.589) (end 110.061 121.589) (width 0.178) (layer "F.Cu") (net 296))
  (segment (start 113.466463 121.589) (end 113.5054 121.550063) (width 0.178) (layer "F.Cu") (net 296))
  (segment (start 111 121.715) (end 111.126 121.589) (width 0.178) (layer "F.Cu") (net 296))
  (segment (start 110.061 121.589) (end 109.8 121.85) (width 0.178) (layer "F.Cu") (net 296))
  (segment (start 113.466463 121.011) (end 113.5054 121.049937) (width 0.178) (layer "F.Cu") (net 297))
  (segment (start 110.161 121.011) (end 109.8 120.65) (width 0.178) (layer "F.Cu") (net 297))
  (segment (start 111.414 121.011) (end 113.466463 121.011) (width 0.178) (layer "F.Cu") (net 297))
  (segment (start 111 120.885) (end 111.126 121.011) (width 0.178) (layer "F.Cu") (net 297))
  (segment (start 111.126 121.011) (end 111.414 121.011) (width 0.178) (layer "F.Cu") (net 297))
  (segment (start 111.414 121.011) (end 110.161 121.011) (width 0.178) (layer "F.Cu") (net 297))
  (segment (start 146.2 60.9) (end 146.511 60.589) (width 0.182) (layer "F.Cu") (net 298))
  (segment (start 146.449 60.211501) (end 146.449 59.349) (width 0.182) (layer "F.Cu") (net 298))
  (segment (start 147.449 58.526698) (end 147.498381 58.477317) (width 0.2) (layer "F.Cu") (net 298))
  (segment (start 146.511 60.273501) (end 146.449 60.211501) (width 0.182) (layer "F.Cu") (net 298))
  (segment (start 146.449 58.5268) (end 146.399622 58.477422) (width 0.2) (layer "F.Cu") (net 298))
  (segment (start 147.449 59.349) (end 147.449 58.526698) (width 0.2) (layer "F.Cu") (net 298))
  (segment (start 146.449 59.349) (end 146.449 58.5268) (width 0.2) (layer "F.Cu") (net 298))
  (segment (start 146.2 61.15) (end 146.2 60.9) (width 0.182) (layer "F.Cu") (net 298))
  (segment (start 146.511 60.589) (end 146.511 60.273501) (width 0.182) (layer "F.Cu") (net 298))
  (via (at 147.498381 58.477317) (size 0.45) (drill 0.1) (layers "F.Cu" "B.Cu") (net 298))
  (via (at 146.399622 58.477422) (size 0.45) (drill 0.1) (layers "F.Cu" "B.Cu") (net 298))
  (segment (start 147.498381 58.795515) (end 147.343896 58.95) (width 0.182) (layer "B.Cu") (net 298))
  (segment (start 146.399622 58.79562) (end 146.399622 58.477422) (width 0.182) (layer "B.Cu") (net 298))
  (segment (start 147.343896 58.95) (end 146.554002 58.95) (width 0.182) (layer "B.Cu") (net 298))
  (segment (start 146.554002 58.95) (end 146.399622 58.79562) (width 0.182) (layer "B.Cu") (net 298))
  (segment (start 147.498381 58.477317) (end 147.498381 58.795515) (width 0.182) (layer "B.Cu") (net 298))
  (segment (start 147.2 60.9) (end 146.889 60.589) (width 0.182) (layer "F.Cu") (net 299))
  (segment (start 145.949 59.349) (end 145.949 58.54231) (width 0.2) (layer "F.Cu") (net 299))
  (segment (start 146.948999 58.573999) (end 146.948999 58.451001) (width 0.2) (layer "F.Cu") (net 299))
  (segment (start 146.949 59.349) (end 146.948999 58.573999) (width 0.2) (layer "F.Cu") (net 299))
  (segment (start 146.889 60.589) (end 146.889 60.273501) (width 0.182) (layer "F.Cu") (net 299))
  (segment (start 146.949 60.211501) (end 146.949 59.349) (width 0.182) (layer "F.Cu") (net 299))
  (segment (start 145.949 58.54231) (end 145.85063 58.44394) (width 0.2) (layer "F.Cu") (net 299))
  (segment (start 146.889 60.273501) (end 146.888 60.272501) (width 0.182) (layer "F.Cu") (net 299))
  (segment (start 147.2 61.15) (end 147.2 60.9) (width 0.182) (layer "F.Cu") (net 299))
  (segment (start 146.888 60.272501) (end 146.949 60.211501) (width 0.182) (layer "F.Cu") (net 299))
  (via (at 145.85063 58.44394) (size 0.45) (drill 0.1) (layers "F.Cu" "B.Cu") (net 299))
  (via (at 146.948999 58.451001) (size 0.45) (drill 0.1) (layers "F.Cu" "B.Cu") (net 299))
  (segment (start 146.866196 58.05) (end 145.926372 58.05) (width 0.2) (layer "B.Cu") (net 299))
  (segment (start 146.948999 58.451001) (end 146.948999 58.132803) (width 0.2) (layer "B.Cu") (net 299))
  (segment (start 145.926372 58.05) (end 145.85063 58.125742) (width 0.2) (layer "B.Cu") (net 299))
  (segment (start 145.85063 58.125742) (end 145.85063 58.44394) (width 0.2) (layer "B.Cu") (net 299))
  (segment (start 146.948999 58.132803) (end 146.866196 58.05) (width 0.2) (layer "B.Cu") (net 299))
  (segment (start 143.991 60.759) (end 143.991 61.153) (width 0.182) (layer "F.Cu") (net 300))
  (segment (start 144.548 60.45) (end 144.3 60.45) (width 0.182) (layer "F.Cu") (net 300))
  (segment (start 144.949 60.049) (end 144.548 60.45) (width 0.182) (layer "F.Cu") (net 300))
  (segment (start 144.3 60.45) (end 143.991 60.759) (width 0.182) (layer "F.Cu") (net 300))
  (segment (start 144.949 59.349) (end 144.949 60.049) (width 0.2) (layer "F.Cu") (net 300))
  (segment (start 144.987 61.153) (end 144.987 60.613) (width 0.182) (layer "F.Cu") (net 301))
  (segment (start 144.987 60.613) (end 145.1 60.5) (width 0.182) (layer "F.Cu") (net 301))
  (segment (start 147.949 59.349) (end 147.949 60.299) (width 0.182) (layer "F.Cu") (net 301))
  (segment (start 147.949 60.299) (end 147.95 60.3) (width 0.182) (layer "F.Cu") (net 301))
  (via (at 145.1 60.5) (size 0.45) (drill 0.1) (layers "F.Cu" "B.Cu") (net 301))
  (via (at 147.95 60.3) (size 0.45) (drill 0.1) (layers "F.Cu" "B.Cu") (net 301))
  (segment (start 145.1 60.5) (end 147.75 60.5) (width 0.182) (layer "In6.Cu") (net 301))
  (segment (start 147.75 60.5) (end 147.95 60.3) (width 0.182) (layer "In6.Cu") (net 301))
  (segment (start 136.9 74.5) (end 137.15 74.25) (width 0.182) (layer "F.Cu") (net 302))
  (segment (start 137.15 74.25) (end 137.99 74.25) (width 0.182) (layer "F.Cu") (net 302))
  (segment (start 142.315 72.925) (end 143.075 72.925) (width 0.182) (layer "F.Cu") (net 302))
  (segment (start 116.330142 83.334861) (end 114.754861 83.334861) (width 0.182) (layer "F.Cu") (net 302))
  (segment (start 137.99 74.25) (end 138.015 74.225) (width 0.182) (layer "F.Cu") (net 302))
  (segment (start 114.754861 83.334861) (end 113.39 81.97) (width 0.182) (layer "F.Cu") (net 302))
  (segment (start 113.39 78.39) (end 114.08 77.7) (width 0.182) (layer "F.Cu") (net 302))
  (segment (start 113.39 81.97) (end 113.39 78.39) (width 0.182) (layer "F.Cu") (net 302))
  (segment (start 114.08 77.7) (end 114.175 77.7) (width 0.182) (layer "F.Cu") (net 302))
  (segment (start 143.075 72.925) (end 143.4 72.6) (width 0.182) (layer "F.Cu") (net 302))
  (via (at 136.9 74.5) (size 0.45) (drill 0.1) (layers "F.Cu" "B.Cu") (net 302))
  (via (at 143.4 72.6) (size 0.45) (drill 0.1) (layers "F.Cu" "B.Cu") (net 302))
  (via (at 114.175 77.7) (size 0.45) (drill 0.1) (layers "F.Cu" "B.Cu") (net 302))
  (segment (start 114.175 77.7) (end 114.175 75.925) (width 0.109) (layer "In4.Cu") (net 302))
  (segment (start 137.125 71.095) (end 137.295 70.925) (width 0.109) (layer "In4.Cu") (net 302))
  (segment (start 127.475 74.225) (end 131.225 74.225) (width 0.109) (layer "In4.Cu") (net 302))
  (segment (start 138.43 71.65) (end 142.84 71.65) (width 0.109) (layer "In4.Cu") (net 302))
  (segment (start 136.6 74.8) (end 136.9 74.5) (width 0.109) (layer "In4.Cu") (net 302))
  (segment (start 114.975 75.125) (end 116.065 75.125) (width 0.109) (layer "In4.Cu") (net 302))
  (segment (start 136.9 74.5) (end 137.125 74.275) (width 0.109) (layer "In4.Cu") (net 302))
  (segment (start 116.54 75.85) (end 119.275 75.85) (width 0.109) (layer "In4.Cu") (net 302))
  (segment (start 143.72 72.6) (end 143.4 72.6) (width 0.109) (layer "In4.Cu") (net 302))
  (segment (start 137.125 74.275) (end 137.125 71.095) (width 0.109) (layer "In4.Cu") (net 302))
  (segment (start 120 75.125) (end 126.575 75.125) (width 0.109) (layer "In4.Cu") (net 302))
  (segment (start 116.065 75.125) (end 116.345 75.405) (width 0.109) (layer "In4.Cu") (net 302))
  (segment (start 137.295 70.925) (end 137.705 70.925) (width 0.109) (layer "In4.Cu") (net 302))
  (segment (start 126.575 75.125) (end 127.475 74.225) (width 0.109) (layer "In4.Cu") (net 302))
  (segment (start 143.855 71.68) (end 143.855 72.465) (width 0.109) (layer "In4.Cu") (net 302))
  (segment (start 116.345 75.655) (end 116.54 75.85) (width 0.109) (layer "In4.Cu") (net 302))
  (segment (start 142.84 71.65) (end 143.115 71.375) (width 0.109) (layer "In4.Cu") (net 302))
  (segment (start 119.275 75.85) (end 120 75.125) (width 0.109) (layer "In4.Cu") (net 302))
  (segment (start 143.855 72.465) (end 143.72 72.6) (width 0.109) (layer "In4.Cu") (net 302))
  (segment (start 131.8 74.8) (end 136.6 74.8) (width 0.109) (layer "In4.Cu") (net 302))
  (segment (start 114.175 75.925) (end 114.975 75.125) (width 0.109) (layer "In4.Cu") (net 302))
  (segment (start 137.705 70.925) (end 138.43 71.65) (width 0.109) (layer "In4.Cu") (net 302))
  (segment (start 131.225 74.225) (end 131.8 74.8) (width 0.109) (layer "In4.Cu") (net 302))
  (segment (start 143.115 71.375) (end 143.55 71.375) (width 0.109) (layer "In4.Cu") (net 302))
  (segment (start 143.55 71.375) (end 143.855 71.68) (width 0.109) (layer "In4.Cu") (net 302))
  (segment (start 116.345 75.405) (end 116.345 75.655) (width 0.109) (layer "In4.Cu") (net 302))
  (segment (start 142.315 72.275) (end 143.125 72.275) (width 0.182) (layer "F.Cu") (net 303))
  (segment (start 136.95 71.75) (end 136.95 71.525) (width 0.182) (layer "F.Cu") (net 303))
  (segment (start 114.855 77.725) (end 114.875 77.725) (width 0.182) (layer "F.Cu") (net 303))
  (segment (start 113.9 81.78) (end 113.9 78.68) (width 0.182) (layer "F.Cu") (net 303))
  (segment (start 136.95 71.525) (end 137.125 71.35) (width 0.182) (layer "F.Cu") (net 303))
  (segment (start 113.9 78.68) (end 114.855 77.725) (width 0.182) (layer "F.Cu") (net 303))
  (segment (start 143.125 72.275) (end 143.4 72) (width 0.182) (layer "F.Cu") (net 303))
  (segment (start 116.330142 82.53486) (end 114.65486 82.53486) (width 0.182) (layer "F.Cu") (net 303))
  (segment (start 138.015 72.275) (end 137.475 72.275) (width 0.182) (layer "F.Cu") (net 303))
  (segment (start 137.475 72.275) (end 136.95 71.75) (width 0.182) (layer "F.Cu") (net 303))
  (segment (start 137.125 71.35) (end 137.525 71.35) (width 0.182) (layer "F.Cu") (net 303))
  (segment (start 114.65486 82.53486) (end 113.9 81.78) (width 0.182) (layer "F.Cu") (net 303))
  (via (at 137.525 71.35) (size 0.45) (drill 0.1) (layers "F.Cu" "B.Cu") (net 303))
  (via (at 143.4 72) (size 0.45) (drill 0.1) (layers "F.Cu" "B.Cu") (net 303))
  (via (at 114.875 77.725) (size 0.45) (drill 0.1) (layers "F.Cu" "B.Cu") (net 303))
  (segment (start 119.5 76.15) (end 120.25 75.4) (width 0.109) (layer "In4.Cu") (net 303))
  (segment (start 137.675 72) (end 137.6 72) (width 0.109) (layer "In4.Cu") (net 303))
  (segment (start 126.674545 75.4) (end 127.599545 74.475) (width 0.109) (layer "In4.Cu") (net 303))
  (segment (start 137.6 72) (end 137.525 72.075) (width 0.109) (layer "In4.Cu") (net 303))
  (segment (start 131.675 75.05) (end 136.925 75.05) (width 0.109) (layer "In4.Cu") (net 303))
  (segment (start 137.525 71.925) (end 137.525 71.35) (width 0.109) (layer "In4.Cu") (net 303))
  (segment (start 114.875 77.725) (end 114.875 75.675) (width 0.109) (layer "In4.Cu") (net 303))
  (segment (start 115.98443 75.4) (end 116.107215 75.522785) (width 0.109) (layer "In4.Cu") (net 303))
  (segment (start 127.599545 74.475) (end 131.1 74.475) (width 0.109) (layer "In4.Cu") (net 303))
  (segment (start 137.675 72) (end 143.4 72) (width 0.109) (layer "In4.Cu") (net 303))
  (segment (start 116.39 76.15) (end 119.5 76.15) (width 0.109) (layer "In4.Cu") (net 303))
  (segment (start 137.525 74.45) (end 137.525 72.575) (width 0.109) (layer "In4.Cu") (net 303))
  (segment (start 131.1 74.475) (end 131.675 75.05) (width 0.109) (layer "In4.Cu") (net 303))
  (segment (start 137.525 72.075) (end 137.525 71.925) (width 0.109) (layer "In4.Cu") (net 303))
  (segment (start 116.107215 75.522785) (end 116.107215 75.867215) (width 0.109) (layer "In4.Cu") (net 303))
  (segment (start 137.525 72.575) (end 137.525 72) (width 0.109) (layer "In4.Cu") (net 303))
  (segment (start 137.6 72) (end 137.525 71.925) (width 0.109) (layer "In4.Cu") (net 303))
  (segment (start 137.525 72.575) (end 137.525 72.075) (width 0.109) (layer "In4.Cu") (net 303))
  (segment (start 116.107215 75.867215) (end 116.39 76.15) (width 0.109) (layer "In4.Cu") (net 303))
  (segment (start 137.525 72) (end 137.675 72) (width 0.109) (layer "In4.Cu") (net 303))
  (segment (start 120.25 75.4) (end 126.674545 75.4) (width 0.109) (layer "In4.Cu") (net 303))
  (segment (start 114.875 75.675) (end 115.15 75.4) (width 0.109) (layer "In4.Cu") (net 303))
  (segment (start 136.925 75.05) (end 137.525 74.45) (width 0.109) (layer "In4.Cu") (net 303))
  (segment (start 115.15 75.4) (end 115.98443 75.4) (width 0.109) (layer "In4.Cu") (net 303))
  (segment (start 116.87 75.09) (end 116.5 75.46) (width 0.182) (layer "F.Cu") (net 304))
  (segment (start 116.5 75.46) (end 116.5 76.78) (width 0.182) (layer "F.Cu") (net 304))
  (segment (start 114.4 78.88) (end 114.4 81.58) (width 0.182) (layer "F.Cu") (net 304))
  (segment (start 122.468 73.773) (end 123.293 73.773) (width 0.182) (layer "F.Cu") (net 304))
  (segment (start 123.6 73.466) (end 123.6 72.6) (width 0.182) (layer "F.Cu") (net 304))
  (segment (start 116.887 75.073) (end 116.87 75.09) (width 0.109) (layer "F.Cu") (net 304))
  (segment (start 123.293 73.773) (end 123.6 73.466) (width 0.182) (layer "F.Cu") (net 304))
  (segment (start 116.5 76.78) (end 114.4 78.88) (width 0.182) (layer "F.Cu") (net 304))
  (segment (start 114.4 81.58) (end 114.954861 82.134861) (width 0.182) (layer "F.Cu") (net 304))
  (segment (start 114.954861 82.134861) (end 116.330142 82.134861) (width 0.182) (layer "F.Cu") (net 304))
  (segment (start 118.169 75.073) (end 116.887 75.073) (width 0.109) (layer "F.Cu") (net 304))
  (via (at 116.87 75.09) (size 0.45) (drill 0.1) (layers "F.Cu" "B.Cu") (net 304))
  (via (at 123.6 72.6) (size 0.45) (drill 0.1) (layers "F.Cu" "B.Cu") (net 304))
  (segment (start 116.87 75.09) (end 118.525 73.435) (width 0.109) (layer "In4.Cu") (net 304))
  (segment (start 118.525 73.435) (end 118.525 73.05) (width 0.109) (layer "In4.Cu") (net 304))
  (segment (start 118.525 73.05) (end 118.975 72.6) (width 0.109) (layer "In4.Cu") (net 304))
  (segment (start 118.975 72.6) (end 123.6 72.6) (width 0.109) (layer "In4.Cu") (net 304))
  (segment (start 116.308458 81.756546) (end 116.330142 81.734862) (width 0.182) (layer "F.Cu") (net 305))
  (segment (start 115.291386 81.756546) (end 116.308458 81.756546) (width 0.182) (layer "F.Cu") (net 305))
  (segment (start 114.913998 79.053998) (end 114.913998 81.379158) (width 0.182) (layer "F.Cu") (net 305))
  (segment (start 114.87 79.01) (end 114.913998 79.053998) (width 0.182) (layer "F.Cu") (net 305))
  (segment (start 122.45 72.1) (end 122.45 73.014) (width 0.182) (layer "F.Cu") (net 305))
  (segment (start 118.17 72.63) (end 118.169 72.631) (width 0.182) (layer "F.Cu") (net 305))
  (segment (start 118.169 72.631) (end 118.169 73.124) (width 0.182) (layer "F.Cu") (net 305))
  (segment (start 114.913998 81.379158) (end 115.291386 81.756546) (width 0.182) (layer "F.Cu") (net 305))
  (via (at 114.87 79.01) (size 0.4) (drill 0.15) (layers "F.Cu" "B.Cu") (net 305))
  (via (at 118.17 72.63) (size 0.45) (drill 0.1) (layers "F.Cu" "B.Cu") (net 305))
  (via (at 122.45 72.1) (size 0.45) (drill 0.1) (layers "F.Cu" "B.Cu") (net 305))
  (segment (start 113.7 77.84) (end 113.7 77.48) (width 0.109) (layer "In4.Cu") (net 305))
  (segment (start 118.17 73.22) (end 118.17 72.63) (width 0.109) (layer "In4.Cu") (net 305))
  (segment (start 114.86 74.84) (end 116.55 74.84) (width 0.109) (layer "In4.Cu") (net 305))
  (segment (start 113.8665 75.8335) (end 114.86 74.84) (width 0.109) (layer "In4.Cu") (net 305))
  (segment (start 114.87 79.01) (end 113.7 77.84) (width 0.109) (layer "In4.Cu") (net 305))
  (segment (start 122.45 72.1) (end 122.3 72.25) (width 0.109) (layer "In4.Cu") (net 305))
  (segment (start 113.7 77.48) (end 113.8665 77.3135) (width 0.109) (layer "In4.Cu") (net 305))
  (segment (start 118.55 72.25) (end 118.17 72.63) (width 0.109) (layer "In4.Cu") (net 305))
  (segment (start 116.55 74.84) (end 118.17 73.22) (width 0.109) (layer "In4.Cu") (net 305))
  (segment (start 113.8665 77.3135) (end 113.8665 75.8335) (width 0.109) (layer "In4.Cu") (net 305))
  (segment (start 122.3 72.25) (end 118.55 72.25) (width 0.109) (layer "In4.Cu") (net 305))
  (segment (start 143.45 73.575) (end 142.34 73.575) (width 0.4) (layer "F.Cu") (net 306))
  (segment (start 143.85 73.975) (end 143.45 73.575) (width 0.4) (layer "F.Cu") (net 306))
  (segment (start 143.85 74.6) (end 143.85 73.975) (width 0.4) (layer "F.Cu") (net 306))
  (segment (start 142.96 75.49) (end 143.85 74.6) (width 0.4) (layer "F.Cu") (net 306))
  (segment (start 142.96 75.575) (end 142.96 75.49) (width 0.4) (layer "F.Cu") (net 306))
  (segment (start 142.96 75.735) (end 142.96 75.575) (width 0.4) (layer "F.Cu") (net 306))
  (segment (start 142.96 75.735) (end 144.200501 76.975501) (width 0.4) (layer "F.Cu") (net 306))
  (segment (start 145.877001 78.574999) (end 145.101001 78.574999) (width 0.4) (layer "F.Cu") (net 306))
  (segment (start 145.952002 78.65) (end 145.877001 78.574999) (width 0.4) (layer "F.Cu") (net 306))
  (segment (start 146.225 78.65) (end 145.952002 78.65) (width 0.4) (layer "F.Cu") (net 306))
  (segment (start 144.200501 77.674499) (end 144.200501 76.975501) (width 0.4) (layer "F.Cu") (net 306))
  (segment (start 145.101001 78.574999) (end 144.200501 77.674499) (width 0.4) (layer "F.Cu") (net 306))
  (segment (start 124.56 73.326) (end 123.85 74.036) (width 0.4) (layer "F.Cu") (net 306))
  (segment (start 124.56 72.9) (end 124.56 73.326) (width 0.4) (layer "F.Cu") (net 306))
  (segment (start 123.466 74.42) (end 123.85 74.036) (width 0.4) (layer "F.Cu") (net 306))
  (segment (start 122.215 74.42) (end 123.466 74.42) (width 0.4) (layer "F.Cu") (net 306))
  (segment (start 142.935 75.575) (end 142.935 75.49) (width 0.4) (layer "F.Cu") (net 306))
  (via (at 148.625 78.65) (size 0.5) (drill 0.15) (layers "F.Cu" "B.Cu") (net 306))
  (via (at 148.025 78.65) (size 0.5) (drill 0.15) (layers "F.Cu" "B.Cu") (net 306))
  (via (at 147.425 78.65) (size 0.5) (drill 0.15) (layers "F.Cu" "B.Cu") (net 306))
  (via (at 146.825 78.65) (size 0.5) (drill 0.15) (layers "F.Cu" "B.Cu") (net 306))
  (via (at 146.225 78.65) (size 0.5) (drill 0.15) (layers "F.Cu" "B.Cu") (net 306))
  (via (at 102.25 86.74) (size 0.5) (drill 0.15) (layers "F.Cu" "B.Cu") (net 306))
  (via (at 102.8 86.19) (size 0.5) (drill 0.15) (layers "F.Cu" "B.Cu") (net 306))
  (via (at 102.25 86.19) (size 0.5) (drill 0.15) (layers "F.Cu" "B.Cu") (net 306))
  (via (at 102.8 86.74) (size 0.5) (drill 0.15) (layers "F.Cu" "B.Cu") (net 306))
  (via (at 124.56 72.9) (size 0.5) (drill 0.15) (layers "F.Cu" "B.Cu") (net 306))
  (segment (start 102.71 86.74) (end 103 86.74) (width 0.4) (layer "In2.Cu") (net 306))
  (segment (start 102.45 86.74) (end 102.71 86.74) (width 0.4) (layer "In2.Cu") (net 306))
  (segment (start 102.71 86.74) (end 102.71 86.34) (width 0.4) (layer "In2.Cu") (net 306))
  (segment (start 102.45 86.19) (end 102.86 86.19) (width 0.4) (layer "In2.Cu") (net 306))
  (segment (start 102.86 86.19) (end 103 86.19) (width 0.4) (layer "In2.Cu") (net 306))
  (segment (start 102.71 86.34) (end 102.86 86.19) (width 0.4) (layer "In2.Cu") (net 306))
  (segment (start 103 86.19) (end 103 86.74) (width 0.4) (layer "In2.Cu") (net 306))
  (segment (start 102.45 86.19) (end 102.45 86.74) (width 0.4) (layer "In2.Cu") (net 306))
  (segment (start 102.9 86.09) (end 103 86.19) (width 0.4) (layer "In2.Cu") (net 306))
  (segment (start 146.15 78.575) (end 146.225 78.65) (width 0.4) (layer "In2.Cu") (net 306))
  (segment (start 146.225 78.65) (end 148.625 78.65) (width 0.4) (layer "In2.Cu") (net 306))
  (segment (start 144.5 78.15) (end 144.925 78.575) (width 0.4) (layer "In2.Cu") (net 306))
  (segment (start 101.7 61.2) (end 104.9 58) (width 0.4) (layer "In2.Cu") (net 306))
  (segment (start 101.7 84.4) (end 101.7 61.2) (width 0.4) (layer "In2.Cu") (net 306))
  (segment (start 104.9 58) (end 137.25 58) (width 0.4) (layer "In2.Cu") (net 306))
  (segment (start 144.925 78.575) (end 146.15 78.575) (width 0.4) (layer "In2.Cu") (net 306))
  (segment (start 144.475 65.225) (end 144.475 70.882537) (width 0.4) (layer "In2.Cu") (net 306))
  (segment (start 102.45 85.15) (end 101.7 84.4) (width 0.4) (layer "In2.Cu") (net 306))
  (segment (start 137.25 58) (end 144.475 65.225) (width 0.4) (layer "In2.Cu") (net 306))
  (segment (start 144.475 70.882537) (end 144.5 70.907537) (width 0.4) (layer "In2.Cu") (net 306))
  (segment (start 102.45 86.19) (end 102.45 85.15) (width 0.4) (layer "In2.Cu") (net 306))
  (segment (start 144.5 70.907537) (end 144.5 78.15) (width 0.4) (layer "In2.Cu") (net 306))
  (segment (start 101.535 87.45) (end 102.75 87.45) (width 0.4) (layer "B.Cu") (net 306))
  (segment (start 99.8 86.7) (end 102.21 86.7) (width 0.182) (layer "B.Cu") (net 306))
  (segment (start 102.21 86.7) (end 102.25 86.74) (width 0.182) (layer "B.Cu") (net 306))
  (segment (start 99.5 87) (end 99.8 86.7) (width 0.182) (layer "B.Cu") (net 306))
  (segment (start 99.485 87.45) (end 99.5 87.435) (width 0.182) (layer "B.Cu") (net 306))
  (segment (start 99.5 87.435) (end 99.5 87) (width 0.182) (layer "B.Cu") (net 306))
  (segment (start 145.918198 113.05) (end 145.6 113.05) (width 0.182) (layer "F.Cu") (net 307))
  (segment (start 146.162826 113.294628) (end 145.918198 113.05) (width 0.182) (layer "F.Cu") (net 307))
  (segment (start 146.26 113.99) (end 146.162826 113.892826) (width 0.182) (layer "F.Cu") (net 307))
  (segment (start 144.987 62.649) (end 144.987 63.197) (width 0.182) (layer "F.Cu") (net 307))
  (segment (start 146.26 114.425) (end 146.26 113.99) (width 0.182) (layer "F.Cu") (net 307))
  (segment (start 146.162826 113.892826) (end 146.162826 113.294628) (width 0.182) (layer "F.Cu") (net 307))
  (segment (start 144.987 63.197) (end 145.105 63.315) (width 0.182) (layer "F.Cu") (net 307))
  (via (at 145.105 63.315) (size 0.45) (drill 0.1) (layers "F.Cu" "B.Cu") (net 307))
  (via (at 145.6 113.05) (size 0.45) (drill 0.1) (layers "F.Cu" "B.Cu") (net 307))
  (segment (start 134.009011 81.540989) (end 142.35 73.2) (width 0.109) (layer "In6.Cu") (net 307))
  (segment (start 133.811478 98.311478) (end 133.811478 91.545998) (width 0.109) (layer "In6.Cu") (net 307))
  (segment (start 147.425 112.725) (end 147.425 112.05) (width 0.109) (layer "In6.Cu") (net 307))
  (segment (start 142.35 66.07) (end 145.105 63.315) (width 0.109) (layer "In6.Cu") (net 307))
  (segment (start 148.625 111.7) (end 149.5 110.825) (width 0.109) (layer "In6.Cu") (net 307))
  (segment (start 147.93 103.5) (end 139 103.5) (width 0.109) (layer "In6.Cu") (net 307))
  (segment (start 149.5 105.07) (end 147.93 103.5) (width 0.109) (layer "In6.Cu") (net 307))
  (segment (start 147.1 113.05) (end 147.425 112.725) (width 0.109) (layer "In6.Cu") (net 307))
  (segment (start 133.811478 91.545998) (end 133.711477 91.445997) (width 0.109) (layer "In6.Cu") (net 307))
  (segment (start 149.5 110.825) (end 149.5 105.07) (width 0.109) (layer "In6.Cu") (net 307))
  (segment (start 133.711477 91.445997) (end 133.711478 90.654002) (width 0.109) (layer "In6.Cu") (net 307))
  (segment (start 147.775 111.7) (end 148.625 111.7) (width 0.109) (layer "In6.Cu") (net 307))
  (segment (start 142.35 73.2) (end 142.35 66.07) (width 0.109) (layer "In6.Cu") (net 307))
  (segment (start 134.009011 90.356469) (end 134.009011 81.540989) (width 0.109) (layer "In6.Cu") (net 307))
  (segment (start 145.6 113.05) (end 147.1 113.05) (width 0.109) (layer "In6.Cu") (net 307))
  (segment (start 139 103.5) (end 133.811478 98.311478) (width 0.109) (layer "In6.Cu") (net 307))
  (segment (start 133.711478 90.654002) (end 134.009011 90.356469) (width 0.109) (layer "In6.Cu") (net 307))
  (segment (start 147.425 112.05) (end 147.775 111.7) (width 0.109) (layer "In6.Cu") (net 307))
  (segment (start 147.46 114.425) (end 147.46 114.065) (width 0.182) (layer "F.Cu") (net 308))
  (segment (start 147.3 113.905) (end 147.3 112.7) (width 0.182) (layer "F.Cu") (net 308))
  (segment (start 143.991 63.140996) (end 144.130002 63.279998) (width 0.182) (layer "F.Cu") (net 308))
  (segment (start 147.46 114.065) (end 147.3 113.905) (width 0.182) (layer "F.Cu") (net 308))
  (segment (start 147.3 112.7) (end 146.899323 112.299323) (width 0.182) (layer "F.Cu") (net 308))
  (segment (start 143.991 62.649) (end 143.991 63.140996) (width 0.182) (layer "F.Cu") (net 308))
  (via (at 146.899323 112.299323) (size 0.45) (drill 0.1) (layers "F.Cu" "B.Cu") (net 308))
  (via (at 144.130002 63.279998) (size 0.45) (drill 0.1) (layers "F.Cu" "B.Cu") (net 308))
  (segment (start 148.47 110.08) (end 149.1 109.45) (width 0.109) (layer "In6.Cu") (net 308))
  (segment (start 133.502468 90.567426) (end 133.8 90.269894) (width 0.109) (layer "In6.Cu") (net 308))
  (segment (start 147.59 103.85) (end 138.8 103.85) (width 0.109) (layer "In6.Cu") (net 308))
  (segment (start 133.8 90.269894) (end 133.8 81.25) (width 0.109) (layer "In6.Cu") (net 308))
  (segment (start 138.8 103.85) (end 133.6 98.65) (width 0.109) (layer "In6.Cu") (net 308))
  (segment (start 144.130002 63.869998) (end 144.130002 63.279998) (width 0.109) (layer "In6.Cu") (net 308))
  (segment (start 133.6 98.65) (end 133.6 91.630106) (width 0.109) (layer "In6.Cu") (net 308))
  (segment (start 147.27 110.08) (end 148.47 110.08) (width 0.109) (layer "In6.Cu") (net 308))
  (segment (start 146.899323 112.299323) (end 146.46 111.86) (width 0.109) (layer "In6.Cu") (net 308))
  (segment (start 142.05 65.95) (end 144.130002 63.869998) (width 0.109) (layer "In6.Cu") (net 308))
  (segment (start 146.46 110.89) (end 147.27 110.08) (width 0.109) (layer "In6.Cu") (net 308))
  (segment (start 133.6 91.630106) (end 133.502467 91.532571) (width 0.109) (layer "In6.Cu") (net 308))
  (segment (start 146.46 111.86) (end 146.46 110.89) (width 0.109) (layer "In6.Cu") (net 308))
  (segment (start 133.8 81.25) (end 142.05 73) (width 0.109) (layer "In6.Cu") (net 308))
  (segment (start 149.1 105.36) (end 147.59 103.85) (width 0.109) (layer "In6.Cu") (net 308))
  (segment (start 149.1 109.45) (end 149.1 105.36) (width 0.109) (layer "In6.Cu") (net 308))
  (segment (start 133.502467 91.532571) (end 133.502468 90.567426) (width 0.109) (layer "In6.Cu") (net 308))
  (segment (start 142.05 73) (end 142.05 65.95) (width 0.109) (layer "In6.Cu") (net 308))
  (segment (start 150.65 106.922502) (end 150.652498 106.925) (width 0.2) (layer "F.Cu") (net 313))
  (segment (start 154.2 109.9) (end 154.2 108.85) (width 0.4) (layer "F.Cu") (net 313))
  (segment (start 152.55 106.5) (end 152.4 106.35) (width 0.182) (layer "F.Cu") (net 313))
  (segment (start 151.4 106.35) (end 151.25 106.5) (width 0.182) (layer "F.Cu") (net 313))
  (segment (start 151.25 110.025) (end 151.25 109.5) (width 0.2) (layer "F.Cu") (net 313))
  (segment (start 152.55 106.925) (end 152.55 106.5) (width 0.182) (layer "F.Cu") (net 313))
  (segment (start 152.4 106.35) (end 151.4 106.35) (width 0.182) (layer "F.Cu") (net 313))
  (segment (start 151.25 109.5) (end 152.45 109.5) (width 0.182) (layer "F.Cu") (net 313))
  (segment (start 152.45 109.5) (end 152.55 109.6) (width 0.182) (layer "F.Cu") (net 313))
  (segment (start 150.652498 106.925) (end 151.25 106.925) (width 0.2) (layer "F.Cu") (net 313))
  (segment (start 151.25 106.5) (end 151.25 106.925) (width 0.182) (layer "F.Cu") (net 313))
  (segment (start 152.55 109.6) (end 152.55 110.025) (width 0.182) (layer "F.Cu") (net 313))
  (via (at 151.25 109.5) (size 0.45) (drill 0.1) (layers "F.Cu" "B.Cu") (net 313))
  (via (at 150.65 106.922502) (size 0.45) (drill 0.1) (layers "F.Cu" "B.Cu") (net 313))
  (segment (start 151.25 110.2) (end 151.3 110.25) (width 0.2) (layer "B.Cu") (net 313))
  (segment (start 151.072502 106.922502) (end 151.3 107.15) (width 0.2) (layer "B.Cu") (net 313))
  (segment (start 150.65 106.922502) (end 151.072502 106.922502) (width 0.2) (layer "B.Cu") (net 313))
  (segment (start 151.25 109.5) (end 151.25 110.2) (width 0.2) (layer "B.Cu") (net 313))
  (segment (start 130.725334 149.325334) (end 130.725 149.325) (width 0.182) (layer "F.Cu") (net 317))
  (segment (start 130.725334 150.604218) (end 130.725334 149.325334) (width 0.182) (layer "F.Cu") (net 317))
  (via (at 130.725 149.325) (size 0.45) (drill 0.1) (layers "F.Cu" "B.Cu") (net 317))
  (segment (start 130.725 149.325) (end 130.725 148.925) (width 0.4) (layer "B.Cu") (net 317))
  (segment (start 129.75 146.15) (end 129.75 147.135) (width 0.4) (layer "B.Cu") (net 317))
  (segment (start 130.725 148.925) (end 129.765 147.965) (width 0.4) (layer "B.Cu") (net 317))
  (segment (start 128.485 146.065) (end 128.5 146.05) (width 0.182) (layer "B.Cu") (net 317))
  (segment (start 129.765 147.965) (end 129.765 147.15) (width 0.4) (layer "B.Cu") (net 317))
  (segment (start 129.65 146.05) (end 129.75 146.15) (width 0.4) (layer "B.Cu") (net 317))
  (segment (start 125.05 146.065) (end 128.485 146.065) (width 0.182) (layer "B.Cu") (net 317))
  (segment (start 129.75 147.135) (end 129.765 147.15) (width 0.4) (layer "B.Cu") (net 317))
  (segment (start 128.5 146.05) (end 129.65 146.05) (width 0.4) (layer "B.Cu") (net 317))
  (via (at 140.645238 151.107285) (size 0.55) (drill 0.2) (layers "F.Cu" "B.Cu") (net 318))
  (segment (start 124.518942 90.323661) (end 124.518942 90.727261) (width 0.182) (layer "F.Cu") (net 320))
  (segment (start 124.861 91.503288) (end 124.861 92.164) (width 0.182) (layer "F.Cu") (net 320))
  (segment (start 124.529942 91.17223) (end 124.861 91.503288) (width 0.182) (layer "F.Cu") (net 320))
  (segment (start 124.529942 90.738261) (end 124.529942 91.17223) (width 0.182) (layer "F.Cu") (net 320))
  (segment (start 124.861 92.164) (end 124.6 92.425) (width 0.182) (layer "F.Cu") (net 320))
  (segment (start 124.518942 90.727261) (end 124.529942 90.738261) (width 0.182) (layer "F.Cu") (net 320))
  (segment (start 125.239 91.346712) (end 125.239 92.164) (width 0.182) (layer "F.Cu") (net 321))
  (segment (start 124.907941 91.015653) (end 125.239 91.346712) (width 0.182) (layer "F.Cu") (net 321))
  (segment (start 124.918941 90.727261) (end 124.907941 90.738261) (width 0.182) (layer "F.Cu") (net 321))
  (segment (start 125.239 92.164) (end 125.5 92.425) (width 0.182) (layer "F.Cu") (net 321))
  (segment (start 124.907941 90.738261) (end 124.907941 91.015653) (width 0.182) (layer "F.Cu") (net 321))
  (segment (start 124.918941 90.323661) (end 124.918941 90.727261) (width 0.182) (layer "F.Cu") (net 321))
  (segment (start 82.68 117.355) (end 83.050001 117.725001) (width 0.182) (layer "F.Cu") (net 322))
  (segment (start 79.425 118.765) (end 80.375 118.765) (width 0.2) (layer "F.Cu") (net 322))
  (segment (start 81.8 117.355) (end 81.325 117.83) (width 0.2) (layer "F.Cu") (net 322))
  (segment (start 82.15 117.355) (end 81.8 117.355) (width 0.2) (layer "F.Cu") (net 322))
  (segment (start 82.15 117.355) (end 82.68 117.355) (width 0.182) (layer "F.Cu") (net 322))
  (segment (start 83.050001 117.725001) (end 83.425 117.725001) (width 0.182) (layer "F.Cu") (net 322))
  (segment (start 80.375 118.765) (end 81.325 118.765) (width 0.2) (layer "F.Cu") (net 322))
  (segment (start 78.475 118.765) (end 79.425 118.765) (width 0.2) (layer "F.Cu") (net 322))
  (segment (start 81.325 117.83) (end 81.325 118.765) (width 0.2) (layer "F.Cu") (net 322))
  (segment (start 101.85 133.315) (end 103.135 133.315) (width 0.182) (layer "F.Cu") (net 324))
  (segment (start 103.135 133.315) (end 103.15 133.3) (width 0.182) (layer "F.Cu") (net 324))
  (segment (start 101.85 132.045) (end 102.995 132.045) (width 0.182) (layer "F.Cu") (net 324))
  (segment (start 102.995 132.045) (end 103.15 132.2) (width 0.182) (layer "F.Cu") (net 324))
  (segment (start 103.15 132.2) (end 103.15 133.3) (width 0.182) (layer "F.Cu") (net 324))
  (via (at 103.15 133.3) (size 0.45) (drill 0.1) (layers "F.Cu" "B.Cu") (net 324))
  (segment (start 102.335 133.3) (end 103.15 133.3) (width 0.4) (layer "B.Cu") (net 324))
  (segment (start 102.325 133.31) (end 102.335 133.3) (width 0.4) (layer "B.Cu") (net 324))
  (segment (start 102.335 134.35) (end 102.335 133.32) (width 0.4) (layer "B.Cu") (net 324))
  (segment (start 102.335 133.32) (end 102.325 133.31) (width 0.4) (layer "B.Cu") (net 324))
  (segment (start 93.15 150.9) (end 97.25 150.9) (width 0.182) (layer "F.Cu") (net 327))
  (segment (start 98.5 150.9) (end 101.65 147.75) (width 0.182) (layer "F.Cu") (net 327))
  (segment (start 94.975 139.85) (end 94.975 140.465) (width 0.109) (layer "F.Cu") (net 327))
  (segment (start 94.975 140.465) (end 94.89 140.55) (width 0.109) (layer "F.Cu") (net 327))
  (segment (start 101.65 147.75) (end 101.65 144.694998) (width 0.182) (layer "F.Cu") (net 327))
  (segment (start 101.65 143.55) (end 101.65 144.694998) (width 0.182) (layer "F.Cu") (net 327))
  (segment (start 97.25 150.9) (end 98.5 150.9) (width 0.182) (layer "F.Cu") (net 327))
  (via (at 101.65 144.694998) (size 0.45) (drill 0.1) (layers "F.Cu" "B.Cu") (net 327))
  (via (at 94.975 139.85) (size 0.45) (drill 0.1) (layers "F.Cu" "B.Cu") (net 327))
  (segment (start 99.340002 142.385) (end 101.65 144.694998) (width 0.109) (layer "In6.Cu") (net 327))
  (segment (start 97.51 142.385) (end 99.340002 142.385) (width 0.109) (layer "In6.Cu") (net 327))
  (segment (start 94.975 139.85) (end 97.51 142.385) (width 0.109) (layer "In6.Cu") (net 327))
  (segment (start 190.065 66.25) (end 190.7 65.615) (width 0.182) (layer "F.Cu") (net 328))
  (segment (start 190.7 65.615) (end 190.7 64.55) (width 0.182) (layer "F.Cu") (net 328))
  (segment (start 189.4204 66.25) (end 190.065 66.25) (width 0.182) (layer "F.Cu") (net 328))
  (segment (start 178.5 127.95) (end 177.725 127.95) (width 0.2) (layer "F.Cu") (net 329))
  (via (at 177.725 127.95) (size 0.45) (drill 0.1) (layers "F.Cu" "B.Cu") (net 329))
  (segment (start 177.725 127.9) (end 176.775 126.95) (width 0.2) (layer "B.Cu") (net 329))
  (segment (start 177.725 127.95) (end 177.725 127.9) (width 0.2) (layer "B.Cu") (net 329))
  (segment (start 149.79 76.865) (end 149.825 76.9) (width 0.182) (layer "F.Cu") (net 330))
  (segment (start 148.625 76.865) (end 149.79 76.865) (width 0.182) (layer "F.Cu") (net 330))
  (segment (start 186.5296 68.6796) (end 186.5296 66.25) (width 0.2) (layer "F.Cu") (net 331))
  (segment (start 190.335 68.365) (end 189.55 69.15) (width 0.2) (layer "F.Cu") (net 331))
  (segment (start 187.65 69.15) (end 187 69.15) (width 0.2) (layer "F.Cu") (net 331))
  (segment (start 190.7 66.585) (end 190.7 67.235) (width 0.182) (layer "F.Cu") (net 331))
  (segment (start 190.7 67.235) (end 190.335 67.6) (width 0.182) (layer "F.Cu") (net 331))
  (segment (start 187 69.15) (end 186.5296 68.6796) (width 0.2) (layer "F.Cu") (net 331))
  (segment (start 189.55 69.15) (end 188.85 69.15) (width 0.2) (layer "F.Cu") (net 331))
  (segment (start 187.65 69.15) (end 188.85 69.15) (width 0.182) (layer "F.Cu") (net 331))
  (segment (start 190.335 67.6) (end 190.335 68.365) (width 0.2) (layer "F.Cu") (net 331))
  (segment (start 166.4 75.1) (end 166.4 75.9) (width 0.182) (layer "F.Cu") (net 332))
  (segment (start 165.89 74.59) (end 166.4 75.1) (width 0.182) (layer "F.Cu") (net 332))
  (segment (start 165.89 69.26) (end 165.89 74.59) (width 0.182) (layer "F.Cu") (net 332))
  (segment (start 163.92 75.9) (end 163.92 75.18) (width 0.182) (layer "F.Cu") (net 333))
  (segment (start 163.92 75.18) (end 164.62 74.48) (width 0.182) (layer "F.Cu") (net 333))
  (segment (start 164.62 74.48) (end 164.62 71.8) (width 0.182) (layer "F.Cu") (net 333))
  (segment (start 94.263 65.618) (end 94.263 66.963) (width 0.182) (layer "F.Cu") (net 334))
  (segment (start 94.263 66.963) (end 94.375 67.075) (width 0.182) (layer "F.Cu") (net 334))
  (segment (start 95.125 67.075) (end 95.85 67.8) (width 0.182) (layer "F.Cu") (net 334))
  (segment (start 95.85 67.8) (end 95.85 67.94) (width 0.182) (layer "F.Cu") (net 334))
  (segment (start 94.375 67.075) (end 95.125 67.075) (width 0.182) (layer "F.Cu") (net 334))
  (via (at 94.75 67.05) (size 0.45) (drill 0.1) (layers "F.Cu" "B.Cu") (net 334))
  (segment (start 95.175 67.05) (end 95.269999 66.955001) (width 0.4) (layer "B.Cu") (net 334))
  (segment (start 94.75 67.155001) (end 95.269999 67.675) (width 0.4) (layer "B.Cu") (net 334))
  (segment (start 94.75 67.05) (end 95.175 67.05) (width 0.4) (layer "B.Cu") (net 334))
  (segment (start 95.265 66.535) (end 94.75 67.05) (width 0.4) (layer "B.Cu") (net 334))
  (segment (start 95.265 66.525) (end 95.265 66.535) (width 0.4) (layer "B.Cu") (net 334))
  (segment (start 94.75 67.05) (end 94.75 67.155001) (width 0.4) (layer "B.Cu") (net 334))
  (segment (start 95.269999 66.955001) (end 95.269999 66.529999) (width 0.4) (layer "B.Cu") (net 334))
  (segment (start 95.269999 67.675) (end 95.269999 66.955001) (width 0.4) (layer "B.Cu") (net 334))
  (segment (start 95.269999 66.529999) (end 95.265 66.525) (width 0.4) (layer "B.Cu") (net 334))
  (segment (start 95.625 141.925) (end 94.9 142.65) (width 0.182) (layer "F.Cu") (net 335))
  (segment (start 97.975 141.925) (end 95.625 141.925) (width 0.182) (layer "F.Cu") (net 335))
  (segment (start 98.625 141.275) (end 97.975 141.925) (width 0.182) (layer "F.Cu") (net 335))
  (segment (start 98.625 140.325) (end 98.625 141.275) (width 0.182) (layer "F.Cu") (net 335))
  (segment (start 94.9 142.65) (end 94.89 142.65) (width 0.182) (layer "F.Cu") (net 335))
  (segment (start 103.45 143.55) (end 103.75 143.55) (width 0.182) (layer "F.Cu") (net 336))
  (segment (start 102.28 140.78) (end 102.28 142.38) (width 0.182) (layer "F.Cu") (net 336))
  (segment (start 101.475 139.975) (end 102.28 140.78) (width 0.182) (layer "F.Cu") (net 336))
  (segment (start 102.28 142.38) (end 103.45 143.55) (width 0.182) (layer "F.Cu") (net 336))
  (segment (start 183.2 116.325) (end 183.2 116.85) (width 0.182) (layer "F.Cu") (net 337))
  (segment (start 181.675 115.425) (end 182.3 115.425) (width 0.182) (layer "F.Cu") (net 337))
  (segment (start 182.3 115.425) (end 183.2 116.325) (width 0.182) (layer "F.Cu") (net 337))
  (segment (start 171.85 115.7) (end 173.5 115.7) (width 0.182) (layer "F.Cu") (net 338))
  (segment (start 138.42 95.15) (end 138.38 95.19) (width 0.182) (layer "F.Cu") (net 339))
  (segment (start 139.45 95.15) (end 138.42 95.15) (width 0.182) (layer "F.Cu") (net 339))
  (via (at 138.38 95.19) (size 0.45) (drill 0.1) (layers "F.Cu" "B.Cu") (net 339))
  (segment (start 138.38 95.546) (end 138.38 95.19) (width 0.182) (layer "B.Cu") (net 339))
  (segment (start 138.106 95.769) (end 138.157 95.769) (width 0.182) (layer "B.Cu") (net 339))
  (segment (start 138.157 95.769) (end 138.38 95.546) (width 0.182) (layer "B.Cu") (net 339))
  (segment (start 183.9 137.1) (end 184.4 137.6) (width 0.182) (layer "F.Cu") (net 340))
  (segment (start 183.9 136.4) (end 183.9 137.1) (width 0.182) (layer "F.Cu") (net 340))
  (segment (start 185.05 137.6) (end 185.25 137.8) (width 0.182) (layer "F.Cu") (net 340))
  (segment (start 184.4 137.6) (end 185.05 137.6) (width 0.182) (layer "F.Cu") (net 340))
  (segment (start 189.265 76.75) (end 189.265 77.255) (width 0.4) (layer "F.Cu") (net 341))
  (segment (start 189.235 77.285) (end 189.235 78.378) (width 0.4) (layer "F.Cu") (net 341))
  (segment (start 189.265 77.255) (end 189.235 77.285) (width 0.4) (layer "F.Cu") (net 341))
  (segment (start 187.95 77.25) (end 187.965 77.265) (width 0.4) (layer "F.Cu") (net 342))
  (segment (start 187.95 76.55) (end 187.95 77.25) (width 0.4) (layer "F.Cu") (net 342))
  (segment (start 187.965 77.265) (end 187.965 78.378) (width 0.4) (layer "F.Cu") (net 342))
  (segment (start 90.763 65.618) (end 90.763 66.987) (width 0.182) (layer "F.Cu") (net 348))
  (segment (start 89.815 67.935) (end 89.75 67.935) (width 0.182) (layer "F.Cu") (net 348))
  (segment (start 90.763 66.987) (end 89.815 67.935) (width 0.182) (layer "F.Cu") (net 348))
  (segment (start 90.72 67.935) (end 90.765 67.935) (width 0.182) (layer "F.Cu") (net 349))
  (segment (start 91.263 67.437) (end 91.263 65.618) (width 0.182) (layer "F.Cu") (net 349))
  (segment (start 90.765 67.935) (end 91.263 67.437) (width 0.182) (layer "F.Cu") (net 349))
  (segment (start 156.05 60.9) (end 154.625 62.325) (width 0.182) (layer "F.Cu") (net 350))
  (segment (start 154.625 66.475) (end 154.33 66.77) (width 0.182) (layer "F.Cu") (net 350))
  (segment (start 154.625 62.325) (end 154.625 66.475) (width 0.182) (layer "F.Cu") (net 350))
  (segment (start 170.625002 58.840001) (end 170.625002 60.074998) (width 0.182) (layer "F.Cu") (net 350))
  (segment (start 169.8 60.9) (end 156.05 60.9) (width 0.182) (layer "F.Cu") (net 350))
  (segment (start 170.625002 60.074998) (end 169.8 60.9) (width 0.182) (layer "F.Cu") (net 350))
  (segment (start 154.33 66.77) (end 154.33 67.065) (width 0.182) (layer "F.Cu") (net 350))
  (segment (start 168.085002 60.114998) (end 167.7 60.5) (width 0.182) (layer "F.Cu") (net 351))
  (segment (start 154.15 66.15) (end 153.81 66.49) (width 0.182) (layer "F.Cu") (net 351))
  (segment (start 168.085002 58.840001) (end 168.085002 60.114998) (width 0.182) (layer "F.Cu") (net 351))
  (segment (start 155.875 60.5) (end 154.15 62.225) (width 0.182) (layer "F.Cu") (net 351))
  (segment (start 153.81 66.49) (end 153.81 68.598313) (width 0.182) (layer "F.Cu") (net 351))
  (segment (start 167.7 60.5) (end 155.875 60.5) (width 0.182) (layer "F.Cu") (net 351))
  (segment (start 154.15 62.225) (end 154.15 66.15) (width 0.182) (layer "F.Cu") (net 351))
  (segment (start 154.661687 69.45) (end 154.73 69.45) (width 0.182) (layer "F.Cu") (net 351))
  (segment (start 153.81 68.598313) (end 154.661687 69.45) (width 0.182) (layer "F.Cu") (net 351))
  (segment (start 159.884998 59.665002) (end 159.425 60.125) (width 0.182) (layer "F.Cu") (net 352))
  (segment (start 153.27 66.23) (end 153.27 67.085) (width 0.182) (layer "F.Cu") (net 352))
  (segment (start 153.75 65.75) (end 153.27 66.23) (width 0.182) (layer "F.Cu") (net 352))
  (segment (start 153.75 62.05) (end 153.75 65.75) (width 0.182) (layer "F.Cu") (net 352))
  (segment (start 159.425 60.125) (end 155.675 60.125) (width 0.182) (layer "F.Cu") (net 352))
  (segment (start 155.675 60.125) (end 153.75 62.05) (width 0.182) (layer "F.Cu") (net 352))
  (segment (start 159.884998 58.840001) (end 159.884998 59.665002) (width 0.182) (layer "F.Cu") (net 352))
  (segment (start 153.3 61.975) (end 153.3 65.5) (width 0.182) (layer "F.Cu") (net 353))
  (segment (start 157.344998 58.840001) (end 156.384999 59.8) (width 0.182) (layer "F.Cu") (net 353))
  (segment (start 156.384999 59.8) (end 155.475 59.8) (width 0.182) (layer "F.Cu") (net 353))
  (segment (start 152.741001 69.328999) (end 152.62 69.45) (width 0.182) (layer "F.Cu") (net 353))
  (segment (start 153.3 65.5) (end 152.741001 66.058999) (width 0.182) (layer "F.Cu") (net 353))
  (segment (start 155.475 59.8) (end 153.3 61.975) (width 0.182) (layer "F.Cu") (net 353))
  (segment (start 152.741001 66.058999) (end 152.741001 69.328999) (width 0.182) (layer "F.Cu") (net 353))
  (segment (start 142.755 143.095) (end 143.1 143.44) (width 0.2) (layer "F.Cu") (net 354))
  (segment (start 143.1 143.44) (end 143.1 144.325) (width 0.2) (layer "F.Cu") (net 354))
  (segment (start 142.755 142.56) (end 142.755 143.095) (width 0.2) (layer "F.Cu") (net 354))
  (segment (start 145.1 144.325) (end 145.1 145.075) (width 0.182) (layer "F.Cu") (net 355))
  (segment (start 144.1 143.532) (end 144.1 144.325) (width 0.182) (layer "F.Cu") (net 355))
  (segment (start 144.1 145.199998) (end 144.100002 145.2) (width 0.182) (layer "F.Cu") (net 355))
  (segment (start 143.85 143.282) (end 144.1 143.532) (width 0.182) (layer "F.Cu") (net 355))
  (segment (start 145.1 145.075) (end 145.225 145.2) (width 0.182) (layer "F.Cu") (net 355))
  (segment (start 143.85 142.85) (end 143.85 143.282) (width 0.182) (layer "F.Cu") (net 355))
  (segment (start 144.1 144.325) (end 144.1 145.199998) (width 0.182) (layer "F.Cu") (net 355))
  (via (at 144.100002 145.2) (size 0.45) (drill 0.1) (layers "F.Cu" "B.Cu") (net 355))
  (via (at 145.225 145.2) (size 0.45) (drill 0.1) (layers "F.Cu" "B.Cu") (net 355))
  (segment (start 145.025 144.7) (end 144.275 144.7) (width 0.109) (layer "In2.Cu") (net 355))
  (segment (start 145.225 145.2) (end 145.225 144.9) (width 0.109) (layer "In2.Cu") (net 355))
  (segment (start 144.275 144.7) (end 144.100002 144.874998) (width 0.109) (layer "In2.Cu") (net 355))
  (segment (start 145.225 144.9) (end 145.025 144.7) (width 0.109) (layer "In2.Cu") (net 355))
  (segment (start 144.100002 144.874998) (end 144.100002 145.2) (width 0.109) (layer "In2.Cu") (net 355))
  (segment (start 144.85 143.3) (end 144.6 143.55) (width 0.182) (layer "F.Cu") (net 356))
  (segment (start 144.85 142.85) (end 144.85 143.3) (width 0.182) (layer "F.Cu") (net 356))
  (segment (start 144.6 144.325) (end 144.6 145.149985) (width 0.182) (layer "F.Cu") (net 356))
  (segment (start 143.6 144.325) (end 143.6 145.081984) (width 0.182) (layer "F.Cu") (net 356))
  (segment (start 144.6 145.149985) (end 144.650015 145.2) (width 0.182) (layer "F.Cu") (net 356))
  (segment (start 143.6 145.081984) (end 143.49666 145.185324) (width 0.182) (layer "F.Cu") (net 356))
  (segment (start 144.6 143.55) (end 144.6 144.325) (width 0.182) (layer "F.Cu") (net 356))
  (via (at 143.49666 145.185324) (size 0.45) (drill 0.1) (layers "F.Cu" "B.Cu") (net 356))
  (via (at 144.650015 145.2) (size 0.45) (drill 0.1) (layers "F.Cu" "B.Cu") (net 356))
  (segment (start 143.49666 145.47166) (end 143.49666 145.185324) (width 0.109) (layer "In2.Cu") (net 356))
  (segment (start 143.675 145.65) (end 143.49666 145.47166) (width 0.109) (layer "In2.Cu") (net 356))
  (segment (start 144.525 145.65) (end 143.675 145.65) (width 0.109) (layer "In2.Cu") (net 356))
  (segment (start 144.650015 145.2) (end 144.650015 145.524985) (width 0.109) (layer "In2.Cu") (net 356))
  (segment (start 144.650015 145.524985) (end 144.525 145.65) (width 0.109) (layer "In2.Cu") (net 356))
  (segment (start 146.1 144.325) (end 146.1 142.96) (width 0.182) (layer "F.Cu") (net 358))
  (segment (start 146.1 142.96) (end 146.05 142.91) (width 0.182) (layer "F.Cu") (net 358))
  (segment (start 127.907742 83.734861) (end 127.149342 83.734861) (width 0.182) (layer "F.Cu") (net 360))
  (segment (start 126.916018 83.74586) (end 126.807018 83.63686) (width 0.182) (layer "F.Cu") (net 360))
  (segment (start 127.138342 83.745861) (end 126.916018 83.74586) (width 0.182) (layer "F.Cu") (net 360))
  (segment (start 127.149342 83.734861) (end 127.138342 83.745861) (width 0.182) (layer "F.Cu") (net 360))
  (via (at 126.807018 83.63686) (size 0.45) (drill 0.1) (layers "F.Cu" "B.Cu") (net 360))
  (via (at 133.7 130.226723) (size 0.45) (drill 0.1) (layers "F.Cu" "B.Cu") (net 360))
  (segment (start 132.487186 131.7725) (end 133.0025 131.257186) (width 0.109) (layer "In6.Cu") (net 360))
  (segment (start 132.2775 94.697186) (end 132.2775 97.652814) (width 0.109) (layer "In6.Cu") (net 360))
  (segment (start 131.3775 98.552814) (end 131.3775 108.302814) (width 0.109) (layer "In6.Cu") (net 360))
  (segment (start 131.552814 88.1725) (end 132.2775 88.897186) (width 0.109) (layer "In6.Cu") (net 360))
  (segment (start 126.807018 83.63686) (end 126.977518 83.80736) (width 0.109) (layer "In6.Cu") (net 360))
  (segment (start 131.9775 91.502814) (end 131.9775 94.397186) (width 0.109) (layer "In6.Cu") (net 360))
  (segment (start 126.977518 83.80736) (end 127.187674 83.80736) (width 0.109) (layer "In6.Cu") (net 360))
  (segment (start 133.0025 130.587186) (end 133.192463 130.397223) (width 0.109) (layer "In6.Cu") (net 360))
  (segment (start 133.5295 130.397223) (end 133.7 130.226723) (width 0.109) (layer "In6.Cu") (net 360))
  (segment (start 130.722814 131.7725) (end 132.487186 131.7725) (width 0.109) (layer "In6.Cu") (net 360))
  (segment (start 127.4775 128.527186) (end 130.722814 131.7725) (width 0.109) (layer "In6.Cu") (net 360))
  (segment (start 127.4775 116.002814) (end 127.4775 128.527186) (width 0.109) (layer "In6.Cu") (net 360))
  (segment (start 129.6275 113.852814) (end 127.4775 116.002814) (width 0.109) (layer "In6.Cu") (net 360))
  (segment (start 133.0025 131.257186) (end 133.0025 130.587186) (width 0.109) (layer "In6.Cu") (net 360))
  (segment (start 132.2775 88.897186) (end 132.2775 91.202814) (width 0.109) (layer "In6.Cu") (net 360))
  (segment (start 129.102814 88.1725) (end 131.552814 88.1725) (width 0.109) (layer "In6.Cu") (net 360))
  (segment (start 127.4575 84.077186) (end 127.4575 86.527186) (width 0.109) (layer "In6.Cu") (net 360))
  (segment (start 131.9775 94.397186) (end 132.2775 94.697186) (width 0.109) (layer "In6.Cu") (net 360))
  (segment (start 133.192463 130.397223) (end 133.5295 130.397223) (width 0.109) (layer "In6.Cu") (net 360))
  (segment (start 131.3775 108.302814) (end 129.6275 110.052814) (width 0.109) (layer "In6.Cu") (net 360))
  (segment (start 129.6275 110.052814) (end 129.6275 113.852814) (width 0.109) (layer "In6.Cu") (net 360))
  (segment (start 132.2775 91.202814) (end 131.9775 91.502814) (width 0.109) (layer "In6.Cu") (net 360))
  (segment (start 127.4575 86.527186) (end 129.102814 88.1725) (width 0.109) (layer "In6.Cu") (net 360))
  (segment (start 127.187674 83.80736) (end 127.4575 84.077186) (width 0.109) (layer "In6.Cu") (net 360))
  (segment (start 132.2775 97.652814) (end 131.3775 98.552814) (width 0.109) (layer "In6.Cu") (net 360))
  (segment (start 133.45106 130.274723) (end 133.51206 130.335723) (width 0.182) (layer "B.Cu") (net 360))
  (segment (start 132.288559 130.274723) (end 133.45106 130.274723) (width 0.182) (layer "B.Cu") (net 360))
  (segment (start 133.51206 130.335723) (end 133.591 130.335723) (width 0.182) (layer "B.Cu") (net 360))
  (segment (start 133.591 130.335723) (end 133.7 130.226723) (width 0.182) (layer "B.Cu") (net 360))
  (segment (start 126.916018 84.12386) (end 126.807018 84.23286) (width 0.182) (layer "F.Cu") (net 361))
  (segment (start 127.149342 84.13486) (end 127.138342 84.12386) (width 0.182) (layer "F.Cu") (net 361))
  (segment (start 127.138342 84.12386) (end 126.916018 84.12386) (width 0.182) (layer "F.Cu") (net 361))
  (segment (start 127.907742 84.13486) (end 127.149342 84.13486) (width 0.182) (layer "F.Cu") (net 361))
  (via (at 126.807018 84.23286) (size 0.45) (drill 0.1) (layers "F.Cu" "B.Cu") (net 361))
  (via (at 133.7 130.822723) (size 0.45) (drill 0.1) (layers "F.Cu" "B.Cu") (net 361))
  (segment (start 133.5295 130.652223) (end 133.7 130.822723) (width 0.109) (layer "In6.Cu") (net 361))
  (segment (start 132.0225 91.097186) (end 131.7225 91.397186) (width 0.109) (layer "In6.Cu") (net 361))
  (segment (start 127.2025 84.182814) (end 127.2025 86.632814) (width 0.109) (layer "In6.Cu") (net 361))
  (segment (start 126.807018 84.23286) (end 126.977518 84.06236) (width 0.109) (layer "In6.Cu") (net 361))
  (segment (start 132.0225 89.002814) (end 132.0225 91.097186) (width 0.109) (layer "In6.Cu") (net 361))
  (segment (start 131.7225 91.397186) (end 131.7225 94.502814) (width 0.109) (layer "In6.Cu") (net 361))
  (segment (start 132.0225 94.802814) (end 132.0225 97.547186) (width 0.109) (layer "In6.Cu") (net 361))
  (segment (start 126.977518 84.06236) (end 127.082046 84.06236) (width 0.109) (layer "In6.Cu") (net 361))
  (segment (start 133.2575 130.692814) (end 133.298091 130.652223) (width 0.109) (layer "In6.Cu") (net 361))
  (segment (start 131.7225 94.502814) (end 132.0225 94.802814) (width 0.109) (layer "In6.Cu") (net 361))
  (segment (start 127.2225 115.897186) (end 127.2225 128.632814) (width 0.109) (layer "In6.Cu") (net 361))
  (segment (start 133.2575 131.362814) (end 133.2575 130.692814) (width 0.109) (layer "In6.Cu") (net 361))
  (segment (start 131.1225 98.447186) (end 131.1225 108.197186) (width 0.109) (layer "In6.Cu") (net 361))
  (segment (start 131.1225 108.197186) (end 129.3725 109.947186) (width 0.109) (layer "In6.Cu") (net 361))
  (segment (start 127.082046 84.06236) (end 127.2025 84.182814) (width 0.109) (layer "In6.Cu") (net 361))
  (segment (start 127.2225 128.632814) (end 130.617186 132.0275) (width 0.109) (layer "In6.Cu") (net 361))
  (segment (start 131.447186 88.4275) (end 132.0225 89.002814) (width 0.109) (layer "In6.Cu") (net 361))
  (segment (start 127.2025 86.632814) (end 128.997186 88.4275) (width 0.109) (layer "In6.Cu") (net 361))
  (segment (start 133.298091 130.652223) (end 133.5295 130.652223) (width 0.109) (layer "In6.Cu") (net 361))
  (segment (start 129.3725 113.747186) (end 127.2225 115.897186) (width 0.109) (layer "In6.Cu") (net 361))
  (segment (start 129.3725 109.947186) (end 129.3725 113.747186) (width 0.109) (layer "In6.Cu") (net 361))
  (segment (start 130.617186 132.0275) (end 132.592814 132.0275) (width 0.109) (layer "In6.Cu") (net 361))
  (segment (start 132.592814 132.0275) (end 133.2575 131.362814) (width 0.109) (layer "In6.Cu") (net 361))
  (segment (start 132.0225 97.547186) (end 131.1225 98.447186) (width 0.109) (layer "In6.Cu") (net 361))
  (segment (start 128.997186 88.4275) (end 131.447186 88.4275) (width 0.109) (layer "In6.Cu") (net 361))
  (segment (start 133.51206 130.713723) (end 133.591 130.713723) (width 0.182) (layer "B.Cu") (net 361))
  (segment (start 132.288559 130.774723) (end 133.45106 130.774723) (width 0.182) (layer "B.Cu") (net 361))
  (segment (start 133.45106 130.774723) (end 133.51206 130.713723) (width 0.182) (layer "B.Cu") (net 361))
  (segment (start 133.591 130.713723) (end 133.7 130.822723) (width 0.182) (layer "B.Cu") (net 361))
  (segment (start 91.763 67.363) (end 92.1 67.7) (width 0.182) (layer "F.Cu") (net 362))
  (segment (start 92.1 67.7) (end 92.1 68.225) (width 0.182) (layer "F.Cu") (net 362))
  (segment (start 91.763 65.618) (end 91.763 67.363) (width 0.182) (layer "F.Cu") (net 362))
  (segment (start 92.763 65.618) (end 92.763 67.387) (width 0.182) (layer "F.Cu") (net 363))
  (segment (start 92.763 67.387) (end 92.45 67.7) (width 0.182) (layer "F.Cu") (net 363))
  (segment (start 92.45 67.7) (end 92.45 68.225) (width 0.182) (layer "F.Cu") (net 363))
  (segment (start 152.245912 86.464034) (end 152.815966 86.464034) (width 0.182) (layer "F.Cu") (net 364))
  (segment (start 154.23 71.64) (end 154.23 70.752) (width 0.182) (layer "F.Cu") (net 364))
  (segment (start 154.35 75.33) (end 154.35 72.88) (width 0.182) (layer "F.Cu") (net 364))
  (segment (start 153.01 76.67) (end 154.35 75.33) (width 0.182) (layer "F.Cu") (net 364))
  (segment (start 154.35 71.74) (end 154.33 71.74) (width 0.182) (layer "F.Cu") (net 364))
  (segment (start 154.33 71.74) (end 154.23 71.64) (width 0.182) (layer "F.Cu") (net 364))
  (segment (start 152.815966 86.464034) (end 153.01 86.27) (width 0.182) (layer "F.Cu") (net 364))
  (segment (start 153.01 86.27) (end 153.01 76.67) (width 0.182) (layer "F.Cu") (net 364))
  (via (at 154.35 71.74) (size 0.45) (drill 0.1) (layers "F.Cu" "B.Cu") (net 364))
  (via (at 154.35 72.88) (size 0.45) (drill 0.1) (layers "F.Cu" "B.Cu") (net 364))
  (segment (start 154.35 72.88) (end 154.35 71.74) (width 0.182) (layer "In6.Cu") (net 364))
  (segment (start 94.59 74.217) (end 94.605 74.202) (width 0.182) (layer "F.Cu") (net 380))
  (segment (start 93.69 74.217) (end 93.69 74.919998) (width 0.182) (layer "F.Cu") (net 380))
  (segment (start 93.69 74.919998) (end 93.659998 74.95) (width 0.182) (layer "F.Cu") (net 380))
  (segment (start 93.69 74.217) (end 94.59 74.217) (width 0.182) (layer "F.Cu") (net 380))
  (segment (start 90.82 74.909998) (end 90.819998 74.91) (width 0.182) (layer "F.Cu") (net 380))
  (segment (start 89.905 74.202) (end 90.805 74.202) (width 0.182) (layer "F.Cu") (net 380))
  (segment (start 90.805 74.202) (end 90.82 74.217) (width 0.182) (layer "F.Cu") (net 380))
  (segment (start 90.82 74.217) (end 90.82 74.909998) (width 0.182) (layer "F.Cu") (net 380))
  (via (at 90.819998 74.91) (size 0.45) (drill 0.1) (layers "F.Cu" "B.Cu") (net 380))
  (via (at 93.659998 74.95) (size 0.45) (drill 0.1) (layers "F.Cu" "B.Cu") (net 380))
  (segment (start 90.819998 74.91) (end 91.129998 74.6) (width 0.109) (layer "In6.Cu") (net 380))
  (segment (start 93.309998 74.6) (end 93.659998 74.95) (width 0.109) (layer "In6.Cu") (net 380))
  (segment (start 91.129998 74.6) (end 93.309998 74.6) (width 0.109) (layer "In6.Cu") (net 380))
  (segment (start 133.4 118.275) (end 134.2242 118.275) (width 0.182) (layer "F.Cu") (net 396))
  (segment (start 133.325 118.2) (end 133.4 118.275) (width 0.182) (layer "F.Cu") (net 396))
  (segment (start 132.7 118) (end 132.9 118.2) (width 0.182) (layer "F.Cu") (net 396))
  (segment (start 129.28 118.48) (end 129.3 118.5) (width 0.182) (layer "F.Cu") (net 396))
  (segment (start 132.9 118.2) (end 133.325 118.2) (width 0.182) (layer "F.Cu") (net 396))
  (segment (start 132.285 118) (end 132.7 118) (width 0.182) (layer "F.Cu") (net 396))
  (segment (start 134.2242 118.275) (end 134.725 117.7742) (width 0.182) (layer "F.Cu") (net 396))
  (segment (start 129.28 117.805) (end 129.28 118.48) (width 0.182) (layer "F.Cu") (net 396))
  (via (at 129.3 118.5) (size 0.5) (drill 0.15) (layers "F.Cu" "B.Cu") (net 396))
  (via (at 133.4 118.275) (size 0.45) (drill 0.1) (layers "F.Cu" "B.Cu") (net 396))
  (segment (start 132.35 118.275) (end 131.025 118.275) (width 0.109) (layer "In6.Cu") (net 396))
  (segment (start 131.025 118.275) (end 130.8 118.5) (width 0.109) (layer "In6.Cu") (net 396))
  (segment (start 132.35 118.275) (end 133.4 118.275) (width 0.109) (layer "In6.Cu") (net 396))
  (segment (start 130.8 118.5) (end 129.3 118.5) (width 0.109) (layer "In6.Cu") (net 396))
  (segment (start 133.399723 118.274723) (end 133.4 118.275) (width 0.182) (layer "B.Cu") (net 396))
  (segment (start 132.288559 118.274723) (end 133.399723 118.274723) (width 0.182) (layer "B.Cu") (net 396))
  (segment (start 90.3 116.985) (end 90.7865 116.669) (width 0.182) (layer "F.Cu") (net 409))
  (segment (start 87.7594 115.0112) (end 88.4174 115.0112) (width 0.182) (layer "F.Cu") (net 409))
  (via (at 90.3 116.985) (size 0.45) (drill 0.1) (layers "F.Cu" "B.Cu") (net 409))
  (via (at 88.4174 115.0112) (size 0.45) (drill 0.1) (layers "F.Cu" "B.Cu") (net 409))
  (segment (start 89.8756 116.5606) (end 89.3572 116.5606) (width 0.109) (layer "In4.Cu") (net 409))
  (segment (start 89.3572 116.5606) (end 88.4174 115.6208) (width 0.109) (layer "In4.Cu") (net 409))
  (segment (start 88.4174 115.6208) (end 88.4174 115.0112) (width 0.109) (layer "In4.Cu") (net 409))
  (segment (start 90.3 116.985) (end 89.8756 116.5606) (width 0.109) (layer "In4.Cu") (net 409))
  (segment (start 85.659822 123.025) (end 87.6242 123.025) (width 0.2) (layer "F.Cu") (net 410))
  (segment (start 89.4415 127.139) (end 89.8265 126.829) (width 0.182) (layer "F.Cu") (net 410))
  (segment (start 84.575 123.025) (end 84.15 123.45) (width 0.182) (layer "F.Cu") (net 410))
  (segment (start 85.659822 123.025) (end 84.575 123.025) (width 0.182) (layer "F.Cu") (net 410))
  (segment (start 84.15 123.45) (end 84.15 123.85) (width 0.182) (layer "F.Cu") (net 410))
  (via (at 89.4415 127.139) (size 0.45) (drill 0.1) (layers "F.Cu" "B.Cu") (net 410))
  (via (at 84.15 123.85) (size 0.45) (drill 0.1) (layers "F.Cu" "B.Cu") (net 410))
  (segment (start 87.439 127.139) (end 89.4415 127.139) (width 0.109) (layer "In6.Cu") (net 410))
  (segment (start 84.15 123.85) (end 87.439 127.139) (width 0.109) (layer "In6.Cu") (net 410))
  (segment (start 84.15 123.85) (end 84.35 123.65) (width 0.182) (layer "B.Cu") (net 410))
  (segment (start 84.35 123.65) (end 84.75 123.65) (width 0.182) (layer "B.Cu") (net 410))
  (segment (start 120.9 146.05) (end 122.235 146.05) (width 0.182) (layer "B.Cu") (net 415))
  (segment (start 118.315 119.56) (end 118 119.875) (width 0.182) (layer "F.Cu") (net 429))
  (segment (start 118.315 118.8) (end 118.315 119.56) (width 0.182) (layer "F.Cu") (net 429))
  (segment (start 116.950063 121.049937) (end 117.55 120.45) (width 0.182) (layer "F.Cu") (net 429))
  (segment (start 117.55 120.45) (end 118 120.45) (width 0.182) (layer "F.Cu") (net 429))
  (segment (start 118 119.875) (end 118 120.45) (width 0.182) (layer "F.Cu") (net 429))
  (segment (start 116.2946 121.049937) (end 116.950063 121.049937) (width 0.182) (layer "F.Cu") (net 429))
  (segment (start 100.565 87.965) (end 101.25 88.65) (width 0.182) (layer "B.Cu") (net 430))
  (segment (start 101.25 88.65) (end 101.25 89.2) (width 0.182) (layer "B.Cu") (net 430))
  (segment (start 100.565 87.45) (end 100.565 87.965) (width 0.182) (layer "B.Cu") (net 430))
  (segment (start 101.25 89.2) (end 101.8 89.2) (width 0.4) (layer "B.Cu") (net 430))
  (segment (start 101.8 89.2) (end 101.95 89.35) (width 0.4) (layer "B.Cu") (net 430))
  (segment (start 101.95 89.35) (end 102.75 89.35) (width 0.4) (layer "B.Cu") (net 430))
  (segment (start 98.65 89.2) (end 99.15 89.7) (width 0.182) (layer "B.Cu") (net 431))
  (segment (start 99.15 90.1) (end 99.15 89.7) (width 0.182) (layer "B.Cu") (net 431))
  (segment (start 98.285 90.965) (end 99.15 90.1) (width 0.182) (layer "B.Cu") (net 431))
  (segment (start 98.285 91) (end 98.285 90.965) (width 0.182) (layer "B.Cu") (net 431))
  (segment (start 98.515 88.165) (end 98.65 88.3) (width 0.182) (layer "B.Cu") (net 431))
  (segment (start 98.515 87.45) (end 98.515 88.165) (width 0.182) (layer "B.Cu") (net 431))
  (segment (start 98.65 88.3) (end 98.65 89.2) (width 0.182) (layer "B.Cu") (net 431))
  (segment (start 99.15 89.7) (end 99.95 89.7) (width 0.182) (layer "B.Cu") (net 431))
  (segment (start 96.95 135.855) (end 95.555 135.855) (width 0.182) (layer "F.Cu") (net 432))
  (segment (start 95.555 135.855) (end 95.55 135.85) (width 0.182) (layer "F.Cu") (net 432))
  (segment (start 103.7 146.8) (end 103.7 148.8) (width 0.109) (layer "F.Cu") (net 432))
  (segment (start 104.55 145.95) (end 103.7 146.8) (width 0.109) (layer "F.Cu") (net 432))
  (segment (start 104.55 145.35) (end 104.55 145.95) (width 0.109) (layer "F.Cu") (net 432))
  (segment (start 90.7865 119.844) (end 91.1715 119.534) (width 0.182) (layer "F.Cu") (net 432))
  (via (at 95.55 135.85) (size 0.45) (drill 0.1) (layers "F.Cu" "B.Cu") (net 432))
  (via (at 91.1715 119.534) (size 0.45) (drill 0.1) (layers "F.Cu" "B.Cu") (net 432))
  (via (at 104.55 145.35) (size 0.45) (drill 0.1) (layers "F.Cu" "B.Cu") (net 432))
  (segment (start 96 134.2) (end 96 126.6) (width 0.109) (layer "In2.Cu") (net 432))
  (segment (start 103.5 141.35) (end 103.5 144.3) (width 0.109) (layer "In2.Cu") (net 432))
  (segment (start 91.5825 119.945) (end 91.1715 119.534) (width 0.109) (layer "In2.Cu") (net 432))
  (segment (start 96.2 135.85) (end 96.2 134.4) (width 0.109) (layer "In2.Cu") (net 432))
  (segment (start 91.5825 119.95) (end 91.5825 119.945) (width 0.109) (layer "In2.Cu") (net 432))
  (segment (start 96.2 135.85) (end 96.95 136.6) (width 0.109) (layer "In2.Cu") (net 432))
  (segment (start 94.72 121.75) (end 94.37 121.4) (width 0.109) (layer "In2.Cu") (net 432))
  (segment (start 96.2 134.4) (end 96 134.2) (width 0.109) (layer "In2.Cu") (net 432))
  (segment (start 98.75 136.6) (end 103.5 141.35) (width 0.109) (layer "In2.Cu") (net 432))
  (segment (start 95.55 135.85) (end 96.2 135.85) (width 0.109) (layer "In2.Cu") (net 432))
  (segment (start 94.37 120.36) (end 93.96 119.95) (width 0.109) (layer "In2.Cu") (net 432))
  (segment (start 96.95 136.6) (end 98.75 136.6) (width 0.109) (layer "In2.Cu") (net 432))
  (segment (start 93.96 119.95) (end 91.5825 119.95) (width 0.109) (layer "In2.Cu") (net 432))
  (segment (start 94.72 125.32) (end 94.72 121.75) (width 0.109) (layer "In2.Cu") (net 432))
  (segment (start 103.5 144.3) (end 104.55 145.35) (width 0.109) (layer "In2.Cu") (net 432))
  (segment (start 96 126.6) (end 94.72 125.32) (width 0.109) (layer "In2.Cu") (net 432))
  (segment (start 94.37 121.4) (end 94.37 120.36) (width 0.109) (layer "In2.Cu") (net 432))
  (segment (start 150.55 67.7) (end 150.55 65.95) (width 0.182) (layer "F.Cu") (net 433))
  (segment (start 150.55 65.95) (end 151.865 65.95) (width 0.182) (layer "F.Cu") (net 433))
  (segment (start 151.865 65.95) (end 151.9 65.985) (width 0.182) (layer "F.Cu") (net 433))
  (segment (start 99.025 116.225) (end 99.6 116.225) (width 0.182) (layer "F.Cu") (net 435))
  (segment (start 98.21 116.6) (end 98.65 116.6) (width 0.182) (layer "F.Cu") (net 435))
  (segment (start 131.1 135.975) (end 131.525 135.55) (width 0.182) (layer "F.Cu") (net 435))
  (segment (start 98.65 116.6) (end 99.025 116.225) (width 0.182) (layer "F.Cu") (net 435))
  (segment (start 131.1 136.375) (end 131.1 135.975) (width 0.182) (layer "F.Cu") (net 435))
  (via (at 131.525 135.55) (size 0.45) (drill 0.1) (layers "F.Cu" "B.Cu") (net 435))
  (via (at 99.6 116.225) (size 0.45) (drill 0.1) (layers "F.Cu" "B.Cu") (net 435))
  (segment (start 103.8 117.1) (end 106.36 119.66) (width 0.109) (layer "In2.Cu") (net 435))
  (segment (start 128.328401 134.678401) (end 130.971599 134.678401) (width 0.109) (layer "In2.Cu") (net 435))
  (segment (start 99.175 115.825) (end 99.525 115.475) (width 0.109) (layer "In2.Cu") (net 435))
  (segment (start 117.55375 132.92) (end 126.57 132.92) (width 0.109) (layer "In2.Cu") (net 435))
  (segment (start 130.971599 134.678401) (end 131.525 135.231802) (width 0.109) (layer "In2.Cu") (net 435))
  (segment (start 99.575 116.2) (end 99.275 116.2) (width 0.109) (layer "In2.Cu") (net 435))
  (segment (start 106.36 121.72625) (end 117.55375 132.92) (width 0.109) (layer "In2.Cu") (net 435))
  (segment (start 100.7 115.925) (end 101.525 115.925) (width 0.109) (layer "In2.Cu") (net 435))
  (segment (start 102.7 117.1) (end 103.8 117.1) (width 0.109) (layer "In2.Cu") (net 435))
  (segment (start 131.525 135.231802) (end 131.525 135.55) (width 0.109) (layer "In2.Cu") (net 435))
  (segment (start 99.175 116.1) (end 99.175 115.825) (width 0.109) (layer "In2.Cu") (net 435))
  (segment (start 99.525 115.475) (end 100.25 115.475) (width 0.109) (layer "In2.Cu") (net 435))
  (segment (start 99.6 116.225) (end 99.575 116.2) (width 0.109) (layer "In2.Cu") (net 435))
  (segment (start 99.275 116.2) (end 99.175 116.1) (width 0.109) (layer "In2.Cu") (net 435))
  (segment (start 106.36 119.66) (end 106.36 121.72625) (width 0.109) (layer "In2.Cu") (net 435))
  (segment (start 101.525 115.925) (end 102.7 117.1) (width 0.109) (layer "In2.Cu") (net 435))
  (segment (start 100.25 115.475) (end 100.7 115.925) (width 0.109) (layer "In2.Cu") (net 435))
  (segment (start 126.57 132.92) (end 128.328401 134.678401) (width 0.109) (layer "In2.Cu") (net 435))
  (segment (start 98.21 115.7) (end 99.93829 115.7) (width 0.182) (layer "F.Cu") (net 436))
  (segment (start 99.93829 115.7) (end 100.1214 115.88311) (width 0.182) (layer "F.Cu") (net 436))
  (segment (start 127.675 135.75) (end 127.675 135.35) (width 0.1) (layer "F.Cu") (net 436))
  (segment (start 128.75 136.375) (end 128.3 136.375) (width 0.1) (layer "F.Cu") (net 436))
  (segment (start 128.3 136.375) (end 127.675 135.75) (width 0.1) (layer "F.Cu") (net 436))
  (via (at 100.1214 115.88311) (size 0.45) (drill 0.1) (layers "F.Cu" "B.Cu") (net 436))
  (via (at 127.675 135.35) (size 0.45) (drill 0.1) (layers "F.Cu" "B.Cu") (net 436))
  (segment (start 107.123428 124.229333) (end 107.168823 124.251194) (width 0.109) (layer "In2.Cu") (net 436))
  (segment (start 107.084037 123.879722) (end 107.052623 123.919114) (width 0.109) (layer "In2.Cu") (net 436))
  (segment (start 107.720428 124.834311) (end 107.759819 124.865724) (width 0.109) (layer "In2.Cu") (net 436))
  (segment (start 106.447646 123.561529) (end 106.487037 123.592942) (width 0.109) (layer "In2.Cu") (net 436))
  (segment (start 107.019551 124.064013) (end 107.030762 124.113134) (width 0.109) (layer "In2.Cu") (net 436))
  (segment (start 105.746769 122.791231) (end 105.75798 122.840352) (width 0.109) (layer "In2.Cu") (net 436))
  (segment (start 107.969764 123.81052) (end 108.015159 123.832382) (width 0.109) (layer "In2.Cu") (net 436))
  (segment (start 107.233868 123.162918) (end 107.284252 123.162918) (width 0.109) (layer "In2.Cu") (net 436))
  (segment (start 108.107826 124.097206) (end 108.085965 124.142601) (width 0.109) (layer "In2.Cu") (net 436))
  (segment (start 107.268328 124.262406) (end 107.317448 124.251194) (width 0.109) (layer "In2.Cu") (net 436))
  (segment (start 108.046587 124.826348) (end 108.085979 124.794934) (width 0.109) (layer "In2.Cu") (net 436))
  (segment (start 107.689014 124.555505) (end 107.667153 124.600899) (width 0.109) (layer "In2.Cu") (net 436))
  (segment (start 105.779841 122.646332) (end 105.75798 122.691726) (width 0.109) (layer "In2.Cu") (net 436))
  (segment (start 107.378768 123.195991) (end 107.41816 123.227405) (width 0.109) (layer "In2.Cu") (net 436))
  (segment (start 106.502963 122.5596) (end 106.548356 122.537738) (width 0.109) (layer "In2.Cu") (net 436))
  (segment (start 107.471434 123.312191) (end 107.482645 123.361311) (width 0.109) (layer "In2.Cu") (net 436))
  (segment (start 106.813182 122.630405) (end 106.835043 122.6758) (width 0.109) (layer "In2.Cu") (net 436))
  (segment (start 108.054551 124.181993) (end 107.720428 124.516113) (width 0.109) (layer "In2.Cu") (net 436))
  (segment (start 105.746769 122.740847) (end 105.746769 122.791231) (width 0.109) (layer "In2.Cu") (net 436))
  (segment (start 108.054551 123.863796) (end 108.085964 123.903187) (width 0.109) (layer "In2.Cu") (net 436))
  (segment (start 106.647861 122.526527) (end 106.696982 122.537738) (width 0.109) (layer "In2.Cu") (net 436))
  (segment (start 107.471435 123.460815) (end 107.449574 123.50621) (width 0.109) (layer "In2.Cu") (net 436))
  (segment (start 107.655942 124.65002) (end 107.655942 124.700404) (width 0.109) (layer "In2.Cu") (net 436))
  (segment (start 105.811255 122.925138) (end 105.850646 122.956551) (width 0.109) (layer "In2.Cu") (net 436))
  (segment (start 105.883703 122.465072) (end 105.872491 122.514192) (width 0.109) (layer "In2.Cu") (net 436))
  (segment (start 117.238437 133.7) (end 126.025 133.7) (width 0.109) (layer "In2.Cu") (net 436))
  (segment (start 107.482645 123.361311) (end 107.482647 123.411695) (width 0.109) (layer "In2.Cu") (net 436))
  (segment (start 103.3 117.6) (end 105.58 119.88) (width 0.109) (layer "In2.Cu") (net 436))
  (segment (start 108.131373 124.773073) (end 108.180494 124.761862) (width 0.109) (layer "In2.Cu") (net 436))
  (segment (start 101.83829 117.6) (end 103.3 117.6) (width 0.109) (layer "In2.Cu") (net 436))
  (segment (start 107.41816 123.227405) (end 107.449573 123.266796) (width 0.109) (layer "In2.Cu") (net 436))
  (segment (start 108.279999 124.773073) (end 108.325393 124.794934) (width 0.109) (layer "In2.Cu") (net 436))
  (segment (start 106.813183 122.869819) (end 106.781769 122.909211) (width 0.109) (layer "In2.Cu") (net 436))
  (segment (start 106.835043 122.6758) (end 106.846254 122.72492) (width 0.109) (layer "In2.Cu") (net 436))
  (segment (start 108.015159 123.832382) (end 108.054551 123.863796) (width 0.109) (layer "In2.Cu") (net 436))
  (segment (start 106.532432 123.614803) (end 106.581553 123.626015) (width 0.109) (layer "In2.Cu") (net 436))
  (segment (start 107.775745 123.832382) (end 107.821138 123.81052) (width 0.109) (layer "In2.Cu") (net 436))
  (segment (start 105.883703 122.414688) (end 105.883703 122.465072) (width 0.109) (layer "In2.Cu") (net 436))
  (segment (start 107.217944 124.262406) (end 107.268328 124.262406) (width 0.109) (layer "In2.Cu") (net 436))
  (segment (start 107.854335 124.898797) (end 107.904719 124.898797) (width 0.109) (layer "In2.Cu") (net 436))
  (segment (start 106.129453 122.925137) (end 106.137414 122.917175) (width 0.109) (layer "In2.Cu") (net 436))
  (segment (start 107.030762 124.113134) (end 107.052623 124.158528) (width 0.109) (layer "In2.Cu") (net 436))
  (segment (start 107.317448 124.251194) (end 107.362843 124.229333) (width 0.109) (layer "In2.Cu") (net 436))
  (segment (start 106.742377 122.5596) (end 106.781769 122.591014) (width 0.109) (layer "In2.Cu") (net 436))
  (segment (start 106.781769 122.909211) (end 106.447646 123.243331) (width 0.109) (layer "In2.Cu") (net 436))
  (segment (start 106.38316 123.427622) (end 106.394371 123.476743) (width 0.109) (layer "In2.Cu") (net 436))
  (segment (start 106.597477 122.526527) (end 106.647861 122.526527) (width 0.109) (layer "In2.Cu") (net 436))
  (segment (start 107.284252 123.162918) (end 107.333373 123.174129) (width 0.109) (layer "In2.Cu") (net 436))
  (segment (start 107.904719 124.898797) (end 107.953839 124.887585) (width 0.109) (layer "In2.Cu") (net 436))
  (segment (start 107.449574 123.50621) (end 107.41816 123.545602) (width 0.109) (layer "In2.Cu") (net 436))
  (segment (start 106.137414 122.917175) (end 106.463573 122.591016) (width 0.109) (layer "In2.Cu") (net 436))
  (segment (start 108.119038 124.048086) (end 108.107826 124.097206) (width 0.109) (layer "In2.Cu") (net 436))
  (segment (start 108.107825 123.948582) (end 108.119036 123.997702) (width 0.109) (layer "In2.Cu") (net 436))
  (segment (start 105.75798 122.840352) (end 105.779841 122.885746) (width 0.109) (layer "In2.Cu") (net 436))
  (segment (start 105.896041 122.978412) (end 105.945162 122.989624) (width 0.109) (layer "In2.Cu") (net 436))
  (segment (start 105.85063 122.320172) (end 105.872491 122.365567) (width 0.109) (layer "In2.Cu") (net 436))
  (segment (start 107.953839 124.887585) (end 107.999234 124.865724) (width 0.109) (layer "In2.Cu") (net 436))
  (segment (start 107.999234 124.865724) (end 108.038626 124.83431) (width 0.109) (layer "In2.Cu") (net 436))
  (segment (start 107.870259 123.799309) (end 107.920643 123.799309) (width 0.109) (layer "In2.Cu") (net 436))
  (segment (start 106.548356 122.537738) (end 106.597477 122.526527) (width 0.109) (layer "In2.Cu") (net 436))
  (segment (start 106.394371 123.476743) (end 106.416232 123.522137) (width 0.109) (layer "In2.Cu") (net 436))
  (segment (start 100.1214 115.88311) (end 101.83829 117.6) (width 0.109) (layer "In2.Cu") (net 436))
  (segment (start 108.085965 124.142601) (end 108.054551 124.181993) (width 0.109) (layer "In2.Cu") (net 436))
  (segment (start 107.655942 124.700404) (end 107.667153 124.749525) (width 0.109) (layer "In2.Cu") (net 436))
  (segment (start 108.085964 123.903187) (end 108.107825 123.948582) (width 0.109) (layer "In2.Cu") (net 436))
  (segment (start 107.41816 123.545602) (end 107.084037 123.879722) (width 0.109) (layer "In2.Cu") (net 436))
  (segment (start 107.333373 123.174129) (end 107.378768 123.195991) (width 0.109) (layer "In2.Cu") (net 436))
  (segment (start 107.019551 124.013629) (end 107.019551 124.064013) (width 0.109) (layer "In2.Cu") (net 436))
  (segment (start 106.846256 122.775304) (end 106.835044 122.824424) (width 0.109) (layer "In2.Cu") (net 436))
  (segment (start 107.805214 124.887585) (end 107.854335 124.898797) (width 0.109) (layer "In2.Cu") (net 436))
  (segment (start 107.449573 123.266796) (end 107.471434 123.312191) (width 0.109) (layer "In2.Cu") (net 436))
  (segment (start 106.765844 123.561528) (end 107.099964 123.227407) (width 0.109) (layer "In2.Cu") (net 436))
  (segment (start 106.726452 123.592942) (end 106.765844 123.561528) (width 0.109) (layer "In2.Cu") (net 436))
  (segment (start 107.052623 123.919114) (end 107.030762 123.964508) (width 0.109) (layer "In2.Cu") (net 436))
  (segment (start 106.681057 123.614803) (end 106.726452 123.592942) (width 0.109) (layer "In2.Cu") (net 436))
  (segment (start 107.821138 123.81052) (end 107.870259 123.799309) (width 0.109) (layer "In2.Cu") (net 436))
  (segment (start 108.085979 124.794934) (end 108.131373 124.773073) (width 0.109) (layer "In2.Cu") (net 436))
  (segment (start 105.850646 122.956551) (end 105.896041 122.978412) (width 0.109) (layer "In2.Cu") (net 436))
  (segment (start 106.416232 123.522137) (end 106.447646 123.561529) (width 0.109) (layer "In2.Cu") (net 436))
  (segment (start 106.090061 122.956551) (end 106.129453 122.925137) (width 0.109) (layer "In2.Cu") (net 436))
  (segment (start 105.779841 122.885746) (end 105.811255 122.925138) (width 0.109) (layer "In2.Cu") (net 436))
  (segment (start 106.044666 122.978412) (end 106.090061 122.956551) (width 0.109) (layer "In2.Cu") (net 436))
  (segment (start 126.025 133.7) (end 127.675 135.35) (width 0.109) (layer "In2.Cu") (net 436))
  (segment (start 106.487037 123.592942) (end 106.532432 123.614803) (width 0.109) (layer "In2.Cu") (net 436))
  (segment (start 108.364785 124.826348) (end 117.238437 133.7) (width 0.109) (layer "In2.Cu") (net 436))
  (segment (start 107.759819 124.865724) (end 107.805214 124.887585) (width 0.109) (layer "In2.Cu") (net 436))
  (segment (start 106.846254 122.72492) (end 106.846256 122.775304) (width 0.109) (layer "In2.Cu") (net 436))
  (segment (start 107.482647 123.411695) (end 107.471435 123.460815) (width 0.109) (layer "In2.Cu") (net 436))
  (segment (start 105.811255 122.60694) (end 105.779841 122.646332) (width 0.109) (layer "In2.Cu") (net 436))
  (segment (start 105.945162 122.989624) (end 105.995546 122.989624) (width 0.109) (layer "In2.Cu") (net 436))
  (segment (start 105.58 119.88) (end 105.58 122.041564) (width 0.109) (layer "In2.Cu") (net 436))
  (segment (start 108.230878 124.761862) (end 108.279999 124.773073) (width 0.109) (layer "In2.Cu") (net 436))
  (segment (start 108.119036 123.997702) (end 108.119038 124.048086) (width 0.109) (layer "In2.Cu") (net 436))
  (segment (start 107.184747 123.174129) (end 107.233868 123.162918) (width 0.109) (layer "In2.Cu") (net 436))
  (segment (start 108.325393 124.794934) (end 108.364785 124.826348) (width 0.109) (layer "In2.Cu") (net 436))
  (segment (start 107.052623 124.158528) (end 107.084037 124.19792) (width 0.109) (layer "In2.Cu") (net 436))
  (segment (start 106.781769 122.591014) (end 106.813182 122.630405) (width 0.109) (layer "In2.Cu") (net 436))
  (segment (start 107.736355 123.863798) (end 107.775745 123.832382) (width 0.109) (layer "In2.Cu") (net 436))
  (segment (start 107.084037 124.19792) (end 107.123428 124.229333) (width 0.109) (layer "In2.Cu") (net 436))
  (segment (start 107.920643 123.799309) (end 107.969764 123.81052) (width 0.109) (layer "In2.Cu") (net 436))
  (segment (start 106.631937 123.626015) (end 106.681057 123.614803) (width 0.109) (layer "In2.Cu") (net 436))
  (segment (start 106.447646 123.243331) (end 106.416232 123.282723) (width 0.109) (layer "In2.Cu") (net 436))
  (segment (start 105.872491 122.365567) (end 105.883703 122.414688) (width 0.109) (layer "In2.Cu") (net 436))
  (segment (start 107.030762 123.964508) (end 107.019551 124.013629) (width 0.109) (layer "In2.Cu") (net 436))
  (segment (start 105.58 122.041564) (end 105.819217 122.280781) (width 0.109) (layer "In2.Cu") (net 436))
  (segment (start 105.819217 122.280781) (end 105.85063 122.320172) (width 0.109) (layer "In2.Cu") (net 436))
  (segment (start 106.394371 123.328117) (end 106.38316 123.377238) (width 0.109) (layer "In2.Cu") (net 436))
  (segment (start 106.38316 123.377238) (end 106.38316 123.427622) (width 0.109) (layer "In2.Cu") (net 436))
  (segment (start 107.099964 123.227407) (end 107.139354 123.195991) (width 0.109) (layer "In2.Cu") (net 436))
  (segment (start 107.402235 124.197919) (end 107.736355 123.863798) (width 0.109) (layer "In2.Cu") (net 436))
  (segment (start 108.038626 124.83431) (end 108.046587 124.826348) (width 0.109) (layer "In2.Cu") (net 436))
  (segment (start 107.667153 124.749525) (end 107.689014 124.794919) (width 0.109) (layer "In2.Cu") (net 436))
  (segment (start 106.581553 123.626015) (end 106.631937 123.626015) (width 0.109) (layer "In2.Cu") (net 436))
  (segment (start 107.139354 123.195991) (end 107.184747 123.174129) (width 0.109) (layer "In2.Cu") (net 436))
  (segment (start 107.667153 124.600899) (end 107.655942 124.65002) (width 0.109) (layer "In2.Cu") (net 436))
  (segment (start 106.696982 122.537738) (end 106.742377 122.5596) (width 0.109) (layer "In2.Cu") (net 436))
  (segment (start 105.85063 122.559587) (end 105.819217 122.598979) (width 0.109) (layer "In2.Cu") (net 436))
  (segment (start 107.720428 124.516113) (end 107.689014 124.555505) (width 0.109) (layer "In2.Cu") (net 436))
  (segment (start 105.75798 122.691726) (end 105.746769 122.740847) (width 0.109) (layer "In2.Cu") (net 436))
  (segment (start 105.995546 122.989624) (end 106.044666 122.978412) (width 0.109) (layer "In2.Cu") (net 436))
  (segment (start 108.180494 124.761862) (end 108.230878 124.761862) (width 0.109) (layer "In2.Cu") (net 436))
  (segment (start 107.689014 124.794919) (end 107.720428 124.834311) (width 0.109) (layer "In2.Cu") (net 436))
  (segment (start 105.872491 122.514192) (end 105.85063 122.559587) (width 0.109) (layer "In2.Cu") (net 436))
  (segment (start 106.463573 122.591016) (end 106.502963 122.5596) (width 0.109) (layer "In2.Cu") (net 436))
  (segment (start 106.835044 122.824424) (end 106.813183 122.869819) (width 0.109) (layer "In2.Cu") (net 436))
  (segment (start 106.416232 123.282723) (end 106.394371 123.328117) (width 0.109) (layer "In2.Cu") (net 436))
  (segment (start 107.168823 124.251194) (end 107.217944 124.262406) (width 0.109) (layer "In2.Cu") (net 436))
  (segment (start 105.819217 122.598979) (end 105.811255 122.60694) (width 0.109) (layer "In2.Cu") (net 436))
  (segment (start 107.362843 124.229333) (end 107.402235 124.197919) (width 0.109) (layer "In2.Cu") (net 436))
  (segment (start 92.84 136.664) (end 93.3265 136.354) (width 0.182) (layer "F.Cu") (net 438))
  (via (at 92.84 136.664) (size 0.45) (drill 0.1) (layers "F.Cu" "B.Cu") (net 438))
  (segment (start 92.84 136.664) (end 93.404 136.664) (width 0.182) (layer "B.Cu") (net 438))
  (segment (start 93.404 136.664) (end 93.575 136.835) (width 0.182) (layer "B.Cu") (net 438))
  (segment (start 82.229289 104.0008) (end 83.1508 104.0008) (width 0.109) (layer "F.Cu") (net 455))
  (segment (start 84.45 105.3) (end 84.45 107.457404) (width 0.109) (layer "F.Cu") (net 455))
  (segment (start 83.1508 104.0008) (end 84.45 105.3) (width 0.109) (layer "F.Cu") (net 455))
  (segment (start 92.853 121.433) (end 92.3665 121.749) (width 0.182) (layer "F.Cu") (net 455))
  (segment (start 84.45 107.457404) (end 85.317758 108.325162) (width 0.109) (layer "F.Cu") (net 455))
  (via (at 92.853 121.433) (size 0.45) (drill 0.1) (layers "F.Cu" "B.Cu") (net 455))
  (via (at 85.317758 108.325162) (size 0.45) (drill 0.1) (layers "F.Cu" "B.Cu") (net 455))
  (segment (start 85.372096 108.3795) (end 86.8295 108.3795) (width 0.109) (layer "B.Cu") (net 455))
  (segment (start 87.5245 114.060277) (end 87.5245 119.011181) (width 0.109) (layer "B.Cu") (net 455))
  (segment (start 85.317758 108.325162) (end 85.372096 108.3795) (width 0.109) (layer "B.Cu") (net 455))
  (segment (start 88.495319 119.982) (end 91.477336 119.982) (width 0.109) (layer "B.Cu") (net 455))
  (segment (start 87.55 112.611258) (end 87.3 112.861258) (width 0.109) (layer "B.Cu") (net 455))
  (segment (start 92.4605 120.6105) (end 92.4605 121.0405) (width 0.109) (layer "B.Cu") (net 455))
  (segment (start 87.3 113.835777) (end 87.5245 114.060277) (width 0.109) (layer "B.Cu") (net 455))
  (segment (start 87.5245 119.011181) (end 88.495319 119.982) (width 0.109) (layer "B.Cu") (net 455))
  (segment (start 91.904836 120.4095) (end 92.2595 120.4095) (width 0.109) (layer "B.Cu") (net 455))
  (segment (start 87.3 112.861258) (end 87.3 113.835777) (width 0.109) (layer "B.Cu") (net 455))
  (segment (start 87.55 109.1) (end 87.55 112.611258) (width 0.109) (layer "B.Cu") (net 455))
  (segment (start 92.2595 120.4095) (end 92.4605 120.6105) (width 0.109) (layer "B.Cu") (net 455))
  (segment (start 86.8295 108.3795) (end 87.55 109.1) (width 0.109) (layer "B.Cu") (net 455))
  (segment (start 92.4605 121.0405) (end 92.853 121.433) (width 0.109) (layer "B.Cu") (net 455))
  (segment (start 91.477336 119.982) (end 91.904836 120.4095) (width 0.109) (layer "B.Cu") (net 455))
  (segment (start 92.3665 121.114) (end 91.9815 121.424) (width 0.182) (layer "F.Cu") (net 456))
  (segment (start 83.7 107.75) (end 85.25 109.3) (width 0.109) (layer "F.Cu") (net 456))
  (segment (start 82.874105 106.0008) (end 83.7 106.826695) (width 0.109) (layer "F.Cu") (net 456))
  (segment (start 82.229289 106.0008) (end 82.874105 106.0008) (width 0.109) (layer "F.Cu") (net 456))
  (segment (start 83.7 106.826695) (end 83.7 107.75) (width 0.109) (layer "F.Cu") (net 456))
  (via (at 91.9815 121.424) (size 0.45) (drill 0.1) (layers "F.Cu" "B.Cu") (net 456))
  (via (at 85.25 109.3) (size 0.45) (drill 0.1) (layers "F.Cu" "B.Cu") (net 456))
  (segment (start 87.05 110.457057) (end 86.692943 110.1) (width 0.109) (layer "B.Cu") (net 456))
  (segment (start 85.25 109.8) (end 85.25 109.3) (width 0.109) (layer "B.Cu") (net 456))
  (segment (start 86.868 113.994919) (end 86.868 112.702117) (width 0.109) (layer "B.Cu") (net 456))
  (segment (start 88.15 120.4) (end 87.1065 119.3565) (width 0.109) (layer "B.Cu") (net 456))
  (segment (start 86.868 112.702117) (end 87.05 112.520117) (width 0.109) (layer "B.Cu") (net 456))
  (segment (start 87.1065 114.233419) (end 86.868 113.994919) (width 0.109) (layer "B.Cu") (net 456))
  (segment (start 91.304196 120.4) (end 88.15 120.4) (width 0.109) (layer "B.Cu") (net 456))
  (segment (start 85.55 110.1) (end 85.25 109.8) (width 0.109) (layer "B.Cu") (net 456))
  (segment (start 86.692943 110.1) (end 85.55 110.1) (width 0.109) (layer "B.Cu") (net 456))
  (segment (start 87.05 112.520117) (end 87.05 110.457057) (width 0.109) (layer "B.Cu") (net 456))
  (segment (start 87.1065 119.3565) (end 87.1065 114.233419) (width 0.109) (layer "B.Cu") (net 456))
  (segment (start 91.6 120.695804) (end 91.304196 120.4) (width 0.109) (layer "B.Cu") (net 456))
  (segment (start 91.9815 121.424) (end 91.6 121.0425) (width 0.109) (layer "B.Cu") (net 456))
  (segment (start 91.6 121.0425) (end 91.6 120.695804) (width 0.109) (layer "B.Cu") (net 456))
  (segment (start 84.05 107.6) (end 85.3 108.85) (width 0.109) (layer "F.Cu") (net 457))
  (segment (start 81.55 105.0008) (end 83.3008 105.0008) (width 0.109) (layer "F.Cu") (net 457))
  (segment (start 83.3008 105.0008) (end 84.05 105.75) (width 0.109) (layer "F.Cu") (net 457))
  (segment (start 85.3 108.85) (end 85.7 108.85) (width 0.109) (layer "F.Cu") (net 457))
  (segment (start 92.3665 120.479) (end 91.9815 120.789) (width 0.182) (layer "F.Cu") (net 457))
  (segment (start 84.05 105.75) (end 84.05 107.6) (width 0.109) (layer "F.Cu") (net 457))
  (via (at 85.7 108.85) (size 0.45) (drill 0.1) (layers "F.Cu" "B.Cu") (net 457))
  (via (at 91.9815 120.789) (size 0.45) (drill 0.1) (layers "F.Cu" "B.Cu") (net 457))
  (segment (start 87.077 112.788687) (end 87.077 113.908348) (width 0.109) (layer "B.Cu") (net 457))
  (segment (start 87.3155 114.146848) (end 87.3155 119.1655) (width 0.109) (layer "B.Cu") (net 457))
  (segment (start 88.341 120.191) (end 91.390766 120.191) (width 0.109) (layer "B.Cu") (net 457))
  (segment (start 85.7 108.85) (end 86.7 108.85) (width 0.109) (layer "B.Cu") (net 457))
  (segment (start 91.9815 120.781734) (end 91.9815 120.789) (width 0.109) (layer "B.Cu") (net 457))
  (segment (start 91.390766 120.191) (end 91.9815 120.781734) (width 0.109) (layer "B.Cu") (net 457))
  (segment (start 87.077 113.908348) (end 87.3155 114.146848) (width 0.109) (layer "B.Cu") (net 457))
  (segment (start 87.3 112.565687) (end 87.077 112.788687) (width 0.109) (layer "B.Cu") (net 457))
  (segment (start 86.7 108.85) (end 87.3 109.45) (width 0.109) (layer "B.Cu") (net 457))
  (segment (start 87.3 109.45) (end 87.3 112.565687) (width 0.109) (layer "B.Cu") (net 457))
  (segment (start 87.3155 119.1655) (end 88.341 120.191) (width 0.109) (layer "B.Cu") (net 457))
  (segment (start 83.625 102.875) (end 84.075 102.875) (width 0.109) (layer "F.Cu") (net 458))
  (segment (start 82.229289 101.921511) (end 82.671511 101.921511) (width 0.109) (layer "F.Cu") (net 458))
  (segment (start 85.3 104.1) (end 85.3 106.3) (width 0.109) (layer "F.Cu") (net 458))
  (segment (start 82.671511 101.921511) (end 83.625 102.875) (width 0.109) (layer "F.Cu") (net 458))
  (segment (start 84.075 102.875) (end 85.3 104.1) (width 0.109) (layer "F.Cu") (net 458))
  (segment (start 91.9815 119.519) (end 92.3665 119.209) (width 0.182) (layer "F.Cu") (net 458))
  (via (at 91.9815 119.519) (size 0.45) (drill 0.1) (layers "F.Cu" "B.Cu") (net 458))
  (via (at 85.3 106.3) (size 0.45) (drill 0.1) (layers "F.Cu" "B.Cu") (net 458))
  (segment (start 85.3 106.757405) (end 85.3 106.3) (width 0.109) (layer "B.Cu") (net 458))
  (segment (start 87.75 113.25) (end 88.1 112.9) (width 0.109) (layer "B.Cu") (net 458))
  (segment (start 91.9815 119.519) (end 92.361 119.1395) (width 0.109) (layer "B.Cu") (net 458))
  (segment (start 87.959 113.903635) (end 87.75 113.694635) (width 0.109) (layer "B.Cu") (net 458))
  (segment (start 85.742595 107.2) (end 85.3 106.757405) (width 0.109) (layer "B.Cu") (net 458))
  (segment (start 92.361 118.661) (end 91.7085 118.0085) (width 0.109) (layer "B.Cu") (net 458))
  (segment (start 92.361 119.1395) (end 92.361 118.661) (width 0.109) (layer "B.Cu") (net 458))
  (segment (start 91.7085 118.0085) (end 88.2085 118.0085) (width 0.109) (layer "B.Cu") (net 458))
  (segment (start 87.75 113.694635) (end 87.75 113.25) (width 0.109) (layer "B.Cu") (net 458))
  (segment (start 87.2 107.2) (end 85.742595 107.2) (width 0.109) (layer "B.Cu") (net 458))
  (segment (start 88.1 108.1) (end 87.2 107.2) (width 0.109) (layer "B.Cu") (net 458))
  (segment (start 88.2085 118.0085) (end 87.959 117.759) (width 0.109) (layer "B.Cu") (net 458))
  (segment (start 88.1 112.9) (end 88.1 108.1) (width 0.109) (layer "B.Cu") (net 458))
  (segment (start 87.959 117.759) (end 87.959 113.903635) (width 0.109) (layer "B.Cu") (net 458))
  (segment (start 83.4 150.9) (end 81.6 150.9) (width 0.182) (layer "F.Cu") (net 467))
  (segment (start 90.7865 119.209) (end 91.1715 118.899) (width 0.182) (layer "F.Cu") (net 467))
  (segment (start 83.4 147) (end 83.4 147.585) (width 0.182) (layer "F.Cu") (net 467))
  (segment (start 83.415 150.885) (end 83.4 150.9) (width 0.182) (layer "F.Cu") (net 467))
  (segment (start 83.4 147.585) (end 83.415 147.6) (width 0.182) (layer "F.Cu") (net 467))
  (segment (start 85.7 150.9) (end 83.4 150.9) (width 0.182) (layer "F.Cu") (net 467))
  (segment (start 83.415 147.6) (end 83.415 150.885) (width 0.182) (layer "F.Cu") (net 467))
  (via (at 91.1715 118.899) (size 0.45) (drill 0.1) (layers "F.Cu" "B.Cu") (net 467))
  (via (at 83.4 147) (size 0.45) (drill 0.1) (layers "F.Cu" "B.Cu") (net 467))
  (segment (start 91.602 119.676195) (end 91.824305 119.8985) (width 0.109) (layer "B.Cu") (net 467))
  (segment (start 89.191 122.309) (end 88.65 122.85) (width 0.109) (layer "B.Cu") (net 467))
  (segment (start 90.7 131.2) (end 91.1 131.6) (width 0.109) (layer "B.Cu") (net 467))
  (segment (start 89.4 127.717195) (end 89.4 128.883305) (width 0.109) (layer "B.Cu") (net 467))
  (segment (start 89.1 138.8) (end 83.4 144.5) (width 0.109) (layer "B.Cu") (net 467))
  (segment (start 94.3 137.4) (end 92.9 138.8) (width 0.109) (layer "B.Cu") (net 467))
  (segment (start 93.010195 121.8125) (end 91.334695 121.8125) (width 0.109) (layer "B.Cu") (net 467))
  (segment (start 83.4 144.5) (end 83.4 147) (width 0.109) (layer "B.Cu") (net 467))
  (segment (start 93.2325 121.590195) (end 93.010195 121.8125) (width 0.109) (layer "B.Cu") (net 467))
  (segment (start 88.65 124.979195) (end 89.821 126.150195) (width 0.109) (layer "B.Cu") (net 467))
  (segment (start 93.2325 120.650805) (end 93.2325 121.590195) (width 0.109) (layer "B.Cu") (net 467))
  (segment (start 94.3 133.8) (end 94.3 137.4) (width 0.109) (layer "B.Cu") (net 467))
  (segment (start 92.9 138.8) (end 89.1 138.8) (width 0.109) (layer "B.Cu") (net 467))
  (segment (start 90.7 130.183305) (end 90.7 131.2) (width 0.109) (layer "B.Cu") (net 467))
  (segment (start 89.4 128.883305) (end 90.7 130.183305) (width 0.109) (layer "B.Cu") (net 467))
  (segment (start 91.1 131.6) (end 92.751695 131.6) (width 0.109) (layer "B.Cu") (net 467))
  (segment (start 91.334695 121.8125) (end 90.838195 122.309) (width 0.109) (layer "B.Cu") (net 467))
  (segment (start 92.480195 119.8985) (end 93.2325 120.650805) (width 0.109) (layer "B.Cu") (net 467))
  (segment (start 93.7 132.548305) (end 93.7 133.2) (width 0.109) (layer "B.Cu") (net 467))
  (segment (start 91.1715 118.899) (end 91.602 119.3295) (width 0.109) (layer "B.Cu") (net 467))
  (segment (start 91.602 119.3295) (end 91.602 119.676195) (width 0.109) (layer "B.Cu") (net 467))
  (segment (start 92.751695 131.6) (end 93.7 132.548305) (width 0.109) (layer "B.Cu") (net 467))
  (segment (start 93.7 133.2) (end 94.3 133.8) (width 0.109) (layer "B.Cu") (net 467))
  (segment (start 90.838195 122.309) (end 89.191 122.309) (width 0.109) (layer "B.Cu") (net 467))
  (segment (start 89.821 127.296195) (end 89.4 127.717195) (width 0.109) (layer "B.Cu") (net 467))
  (segment (start 89.821 126.150195) (end 89.821 127.296195) (width 0.109) (layer "B.Cu") (net 467))
  (segment (start 91.824305 119.8985) (end 92.480195 119.8985) (width 0.109) (layer "B.Cu") (net 467))
  (segment (start 88.65 122.85) (end 88.65 124.979195) (width 0.109) (layer "B.Cu") (net 467))
  (segment (start 82.4 108.9) (end 81.55 108.9) (width 0.109) (layer "F.Cu") (net 473))
  (segment (start 85.6 112.1) (end 82.4 108.9) (width 0.109) (layer "F.Cu") (net 473))
  (segment (start 85.6 112.4) (end 85.6 112.1) (width 0.109) (layer "F.Cu") (net 473))
  (segment (start 90.313 121.433) (end 89.8265 121.749) (width 0.182) (layer "F.Cu") (net 473))
  (via (at 85.6 112.4) (size 0.45) (drill 0.1) (layers "F.Cu" "B.Cu") (net 473))
  (via (at 90.313 121.433) (size 0.45) (drill 0.1) (layers "F.Cu" "B.Cu") (net 473))
  (segment (start 86.4795 115.200239) (end 85.4205 114.141239) (width 0.109) (layer "B.Cu") (net 473))
  (segment (start 85.4205 114.141239) (end 85.4205 112.5795) (width 0.109) (layer "B.Cu") (net 473))
  (segment (start 90.313 121.433) (end 90.067 121.433) (width 0.109) (layer "B.Cu") (net 473))
  (segment (start 89.5 122) (end 88.5 122) (width 0.109) (layer "B.Cu") (net 473))
  (segment (start 90.067 121.433) (end 89.5 122) (width 0.109) (layer "B.Cu") (net 473))
  (segment (start 86.4795 119.9795) (end 86.4795 115.200239) (width 0.109) (layer "B.Cu") (net 473))
  (segment (start 85.4205 112.5795) (end 85.6 112.4) (width 0.109) (layer "B.Cu") (net 473))
  (segment (start 88.5 122) (end 86.4795 119.9795) (width 0.109) (layer "B.Cu") (net 473))
  (segment (start 89.8265 121.114) (end 89.4415 121.424) (width 0.182) (layer "F.Cu") (net 474))
  (segment (start 83.5 109.3) (end 84.95 110.75) (width 0.109) (layer "F.Cu") (net 474))
  (segment (start 83.5 108.633305) (end 83.5 109.3) (width 0.109) (layer "F.Cu") (net 474))
  (segment (start 82.817495 107.9508) (end 83.5 108.633305) (width 0.109) (layer "F.Cu") (net 474))
  (segment (start 82.229289 107.9508) (end 82.817495 107.9508) (width 0.109) (layer "F.Cu") (net 474))
  (segment (start 84.95 110.75) (end 85.3 110.75) (width 0.109) (layer "F.Cu") (net 474))
  (via (at 85.3 110.75) (size 0.45) (drill 0.1) (layers "F.Cu" "B.Cu") (net 474))
  (via (at 89.4415 121.424) (size 0.45) (drill 0.1) (layers "F.Cu" "B.Cu") (net 474))
  (segment (start 86.45 114.168061) (end 86.6885 114.406561) (width 0.109) (layer "B.Cu") (net 474))
  (segment (start 86.45 112.528975) (end 86.45 114.168061) (width 0.109) (layer "B.Cu") (net 474))
  (segment (start 85.3 110.75) (end 86.570057 112.020057) (width 0.109) (layer "B.Cu") (net 474))
  (segment (start 86.570057 112.408918) (end 86.45 112.528975) (width 0.109) (layer "B.Cu") (net 474))
  (segment (start 89.2655 121.6) (end 89.4415 121.424) (width 0.109) (layer "B.Cu") (net 474))
  (segment (start 86.6885 119.7885) (end 88.5 121.6) (width 0.109) (layer "B.Cu") (net 474))
  (segment (start 86.570057 112.020057) (end 86.570057 112.408918) (width 0.109) (layer "B.Cu") (net 474))
  (segment (start 88.5 121.6) (end 89.2655 121.6) (width 0.109) (layer "B.Cu") (net 474))
  (segment (start 86.6885 114.406561) (end 86.6885 119.7885) (width 0.109) (layer "B.Cu") (net 474))
  (segment (start 84 108.65) (end 82.3508 107.0008) (width 0.109) (layer "F.Cu") (net 475))
  (segment (start 82.3508 107.0008) (end 81.55 107.0008) (width 0.109) (layer "F.Cu") (net 475))
  (segment (start 85.65 110.15) (end 85.15 110.15) (width 0.109) (layer "F.Cu") (net 475))
  (segment (start 89.8265 120.479) (end 89.4415 120.789) (width 0.182) (layer "F.Cu") (net 475))
  (segment (start 86.05 110.55) (end 85.65 110.15) (width 0.109) (layer "F.Cu") (net 475))
  (segment (start 84 109) (end 84 108.65) (width 0.109) (layer "F.Cu") (net 475))
  (segment (start 85.15 110.15) (end 84 109) (width 0.109) (layer "F.Cu") (net 475))
  (via (at 86.05 110.55) (size 0.45) (drill 0.1) (layers "F.Cu" "B.Cu") (net 475))
  (via (at 89.4415 120.789) (size 0.45) (drill 0.1) (layers "F.Cu" "B.Cu") (net 475))
  (segment (start 86.659 114.08149) (end 86.659 112.615546) (width 0.109) (layer "B.Cu") (net 475))
  (segment (start 86.779057 112.495489) (end 86.779057 111.279057) (width 0.109) (layer "B.Cu") (net 475))
  (segment (start 86.779057 111.279057) (end 86.05 110.55) (width 0.109) (layer "B.Cu") (net 475))
  (segment (start 88.592595 121.3) (end 86.8975 119.604905) (width 0.109) (layer "B.Cu") (net 475))
  (segment (start 86.8975 114.31999) (end 86.659 114.08149) (width 0.109) (layer "B.Cu") (net 475))
  (segment (start 86.659 112.615546) (end 86.779057 112.495489) (width 0.109) (layer "B.Cu") (net 475))
  (segment (start 89.4415 120.789) (end 88.9305 121.3) (width 0.109) (layer "B.Cu") (net 475))
  (segment (start 88.9305 121.3) (end 88.592595 121.3) (width 0.109) (layer "B.Cu") (net 475))
  (segment (start 86.8975 119.604905) (end 86.8975 114.31999) (width 0.109) (layer "B.Cu") (net 475))
  (segment (start 84.85 104.75) (end 84.85 106.932417) (width 0.109) (layer "F.Cu") (net 476))
  (segment (start 84.85 106.932417) (end 85.253278 107.335695) (width 0.109) (layer "F.Cu") (net 476))
  (segment (start 83.0508 102.9508) (end 84.85 104.75) (width 0.109) (layer "F.Cu") (net 476))
  (segment (start 89.4415 119.519) (end 89.8265 119.209) (width 0.182) (layer "F.Cu") (net 476))
  (segment (start 81.55 102.9508) (end 83.0508 102.9508) (width 0.109) (layer "F.Cu") (net 476))
  (via (at 89.4415 119.519) (size 0.45) (drill 0.1) (layers "F.Cu" "B.Cu") (net 476))
  (via (at 85.253278 107.335695) (size 0.45) (drill 0.1) (layers "F.Cu" "B.Cu") (net 476))
  (segment (start 86.7705 107.5205) (end 85.438083 107.5205) (width 0.109) (layer "B.Cu") (net 476))
  (segment (start 87.85 112.606829) (end 87.85 108.6) (width 0.109) (layer "B.Cu") (net 476))
  (segment (start 87.509 112.947829) (end 87.85 112.606829) (width 0.109) (layer "B.Cu") (net 476))
  (segment (start 87.509 113.749206) (end 87.509 112.947829) (width 0.109) (layer "B.Cu") (net 476))
  (segment (start 88.879494 118.479494) (end 88.7205 118.3205) (width 0.109) (layer "B.Cu") (net 476))
  (segment (start 88.1705 118.3205) (end 87.7335 117.8835) (width 0.109) (layer "B.Cu") (net 476))
  (segment (start 89.4415 119.519) (end 88.879494 118.956994) (width 0.109) (layer "B.Cu") (net 476))
  (segment (start 87.85 108.6) (end 86.7705 107.5205) (width 0.109) (layer "B.Cu") (net 476))
  (segment (start 85.438083 107.5205) (end 85.253278 107.335695) (width 0.109) (layer "B.Cu") (net 476))
  (segment (start 87.7335 117.8835) (end 87.7335 113.973706) (width 0.109) (layer "B.Cu") (net 476))
  (segment (start 88.879494 118.956994) (end 88.879494 118.479494) (width 0.109) (layer "B.Cu") (net 476))
  (segment (start 88.7205 118.3205) (end 88.1705 118.3205) (width 0.109) (layer "B.Cu") (net 476))
  (segment (start 87.7335 113.973706) (end 87.509 113.749206) (width 0.109) (layer "B.Cu") (net 476))
  (segment (start 99.737238 118.6128) (end 99.999342 118.350696) (width 0.182) (layer "F.Cu") (net 638))
  (segment (start 129.725 136.35) (end 129.725 135.815684) (width 0.182) (layer "F.Cu") (net 638))
  (segment (start 98.0553 118.6128) (end 98.0457 118.6032) (width 0.182) (layer "F.Cu") (net 638))
  (segment (start 129.725 135.815684) (end 129.524987 135.615671) (width 0.182) (layer "F.Cu") (net 638))
  (segment (start 99.737238 118.6128) (end 98.0553 118.6128) (width 0.182) (layer "F.Cu") (net 638))
  (segment (start 129.524987 135.615671) (end 129.524987 135.5) (width 0.182) (layer "F.Cu") (net 638))
  (via (at 99.999342 118.350696) (size 0.45) (drill 0.1) (layers "F.Cu" "B.Cu") (net 638))
  (via (at 129.524987 135.5) (size 0.45) (drill 0.1) (layers "F.Cu" "B.Cu") (net 638))
  (segment (start 108.30862 125.465389) (end 108.359004 125.465389) (width 0.109) (layer "In2.Cu") (net 638))
  (segment (start 102.722793 118.022793) (end 104.8 120.1) (width 0.109) (layer "In2.Cu") (net 638))
  (segment (start 109.072711 126.572575) (end 109.061499 126.621695) (width 0.109) (layer "In2.Cu") (net 638))
  (segment (start 99.58401 117.935364) (end 99.58401 117.64099) (width 0.109) (layer "In2.Cu") (net 638))
  (segment (start 107.616466 125.907989) (end 107.665587 125.919201) (width 0.109) (layer "In2.Cu") (net 638))
  (segment (start 108.492911 125.529876) (end 108.524324 125.569267) (width 0.109) (layer "In2.Cu") (net 638))
  (segment (start 104.8 120.1) (end 104.8 122.48) (width 0.109) (layer "In2.Cu") (net 638))
  (segment (start 107.566413 125.493806) (end 107.535 125.533198) (width 0.109) (layer "In2.Cu") (net 638))
  (segment (start 108.114799 126.257698) (end 108.103587 126.306818) (width 0.109) (layer "In2.Cu") (net 638))
  (segment (start 107.535 125.533198) (end 107.53168 125.536517) (width 0.109) (layer "In2.Cu") (net 638))
  (segment (start 107.467193 125.670424) (end 107.467193 125.720808) (width 0.109) (layer "In2.Cu") (net 638))
  (segment (start 108.352365 126.555595) (end 108.401485 126.544383) (width 0.109) (layer "In2.Cu") (net 638))
  (segment (start 109.193792 126.300178) (end 109.193792 126.350562) (width 0.109) (layer "In2.Cu") (net 638))
  (segment (start 108.214105 125.498462) (end 108.2595 125.476601) (width 0.109) (layer "In2.Cu") (net 638))
  (segment (start 108.13666 126.451718) (end 108.168074 126.491109) (width 0.109) (layer "In2.Cu") (net 638))
  (segment (start 108.114799 126.406323) (end 108.13666 126.451718) (width 0.109) (layer "In2.Cu") (net 638))
  (segment (start 107.571071 125.886128) (end 107.616466 125.907989) (width 0.109) (layer "In2.Cu") (net 638))
  (segment (start 108.168074 126.491109) (end 108.207465 126.522522) (width 0.109) (layer "In2.Cu") (net 638))
  (segment (start 108.557398 125.714168) (end 108.546186 125.763288) (width 0.109) (layer "In2.Cu") (net 638))
  (segment (start 108.103587 126.306818) (end 108.103587 126.357202) (width 0.109) (layer "In2.Cu") (net 638))
  (segment (start 107.478405 125.769929) (end 107.500266 125.815324) (width 0.109) (layer "In2.Cu") (net 638))
  (segment (start 109.193792 126.350562) (end 109.18258 126.399682) (width 0.109) (layer "In2.Cu") (net 638))
  (segment (start 109.125986 126.487788) (end 109.094572 126.52718) (width 0.109) (layer "In2.Cu") (net 638))
  (segment (start 109.061499 126.621695) (end 109.061499 126.672079) (width 0.109) (layer "In2.Cu") (net 638))
  (segment (start 107.566413 125.254391) (end 107.588274 125.299786) (width 0.109) (layer "In2.Cu") (net 638))
  (segment (start 107.853197 125.851395) (end 108.174715 125.529878) (width 0.109) (layer "In2.Cu") (net 638))
  (segment (start 107.849878 125.854715) (end 107.853197 125.851395) (width 0.109) (layer "In2.Cu") (net 638))
  (segment (start 107.535 125.215) (end 107.566413 125.254391) (width 0.109) (layer "In2.Cu") (net 638))
  (segment (start 109.160719 126.445077) (end 109.129305 126.484468) (width 0.109) (layer "In2.Cu") (net 638))
  (segment (start 109.160718 126.205661) (end 109.182579 126.251056) (width 0.109) (layer "In2.Cu") (net 638))
  (segment (start 108.44688 126.522522) (end 108.486272 126.491109) (width 0.109) (layer "In2.Cu") (net 638))
  (segment (start 107.467193 125.720808) (end 107.478405 125.769929) (width 0.109) (layer "In2.Cu") (net 638))
  (segment (start 108.2595 125.476601) (end 108.30862 125.465389) (width 0.109) (layer "In2.Cu") (net 638))
  (segment (start 108.207465 126.522522) (end 108.25286 126.544383) (width 0.109) (layer "In2.Cu") (net 638))
  (segment (start 107.715971 125.919201) (end 107.765091 125.907989) (width 0.109) (layer "In2.Cu") (net 638))
  (segment (start 109.089915 126.134857) (end 109.129305 126.16627) (width 0.109) (layer "In2.Cu") (net 638))
  (segment (start 109.125986 126.805986) (end 116.8 134.48) (width 0.109) (layer "In2.Cu") (net 638))
  (segment (start 108.13666 126.212303) (end 108.114799 126.257698) (width 0.109) (layer "In2.Cu") (net 638))
  (segment (start 108.811109 126.166272) (end 108.850499 126.134856) (width 0.109) (layer "In2.Cu") (net 638))
  (segment (start 107.478405 125.621304) (end 107.467193 125.670424) (width 0.109) (layer "In2.Cu") (net 638))
  (segment (start 108.895894 126.112995) (end 108.945014 126.101783) (width 0.109) (layer "In2.Cu") (net 638))
  (segment (start 107.53168 125.536517) (end 107.500266 125.575909) (width 0.109) (layer "In2.Cu") (net 638))
  (segment (start 108.524324 125.569267) (end 108.546185 125.614662) (width 0.109) (layer "In2.Cu") (net 638))
  (segment (start 101.075 117.375) (end 101.722793 118.022793) (width 0.109) (layer "In2.Cu") (net 638))
  (segment (start 108.401485 126.544383) (end 108.44688 126.522522) (width 0.109) (layer "In2.Cu") (net 638))
  (segment (start 108.168074 126.172911) (end 108.13666 126.212303) (width 0.109) (layer "In2.Cu") (net 638))
  (segment (start 109.094572 126.52718) (end 109.072711 126.572575) (width 0.109) (layer "In2.Cu") (net 638))
  (segment (start 108.359004 125.465389) (end 108.408126 125.476602) (width 0.109) (layer "In2.Cu") (net 638))
  (segment (start 104.8 122.48) (end 107.535 125.215) (width 0.109) (layer "In2.Cu") (net 638))
  (segment (start 107.53168 125.854715) (end 107.571071 125.886128) (width 0.109) (layer "In2.Cu") (net 638))
  (segment (start 125.755 134.48) (end 127.054501 135.779501) (width 0.109) (layer "In2.Cu") (net 638))
  (segment (start 109.129305 126.484468) (end 109.125986 126.487788) (width 0.109) (layer "In2.Cu") (net 638))
  (segment (start 109.182579 126.251056) (end 109.193792 126.300178) (width 0.109) (layer "In2.Cu") (net 638))
  (segment (start 108.524325 125.808683) (end 108.492911 125.848074) (width 0.109) (layer "In2.Cu") (net 638))
  (segment (start 108.301981 126.555595) (end 108.352365 126.555595) (width 0.109) (layer "In2.Cu") (net 638))
  (segment (start 109.129305 126.16627) (end 109.160718 126.205661) (width 0.109) (layer "In2.Cu") (net 638))
  (segment (start 107.665587 125.919201) (end 107.715971 125.919201) (width 0.109) (layer "In2.Cu") (net 638))
  (segment (start 108.995398 126.101783) (end 109.04452 126.112996) (width 0.109) (layer "In2.Cu") (net 638))
  (segment (start 108.492911 125.848074) (end 108.168074 126.172911) (width 0.109) (layer "In2.Cu") (net 638))
  (segment (start 107.500266 125.575909) (end 107.478405 125.621304) (width 0.109) (layer "In2.Cu") (net 638))
  (segment (start 108.546185 125.614662) (end 108.557398 125.663784) (width 0.109) (layer "In2.Cu") (net 638))
  (segment (start 108.850499 126.134856) (end 108.895894 126.112995) (width 0.109) (layer "In2.Cu") (net 638))
  (segment (start 109.18258 126.399682) (end 109.160719 126.445077) (width 0.109) (layer "In2.Cu") (net 638))
  (segment (start 108.25286 126.544383) (end 108.301981 126.555595) (width 0.109) (layer "In2.Cu") (net 638))
  (segment (start 109.061499 126.672079) (end 109.07271 126.721199) (width 0.109) (layer "In2.Cu") (net 638))
  (segment (start 99.999342 118.350696) (end 99.58401 117.935364) (width 0.109) (layer "In2.Cu") (net 638))
  (segment (start 127.054501 135.779501) (end 127.957161 135.779501) (width 0.109) (layer "In2.Cu") (net 638))
  (segment (start 107.588274 125.299786) (end 107.599486 125.348907) (width 0.109) (layer "In2.Cu") (net 638))
  (segment (start 108.453521 125.498463) (end 108.492911 125.529876) (width 0.109) (layer "In2.Cu") (net 638))
  (segment (start 107.765091 125.907989) (end 107.810486 125.886128) (width 0.109) (layer "In2.Cu") (net 638))
  (segment (start 108.174715 125.529878) (end 108.214105 125.498462) (width 0.109) (layer "In2.Cu") (net 638))
  (segment (start 107.599486 125.348907) (end 107.599486 125.399291) (width 0.109) (layer "In2.Cu") (net 638))
  (segment (start 116.8 134.48) (end 125.755 134.48) (width 0.109) (layer "In2.Cu") (net 638))
  (segment (start 108.557398 125.663784) (end 108.557398 125.714168) (width 0.109) (layer "In2.Cu") (net 638))
  (segment (start 107.810486 125.886128) (end 107.849878 125.854715) (width 0.109) (layer "In2.Cu") (net 638))
  (segment (start 99.85 117.375) (end 101.075 117.375) (width 0.109) (layer "In2.Cu") (net 638))
  (segment (start 99.58401 117.64099) (end 99.85 117.375) (width 0.109) (layer "In2.Cu") (net 638))
  (segment (start 107.599486 125.399291) (end 107.588274 125.448411) (width 0.109) (layer "In2.Cu") (net 638))
  (segment (start 109.04452 126.112996) (end 109.089915 126.134857) (width 0.109) (layer "In2.Cu") (net 638))
  (segment (start 128.236662 135.5) (end 129.524987 135.5) (width 0.109) (layer "In2.Cu") (net 638))
  (segment (start 107.500266 125.815324) (end 107.53168 125.854715) (width 0.109) (layer "In2.Cu") (net 638))
  (segment (start 127.957161 135.779501) (end 128.236662 135.5) (width 0.109) (layer "In2.Cu") (net 638))
  (segment (start 108.486272 126.491109) (end 108.811109 126.166272) (width 0.109) (layer "In2.Cu") (net 638))
  (segment (start 101.722793 118.022793) (end 102.722793 118.022793) (width 0.109) (layer "In2.Cu") (net 638))
  (segment (start 108.945014 126.101783) (end 108.995398 126.101783) (width 0.109) (layer "In2.Cu") (net 638))
  (segment (start 108.546186 125.763288) (end 108.524325 125.808683) (width 0.109) (layer "In2.Cu") (net 638))
  (segment (start 109.07271 126.721199) (end 109.094571 126.766594) (width 0.109) (layer "In2.Cu") (net 638))
  (segment (start 109.094571 126.766594) (end 109.125986 126.805986) (width 0.109) (layer "In2.Cu") (net 638))
  (segment (start 108.103587 126.357202) (end 108.114799 126.406323) (width 0.109) (layer "In2.Cu") (net 638))
  (segment (start 108.408126 125.476602) (end 108.453521 125.498463) (width 0.109) (layer "In2.Cu") (net 638))
  (segment (start 107.588274 125.448411) (end 107.566413 125.493806) (width 0.109) (layer "In2.Cu") (net 638))
  (segment (start 98.0489 118.2064) (end 98.0457 118.2032) (width 0.182) (layer "F.Cu") (net 639))
  (segment (start 99.55531 118.2064) (end 98.0489 118.2064) (width 0.182) (layer "F.Cu") (net 639))
  (segment (start 129.325 136.125) (end 129.12951 135.92951) (width 0.182) (layer "F.Cu") (net 639))
  (segment (start 129.325 136.35) (end 129.325 136.125) (width 0.182) (layer "F.Cu") (net 639))
  (segment (start 129.10715 135.92951) (end 128.748589 135.92951) (width 0.182) (layer "F.Cu") (net 639))
  (segment (start 99.55531 118.2064) (end 99.976218 117.785492) (width 0.182) (layer "F.Cu") (net 639))
  (segment (start 129.12951 135.92951) (end 129.10715 135.92951) (width 0.182) (layer "F.Cu") (net 639))
  (via (at 99.976218 117.785492) (size 0.45) (drill 0.1) (layers "F.Cu" "B.Cu") (net 639))
  (via (at 128.748589 135.92951) (size 0.45) (drill 0.1) (layers "F.Cu" "B.Cu") (net 639))
  (segment (start 105.625147 124.111063) (end 105.65654 124.071697) (width 0.109) (layer "In2.Cu") (net 639))
  (segment (start 106.420851 125.224758) (end 106.420747 125.224654) (width 0.109) (layer "In2.Cu") (net 639))
  (segment (start 106.261752 125.38365) (end 106.222385 125.415042) (width 0.109) (layer "In2.Cu") (net 639))
  (segment (start 106.028493 125.436889) (end 105.983127 125.415042) (width 0.109) (layer "In2.Cu") (net 639))
  (segment (start 102.293379 118.493379) (end 100.684105 118.493379) (width 0.109) (layer "In2.Cu") (net 639))
  (segment (start 104.391926 123.187861) (end 104.35256 123.156468) (width 0.109) (layer "In2.Cu") (net 639))
  (segment (start 105.65654 124.071697) (end 105.678386 124.026333) (width 0.109) (layer "In2.Cu") (net 639))
  (segment (start 105.689591 123.926893) (end 105.678386 123.877804) (width 0.109) (layer "In2.Cu") (net 639))
  (segment (start 106.96249 125.250142) (end 106.96249 125.199791) (width 0.109) (layer "In2.Cu") (net 639))
  (segment (start 105.689591 123.977244) (end 105.689591 123.926893) (width 0.109) (layer "In2.Cu") (net 639))
  (segment (start 106.929439 125.105337) (end 106.898046 125.065971) (width 0.109) (layer "In2.Cu") (net 639))
  (segment (start 105.053194 123.340847) (end 105.053194 123.290496) (width 0.109) (layer "In2.Cu") (net 639))
  (segment (start 125.16 135.26) (end 116.456093 135.26) (width 0.109) (layer "In2.Cu") (net 639))
  (segment (start 105.540208 123.739625) (end 105.491119 123.728421) (width 0.109) (layer "In2.Cu") (net 639))
  (segment (start 104.536731 123.220912) (end 104.48638 123.220912) (width 0.109) (layer "In2.Cu") (net 639))
  (segment (start 104.755699 124.164095) (end 104.710333 124.142248) (width 0.109) (layer "In2.Cu") (net 639))
  (segment (start 106.713667 125.001319) (end 106.664578 125.012523) (width 0.109) (layer "In2.Cu") (net 639))
  (segment (start 104.606316 123.976828) (end 104.606315 123.926476) (width 0.109) (layer "In2.Cu") (net 639))
  (segment (start 106.127516 124.364818) (end 106.077165 124.364818) (width 0.109) (layer "In2.Cu") (net 639))
  (segment (start 104.639366 123.832024) (end 104.670759 123.792656) (width 0.109) (layer "In2.Cu") (net 639))
  (segment (start 105.441185 124.811697) (end 105.392096 124.800492) (width 0.109) (layer "In2.Cu") (net 639))
  (segment (start 104.988958 124.110856) (end 105.306948 123.792865) (width 0.109) (layer "In2.Cu") (net 639))
  (segment (start 104.437291 123.209707) (end 104.391926 123.187861) (width 0.109) (layer "In2.Cu") (net 639))
  (segment (start 105.65654 123.832439) (end 105.625147 123.793073) (width 0.109) (layer "In2.Cu") (net 639))
  (segment (start 104.804788 124.1753) (end 104.755699 124.164095) (width 0.109) (layer "In2.Cu") (net 639))
  (segment (start 105.943762 125.38365) (end 105.943554 125.383442) (width 0.109) (layer "In2.Cu") (net 639))
  (segment (start 104.631184 123.187861) (end 104.58582 123.209707) (width 0.109) (layer "In2.Cu") (net 639))
  (segment (start 104.05 120.25) (end 102.293379 118.493379) (width 0.109) (layer "In2.Cu") (net 639))
  (segment (start 106.261336 124.429262) (end 106.22197 124.397868) (width 0.109) (layer "In2.Cu") (net 639))
  (segment (start 104.98875 123.156676) (end 104.988542 123.156468) (width 0.109) (layer "In2.Cu") (net 639))
  (segment (start 105.943554 125.383442) (end 105.91216 125.344076) (width 0.109) (layer "In2.Cu") (net 639))
  (segment (start 105.625355 124.747253) (end 105.943345 124.429262) (width 0.109) (layer "In2.Cu") (net 639))
  (segment (start 100.684105 118.493379) (end 99.976218 117.785492) (width 0.109) (layer "In2.Cu") (net 639))
  (segment (start 116.456093 135.26) (end 106.898046 125.701953) (width 0.109) (layer "In2.Cu") (net 639))
  (segment (start 106.844806 125.468693) (end 106.866652 125.423328) (width 0.109) (layer "In2.Cu") (net 639))
  (segment (start 104.710333 124.142248) (end 104.670968 124.110856) (width 0.109) (layer "In2.Cu") (net 639))
  (segment (start 106.664578 125.012523) (end 106.619214 125.034369) (width 0.109) (layer "In2.Cu") (net 639))
  (segment (start 105.253917 124.513785) (end 105.275763 124.468421) (width 0.109) (layer "In2.Cu") (net 639))
  (segment (start 106.897838 125.065763) (end 106.858472 125.034369) (width 0.109) (layer "In2.Cu") (net 639))
  (segment (start 128.748589 135.92951) (end 128.52359 136.154509) (width 0.109) (layer "In2.Cu") (net 639))
  (segment (start 106.866652 125.423328) (end 106.929439 125.344595) (width 0.109) (layer "In2.Cu") (net 639))
  (segment (start 105.585988 124.778645) (end 105.540624 124.800491) (width 0.109) (layer "In2.Cu") (net 639))
  (segment (start 104.67076 124.110648) (end 104.639366 124.071282) (width 0.109) (layer "In2.Cu") (net 639))
  (segment (start 105.391679 123.739625) (end 105.346315 123.761471) (width 0.109) (layer "In2.Cu") (net 639))
  (segment (start 106.898046 125.065971) (end 106.897838 125.065763) (width 0.109) (layer "In2.Cu") (net 639))
  (segment (start 105.491535 124.811696) (end 105.441185 124.811697) (width 0.109) (layer "In2.Cu") (net 639))
  (segment (start 106.176605 124.376022) (end 106.127516 124.364818) (width 0.109) (layer "In2.Cu") (net 639))
  (segment (start 106.96249 125.199791) (end 106.951285 125.150702) (width 0.109) (layer "In2.Cu") (net 639))
  (segment (start 106.929439 125.344595) (end 106.951285 125.299231) (width 0.109) (layer "In2.Cu") (net 639))
  (segment (start 106.858472 125.034369) (end 106.813107 125.012523) (width 0.109) (layer "In2.Cu") (net 639))
  (segment (start 105.585573 123.761471) (end 105.540208 123.739625) (width 0.109) (layer "In2.Cu") (net 639))
  (segment (start 104.904227 124.164094) (end 104.855138 124.175299) (width 0.109) (layer "In2.Cu") (net 639))
  (segment (start 106.325988 124.56329) (end 106.314783 124.514201) (width 0.109) (layer "In2.Cu") (net 639))
  (segment (start 105.678386 124.026333) (end 105.689591 123.977244) (width 0.109) (layer "In2.Cu") (net 639))
  (segment (start 126.054509 136.154509) (end 125.16 135.26) (width 0.109) (layer "In2.Cu") (net 639))
  (segment (start 104.48638 123.220912) (end 104.437291 123.209707) (width 0.109) (layer "In2.Cu") (net 639))
  (segment (start 105.625355 124.747253) (end 105.585988 124.778645) (width 0.109) (layer "In2.Cu") (net 639))
  (segment (start 106.764018 125.001319) (end 106.713667 125.001319) (width 0.109) (layer "In2.Cu") (net 639))
  (segment (start 105.307365 124.747253) (end 105.307157 124.747045) (width 0.109) (layer "In2.Cu") (net 639))
  (segment (start 106.292937 124.468836) (end 106.261544 124.42947) (width 0.109) (layer "In2.Cu") (net 639))
  (segment (start 104.709918 123.125074) (end 104.631184 123.187861) (width 0.109) (layer "In2.Cu") (net 639))
  (segment (start 104.988958 124.110856) (end 104.949591 124.142248) (width 0.109) (layer "In2.Cu") (net 639))
  (segment (start 104.903811 123.103228) (end 104.854722 123.092024) (width 0.109) (layer "In2.Cu") (net 639))
  (segment (start 104.58582 123.209707) (end 104.536731 123.220912) (width 0.109) (layer "In2.Cu") (net 639))
  (segment (start 104.606315 123.926476) (end 104.61752 123.877388) (width 0.109) (layer "In2.Cu") (net 639))
  (segment (start 106.833601 125.568133) (end 106.833601 125.517782) (width 0.109) (layer "In2.Cu") (net 639))
  (segment (start 104.988542 123.156468) (end 104.949176 123.125074) (width 0.109) (layer "In2.Cu") (net 639))
  (segment (start 106.261544 124.42947) (end 106.261336 124.429262) (width 0.109) (layer "In2.Cu") (net 639))
  (segment (start 105.307156 124.429053) (end 105.625147 124.111063) (width 0.109) (layer "In2.Cu") (net 639))
  (segment (start 105.041989 123.241407) (end 105.020143 123.196042) (width 0.109) (layer "In2.Cu") (net 639))
  (segment (start 104.617519 124.025916) (end 104.606316 123.976828) (width 0.109) (layer "In2.Cu") (net 639))
  (segment (start 105.982712 124.397868) (end 105.943345 124.429262) (width 0.109) (layer "In2.Cu") (net 639))
  (segment (start 104.639366 124.071282) (end 104.617519 124.025916) (width 0.109) (layer "In2.Cu") (net 639))
  (segment (start 105.041989 123.389936) (end 105.053194 123.340847) (width 0.109) (layer "In2.Cu") (net 639))
  (segment (start 106.579847 125.065763) (end 106.420851 125.224758) (width 0.109) (layer "In2.Cu") (net 639))
  (segment (start 105.890313 125.29871) (end 105.87911 125.249622) (width 0.109) (layer "In2.Cu") (net 639))
  (segment (start 106.833601 125.517782) (end 106.844806 125.468693) (width 0.109) (layer "In2.Cu") (net 639))
  (segment (start 106.314783 124.66273) (end 106.325988 124.613641) (width 0.109) (layer "In2.Cu") (net 639))
  (segment (start 104.35256 123.156468) (end 104.05 122.853907) (width 0.109) (layer "In2.Cu") (net 639))
  (segment (start 105.392096 124.800492) (end 105.34673 124.778645) (width 0.109) (layer "In2.Cu") (net 639))
  (segment (start 128.52359 136.154509) (end 126.054509 136.154509) (width 0.109) (layer "In2.Cu") (net 639))
  (segment (start 104.61752 123.877388) (end 104.639366 123.832024) (width 0.109) (layer "In2.Cu") (net 639))
  (segment (start 106.951285 125.299231) (end 106.96249 125.250142) (width 0.109) (layer "In2.Cu") (net 639))
  (segment (start 106.177021 125.436888) (end 106.127932 125.448093) (width 0.109) (layer "In2.Cu") (net 639))
  (segment (start 106.325988 124.613641) (end 106.325988 124.56329) (width 0.109) (layer "In2.Cu") (net 639))
  (segment (start 104.854722 123.092024) (end 104.804371 123.092024) (width 0.109) (layer "In2.Cu") (net 639))
  (segment (start 106.951285 125.150702) (end 106.929439 125.105337) (width 0.109) (layer "In2.Cu") (net 639))
  (segment (start 105.020143 123.196042) (end 104.98875 123.156676) (width 0.109) (layer "In2.Cu") (net 639))
  (segment (start 105.91216 125.344076) (end 105.890313 125.29871) (width 0.109) (layer "In2.Cu") (net 639))
  (segment (start 106.222385 125.415042) (end 106.177021 125.436888) (width 0.109) (layer "In2.Cu") (net 639))
  (segment (start 105.053194 123.290496) (end 105.041989 123.241407) (width 0.109) (layer "In2.Cu") (net 639))
  (segment (start 106.077165 124.364818) (end 106.028076 124.376022) (width 0.109) (layer "In2.Cu") (net 639))
  (segment (start 106.619214 125.034369) (end 106.579847 125.065763) (width 0.109) (layer "In2.Cu") (net 639))
  (segment (start 104.949591 124.142248) (end 104.904227 124.164094) (width 0.109) (layer "In2.Cu") (net 639))
  (segment (start 105.242712 124.562873) (end 105.253917 124.513785) (width 0.109) (layer "In2.Cu") (net 639))
  (segment (start 105.879109 125.19927) (end 105.890314 125.150182) (width 0.109) (layer "In2.Cu") (net 639))
  (segment (start 106.314783 124.514201) (end 106.292937 124.468836) (width 0.109) (layer "In2.Cu") (net 639))
  (segment (start 104.05 122.853907) (end 104.05 120.25) (width 0.109) (layer "In2.Cu") (net 639))
  (segment (start 104.670759 123.792656) (end 104.98875 123.474666) (width 0.109) (layer "In2.Cu") (net 639))
  (segment (start 104.755282 123.103228) (end 104.709918 123.125074) (width 0.109) (layer "In2.Cu") (net 639))
  (segment (start 104.804371 123.092024) (end 104.755282 123.103228) (width 0.109) (layer "In2.Cu") (net 639))
  (segment (start 105.678386 123.877804) (end 105.65654 123.832439) (width 0.109) (layer "In2.Cu") (net 639))
  (segment (start 105.440768 123.728421) (end 105.391679 123.739625) (width 0.109) (layer "In2.Cu") (net 639))
  (segment (start 106.22197 124.397868) (end 106.176605 124.376022) (width 0.109) (layer "In2.Cu") (net 639))
  (segment (start 106.844806 125.617222) (end 106.833601 125.568133) (width 0.109) (layer "In2.Cu") (net 639))
  (segment (start 105.34673 124.778645) (end 105.307365 124.747253) (width 0.109) (layer "In2.Cu") (net 639))
  (segment (start 106.813107 125.012523) (end 106.764018 125.001319) (width 0.109) (layer "In2.Cu") (net 639))
  (segment (start 105.275763 124.707679) (end 105.253916 124.662313) (width 0.109) (layer "In2.Cu") (net 639))
  (segment (start 105.275763 124.468421) (end 105.307156 124.429053) (width 0.109) (layer "In2.Cu") (net 639))
  (segment (start 105.307157 124.747045) (end 105.275763 124.707679) (width 0.109) (layer "In2.Cu") (net 639))
  (segment (start 106.077582 125.448094) (end 106.028493 125.436889) (width 0.109) (layer "In2.Cu") (net 639))
  (segment (start 105.983127 125.415042) (end 105.943762 125.38365) (width 0.109) (layer "In2.Cu") (net 639))
  (segment (start 106.898046 125.701953) (end 106.866652 125.662586) (width 0.109) (layer "In2.Cu") (net 639))
  (segment (start 104.98875 123.474666) (end 105.020143 123.4353) (width 0.109) (layer "In2.Cu") (net 639))
  (segment (start 104.855138 124.175299) (end 104.804788 124.1753) (width 0.109) (layer "In2.Cu") (net 639))
  (segment (start 105.540624 124.800491) (end 105.491535 124.811696) (width 0.109) (layer "In2.Cu") (net 639))
  (segment (start 105.346315 123.761471) (end 105.306948 123.792865) (width 0.109) (layer "In2.Cu") (net 639))
  (segment (start 105.625147 123.793073) (end 105.624939 123.792865) (width 0.109) (layer "In2.Cu") (net 639))
  (segment (start 105.491119 123.728421) (end 105.440768 123.728421) (width 0.109) (layer "In2.Cu") (net 639))
  (segment (start 105.624939 123.792865) (end 105.585573 123.761471) (width 0.109) (layer "In2.Cu") (net 639))
  (segment (start 105.020143 123.4353) (end 105.041989 123.389936) (width 0.109) (layer "In2.Cu") (net 639))
  (segment (start 105.253916 124.662313) (end 105.242713 124.613225) (width 0.109) (layer "In2.Cu") (net 639))
  (segment (start 106.292937 124.708094) (end 106.314783 124.66273) (width 0.109) (layer "In2.Cu") (net 639))
  (segment (start 106.261544 124.74746) (end 106.292937 124.708094) (width 0.109) (layer "In2.Cu") (net 639))
  (segment (start 106.866652 125.662586) (end 106.844806 125.617222) (width 0.109) (layer "In2.Cu") (net 639))
  (segment (start 105.943553 125.06545) (end 106.261544 124.74746) (width 0.109) (layer "In2.Cu") (net 639))
  (segment (start 106.127932 125.448093) (end 106.077582 125.448094) (width 0.109) (layer "In2.Cu") (net 639))
  (segment (start 104.670968 124.110856) (end 104.67076 124.110648) (width 0.109) (layer "In2.Cu") (net 639))
  (segment (start 105.87911 125.249622) (end 105.879109 125.19927) (width 0.109) (layer "In2.Cu") (net 639))
  (segment (start 105.242713 124.613225) (end 105.242712 124.562873) (width 0.109) (layer "In2.Cu") (net 639))
  (segment (start 105.890314 125.150182) (end 105.91216 125.104818) (width 0.109) (layer "In2.Cu") (net 639))
  (segment (start 106.028076 124.376022) (end 105.982712 124.397868) (width 0.109) (layer "In2.Cu") (net 639))
  (segment (start 104.949176 123.125074) (end 104.903811 123.103228) (width 0.109) (layer "In2.Cu") (net 639))
  (segment (start 106.420747 125.224654) (end 106.261752 125.38365) (width 0.109) (layer "In2.Cu") (net 639))
  (segment (start 105.91216 125.104818) (end 105.943553 125.06545) (width 0.109) (layer "In2.Cu") (net 639))
  (segment (start 98.752964 117.8) (end 98.982023 117.570941) (width 0.182) (layer "F.Cu") (net 640))
  (segment (start 98.752964 117.8) (end 98.0489 117.8) (width 0.182) (layer "F.Cu") (net 640))
  (segment (start 130.525 135.825) (end 130.849323 135.500677) (width 0.182) (layer "F.Cu") (net 640))
  (segment (start 130.849323 135.500677) (end 130.949323 135.500677) (width 0.182) (layer "F.Cu") (net 640))
  (segment (start 98.0489 117.8) (end 98.0457 117.8032) (width 0.182) (layer "F.Cu") (net 640))
  (segment (start 130.525 136.375) (end 130.525 135.825) (width 0.182) (layer "F.Cu") (net 640))
  (via (at 130.949323 135.500677) (size 0.45) (drill 0.1) (layers "F.Cu" "B.Cu") (net 640))
  (via (at 98.982023 117.570941) (size 0.45) (drill 0.1) (layers "F.Cu" "B.Cu") (net 640))
  (segment (start 103.446396 124.726396) (end 115.54 136.82) (width 0.109) (layer "In2.Cu") (net 640))
  (segment (start 102.978327 124.806845) (end 103.027447 124.795633) (width 0.109) (layer "In2.Cu") (net 640))
  (segment (start 102.5 123.78) (end 102.81 124.09) (width 0.109) (layer "In2.Cu") (net 640))
  (segment (start 102.841413 124.129391) (end 102.863274 124.174786) (width 0.109) (layer "In2.Cu") (net 640))
  (segment (start 103.027447 124.795633) (end 103.072842 124.773772) (width 0.109) (layer "In2.Cu") (net 640))
  (segment (start 102.794036 124.424161) (end 102.762622 124.463553) (width 0.109) (layer "In2.Cu") (net 640))
  (segment (start 102.72955 124.608452) (end 102.740761 124.657573) (width 0.109) (layer "In2.Cu") (net 640))
  (segment (start 102.740761 124.508947) (end 102.72955 124.558068) (width 0.109) (layer "In2.Cu") (net 640))
  (segment (start 99.290989 118.990989) (end 100.940989 118.990989) (width 0.109) (layer "In2.Cu") (net 640))
  (segment (start 102.5 120.55) (end 102.5 123.78) (width 0.109) (layer "In2.Cu") (net 640))
  (segment (start 103.361609 124.67312) (end 103.407003 124.694981) (width 0.109) (layer "In2.Cu") (net 640))
  (segment (start 102.794036 124.742359) (end 102.833427 124.773772) (width 0.109) (layer "In2.Cu") (net 640))
  (segment (start 103.407003 124.694981) (end 103.446396 124.726396) (width 0.109) (layer "In2.Cu") (net 640))
  (segment (start 102.833427 124.773772) (end 102.878822 124.795633) (width 0.109) (layer "In2.Cu") (net 640))
  (segment (start 103.212983 124.67312) (end 103.262104 124.661909) (width 0.109) (layer "In2.Cu") (net 640))
  (segment (start 102.81 124.408198) (end 102.794036 124.424161) (width 0.109) (layer "In2.Cu") (net 640))
  (segment (start 103.312488 124.661909) (end 103.361609 124.67312) (width 0.109) (layer "In2.Cu") (net 640))
  (segment (start 103.128197 124.726395) (end 103.167589 124.694981) (width 0.109) (layer "In2.Cu") (net 640))
  (segment (start 98.982023 117.570941) (end 98.982023 118.682023) (width 0.109) (layer "In2.Cu") (net 640))
  (segment (start 103.112234 124.742359) (end 103.128197 124.726395) (width 0.109) (layer "In2.Cu") (net 640))
  (segment (start 102.874486 124.223907) (end 102.874486 124.274291) (width 0.109) (layer "In2.Cu") (net 640))
  (segment (start 129.63 136.82) (end 130.949323 135.500677) (width 0.109) (layer "In2.Cu") (net 640))
  (segment (start 102.72955 124.558068) (end 102.72955 124.608452) (width 0.109) (layer "In2.Cu") (net 640))
  (segment (start 102.841413 124.368806) (end 102.81 124.408198) (width 0.109) (layer "In2.Cu") (net 640))
  (segment (start 102.740761 124.657573) (end 102.762622 124.702967) (width 0.109) (layer "In2.Cu") (net 640))
  (segment (start 102.927943 124.806845) (end 102.978327 124.806845) (width 0.109) (layer "In2.Cu") (net 640))
  (segment (start 102.863274 124.174786) (end 102.874486 124.223907) (width 0.109) (layer "In2.Cu") (net 640))
  (segment (start 102.81 124.09) (end 102.841413 124.129391) (width 0.109) (layer "In2.Cu") (net 640))
  (segment (start 115.54 136.82) (end 129.63 136.82) (width 0.109) (layer "In2.Cu") (net 640))
  (segment (start 102.863274 124.323411) (end 102.841413 124.368806) (width 0.109) (layer "In2.Cu") (net 640))
  (segment (start 102.762622 124.463553) (end 102.740761 124.508947) (width 0.109) (layer "In2.Cu") (net 640))
  (segment (start 98.982023 118.682023) (end 99.290989 118.990989) (width 0.109) (layer "In2.Cu") (net 640))
  (segment (start 102.878822 124.795633) (end 102.927943 124.806845) (width 0.109) (layer "In2.Cu") (net 640))
  (segment (start 103.167589 124.694981) (end 103.212983 124.67312) (width 0.109) (layer "In2.Cu") (net 640))
  (segment (start 103.072842 124.773772) (end 103.112234 124.742359) (width 0.109) (layer "In2.Cu") (net 640))
  (segment (start 102.874486 124.274291) (end 102.863274 124.323411) (width 0.109) (layer "In2.Cu") (net 640))
  (segment (start 102.762622 124.702967) (end 102.794036 124.742359) (width 0.109) (layer "In2.Cu") (net 640))
  (segment (start 100.940989 118.990989) (end 102.5 120.55) (width 0.109) (layer "In2.Cu") (net 640))
  (segment (start 103.262104 124.661909) (end 103.312488 124.661909) (width 0.109) (layer "In2.Cu") (net 640))
  (segment (start 98.4564 117.3936) (end 98.925001 116.924999) (width 0.182) (layer "F.Cu") (net 641))
  (segment (start 98.925001 116.924999) (end 99.700001 116.924999) (width 0.182) (layer "F.Cu") (net 641))
  (segment (start 98.4564 117.3936) (end 98.0553 117.3936) (width 0.182) (layer "F.Cu") (net 641))
  (segment (start 130.125 136.35) (end 130.125 135.55) (width 0.182) (layer "F.Cu") (net 641))
  (segment (start 130.125 135.55) (end 130.175 135.5) (width 0.182) (layer "F.Cu") (net 641))
  (segment (start 99.700001 116.924999) (end 99.925 116.7) (width 0.182) (layer "F.Cu") (net 641))
  (segment (start 98.0553 117.3936) (end 98.0457 117.4032) (width 0.182) (layer "F.Cu") (net 641))
  (via (at 130.175 135.5) (size 0.45) (drill 0.1) (layers "F.Cu" "B.Cu") (net 641))
  (via (at 99.925 116.7) (size 0.45) (drill 0.1) (layers "F.Cu" "B.Cu") (net 641))
  (segment (start 103.664148 123.898298) (end 103.683232 123.883079) (width 0.109) (layer "In2.Cu") (net 641))
  (segment (start 103.51 123.59) (end 103.525218 123.609083) (width 0.109) (layer "In2.Cu") (net 641))
  (segment (start 115.97 136.05) (end 124.55 136.05) (width 0.109) (layer "In2.Cu") (net 641))
  (segment (start 103.622739 123.924442) (end 103.64473 123.913852) (width 0.109) (layer "In2.Cu") (net 641))
  (segment (start 103.509664 123.898634) (end 103.528747 123.913852) (width 0.109) (layer "In2.Cu") (net 641))
  (segment (start 103.528747 123.913852) (end 103.550738 123.924442) (width 0.109) (layer "In2.Cu") (net 641))
  (segment (start 103.494445 123.763568) (end 103.483855 123.785559) (width 0.109) (layer "In2.Cu") (net 641))
  (segment (start 129.175 136.5) (end 130.175 135.5) (width 0.109) (layer "In2.Cu") (net 641))
  (segment (start 103.535808 123.703075) (end 103.525218 123.725066) (width 0.109) (layer "In2.Cu") (net 641))
  (segment (start 103.535808 123.631074) (end 103.541239 123.65487) (width 0.109) (layer "In2.Cu") (net 641))
  (segment (start 103.574534 123.929873) (end 103.598942 123.929873) (width 0.109) (layer "In2.Cu") (net 641))
  (segment (start 99.361533 118.461533) (end 99.658086 118.758086) (width 0.109) (layer "In2.Cu") (net 641))
  (segment (start 103.683232 123.883079) (end 103.705223 123.872489) (width 0.109) (layer "In2.Cu") (net 641))
  (segment (start 103.705223 123.872489) (end 103.729019 123.867058) (width 0.109) (layer "In2.Cu") (net 641))
  (segment (start 103.598942 123.929873) (end 103.622739 123.924442) (width 0.109) (layer "In2.Cu") (net 641))
  (segment (start 103.799215 123.883079) (end 103.818298 123.898298) (width 0.109) (layer "In2.Cu") (net 641))
  (segment (start 124.55 136.05) (end 125 136.5) (width 0.109) (layer "In2.Cu") (net 641))
  (segment (start 103.550738 123.924442) (end 103.574534 123.929873) (width 0.109) (layer "In2.Cu") (net 641))
  (segment (start 99.925 116.7) (end 99.361533 117.263467) (width 0.109) (layer "In2.Cu") (net 641))
  (segment (start 99.658086 118.758086) (end 101.658086 118.758086) (width 0.109) (layer "In2.Cu") (net 641))
  (segment (start 103.275 123.355) (end 103.51 123.59) (width 0.109) (layer "In2.Cu") (net 641))
  (segment (start 103.483855 123.785559) (end 103.478424 123.809355) (width 0.109) (layer "In2.Cu") (net 641))
  (segment (start 103.525218 123.725066) (end 103.51 123.744149) (width 0.109) (layer "In2.Cu") (net 641))
  (segment (start 103.275 120.375) (end 103.275 123.355) (width 0.109) (layer "In2.Cu") (net 641))
  (segment (start 101.658086 118.758086) (end 103.275 120.375) (width 0.109) (layer "In2.Cu") (net 641))
  (segment (start 99.361533 117.263467) (end 99.361533 118.461533) (width 0.109) (layer "In2.Cu") (net 641))
  (segment (start 103.663813 123.898634) (end 103.664148 123.898298) (width 0.109) (layer "In2.Cu") (net 641))
  (segment (start 103.818298 123.898298) (end 115.97 136.05) (width 0.109) (layer "In2.Cu") (net 641))
  (segment (start 103.478424 123.809355) (end 103.478424 123.833763) (width 0.109) (layer "In2.Cu") (net 641))
  (segment (start 103.478424 123.833763) (end 103.483855 123.857559) (width 0.109) (layer "In2.Cu") (net 641))
  (segment (start 103.509664 123.744484) (end 103.494445 123.763568) (width 0.109) (layer "In2.Cu") (net 641))
  (segment (start 103.51 123.744149) (end 103.509664 123.744484) (width 0.109) (layer "In2.Cu") (net 641))
  (segment (start 125 136.5) (end 129.175 136.5) (width 0.109) (layer "In2.Cu") (net 641))
  (segment (start 103.483855 123.857559) (end 103.494445 123.879551) (width 0.109) (layer "In2.Cu") (net 641))
  (segment (start 103.729019 123.867058) (end 103.753427 123.867058) (width 0.109) (layer "In2.Cu") (net 641))
  (segment (start 103.494445 123.879551) (end 103.509664 123.898634) (width 0.109) (layer "In2.Cu") (net 641))
  (segment (start 103.541239 123.679278) (end 103.535808 123.703075) (width 0.109) (layer "In2.Cu") (net 641))
  (segment (start 103.753427 123.867058) (end 103.777223 123.872489) (width 0.109) (layer "In2.Cu") (net 641))
  (segment (start 103.541239 123.65487) (end 103.541239 123.679278) (width 0.109) (layer "In2.Cu") (net 641))
  (segment (start 103.64473 123.913852) (end 103.663813 123.898634) (width 0.109) (layer "In2.Cu") (net 641))
  (segment (start 103.525218 123.609083) (end 103.535808 123.631074) (width 0.109) (layer "In2.Cu") (net 641))
  (segment (start 103.777223 123.872489) (end 103.799215 123.883079) (width 0.109) (layer "In2.Cu") (net 641))
  (segment (start 116.2946 121.550063) (end 117.170063 121.550063) (width 0.2) (layer "F.Cu") (net 642))
  (segment (start 114.811939 86.838061) (end 115.129553 86.520447) (width 0.182) (layer "F.Cu") (net 643))
  (segment (start 116.315729 86.520447) (end 116.330141 86.534859) (width 0.182) (layer "F.Cu") (net 643))
  (segment (start 114.811939 86.87486) (end 114.811939 86.838061) (width 0.182) (layer "F.Cu") (net 643))
  (segment (start 115.129553 86.520447) (end 116.315729 86.520447) (width 0.182) (layer "F.Cu") (net 643))
  (segment (start 115.456942 86.98186) (end 115.599939 86.981862) (width 0.182) (layer "F.Cu") (net 644))
  (segment (start 115.599939 86.981862) (end 115.646941 86.93486) (width 0.182) (layer "F.Cu") (net 644))
  (segment (start 115.646941 86.93486) (end 116.330142 86.93486) (width 0.182) (layer "F.Cu") (net 644))
  (via (at 115.440912 86.936448) (size 0.45) (drill 0.1) (layers "F.Cu" "B.Cu") (net 644))
  (segment (start 115.904464 87.4) (end 115.440912 86.936448) (width 0.4) (layer "B.Cu") (net 644))
  (segment (start 116.1 87.4) (end 115.904464 87.4) (width 0.4) (layer "B.Cu") (net 644))
  (segment (start 114.811942 87.82359) (end 114.811942 87.874861) (width 0.182) (layer "F.Cu") (net 645))
  (segment (start 115.197542 87.352458) (end 115.624943 87.352458) (width 0.182) (layer "F.Cu") (net 645))
  (segment (start 114.811942 87.738058) (end 115.197542 87.352458) (width 0.182) (layer "F.Cu") (net 645))
  (segment (start 115.642543 87.334859) (end 115.624943 87.352458) (width 0.182) (layer "F.Cu") (net 645))
  (segment (start 114.811942 87.874861) (end 114.811942 87.738058) (width 0.182) (layer "F.Cu") (net 645))
  (segment (start 116.330142 87.334859) (end 115.642543 87.334859) (width 0.182) (layer "F.Cu") (net 645))
  (segment (start 115.483644 87.73486) (end 115.454606 87.763898) (width 0.182) (layer "F.Cu") (net 646))
  (segment (start 115.510756 87.73486) (end 115.444606 87.80101) (width 0.182) (layer "F.Cu") (net 646))
  (segment (start 116.330142 87.73486) (end 115.510756 87.73486) (width 0.182) (layer "F.Cu") (net 646))
  (via (at 115.444606 87.80101) (size 0.45) (drill 0.1) (layers "F.Cu" "B.Cu") (net 646))
  (segment (start 116.071942 88.47486) (end 115.916943 88.31986) (width 0.4) (layer "B.Cu") (net 646))
  (segment (start 115.444606 88.052523) (end 115.444606 87.80101) (width 0.4) (layer "B.Cu") (net 646))
  (segment (start 115.681944 88.289861) (end 115.444606 88.052523) (width 0.4) (layer "B.Cu") (net 646))
  (segment (start 115.916943 88.31986) (end 115.916942 88.289861) (width 0.4) (layer "B.Cu") (net 646))
  (segment (start 115.916942 88.289861) (end 115.691944 88.289861) (width 0.4) (layer "B.Cu") (net 646))
  (segment (start 114.796942 88.85486) (end 114.796942 88.874862) (width 0.182) (layer "F.Cu") (net 647))
  (segment (start 115.74514 88.13486) (end 115.455 88.425) (width 0.182) (layer "F.Cu") (net 647))
  (segment (start 115.106802 88.575) (end 114.826942 88.85486) (width 0.182) (layer "F.Cu") (net 647))
  (segment (start 115.455 88.425) (end 115.256802 88.425) (width 0.182) (layer "F.Cu") (net 647))
  (segment (start 115.256802 88.425) (end 115.106802 88.575) (width 0.182) (layer "F.Cu") (net 647))
  (segment (start 116.330141 88.13486) (end 115.74514 88.13486) (width 0.182) (layer "F.Cu") (net 647))
  (segment (start 116.330141 88.534859) (end 115.835141 88.534859) (width 0.182) (layer "F.Cu") (net 648))
  (segment (start 115.835139 88.534861) (end 115.815139 88.534861) (width 0.182) (layer "F.Cu") (net 648))
  (segment (start 115.815139 88.534861) (end 115.485 88.865) (width 0.182) (layer "F.Cu") (net 648))
  (segment (start 115.835141 88.534859) (end 115.835139 88.534861) (width 0.182) (layer "F.Cu") (net 648))
  (via (at 115.485 88.865) (size 0.45) (drill 0.1) (layers "F.Cu" "B.Cu") (net 648))
  (segment (start 115.87486 89.37486) (end 115.485 88.985) (width 0.4) (layer "B.Cu") (net 648))
  (segment (start 116.071941 89.37486) (end 115.87486 89.37486) (width 0.4) (layer "B.Cu") (net 648))
  (segment (start 115.485 88.985) (end 115.485 88.865) (width 0.4) (layer "B.Cu") (net 648))
  (segment (start 115.514345 84.534861) (end 115.501025 84.548181) (width 0.182) (layer "F.Cu") (net 649))
  (segment (start 116.330142 84.534861) (end 115.514345 84.534861) (width 0.182) (layer "F.Cu") (net 649))
  (via (at 115.501025 84.548181) (size 0.45) (drill 0.1) (layers "F.Cu" "B.Cu") (net 649))
  (segment (start 115.851819 84.548181) (end 115.501025 84.548181) (width 0.4) (layer "B.Cu") (net 649))
  (segment (start 116 84.4) (end 115.851819 84.548181) (width 0.4) (layer "B.Cu") (net 649))
  (segment (start 115.50694 84.554096) (end 115.501025 84.548181) (width 0.4) (layer "B.Cu") (net 649))
  (segment (start 116.121942 84.4) (end 116 84.4) (width 0.4) (layer "B.Cu") (net 649))
  (segment (start 114.95262 84.964182) (end 114.891942 85.02486) (width 0.182) (layer "F.Cu") (net 650))
  (segment (start 116.30082 84.964182) (end 114.95262 84.964182) (width 0.182) (layer "F.Cu") (net 650))
  (segment (start 116.330142 84.93486) (end 116.30082 84.964182) (width 0.182) (layer "F.Cu") (net 650))
  (segment (start 116.330141 85.33486) (end 115.596942 85.334862) (width 0.182) (layer "F.Cu") (net 651))
  (segment (start 115.596942 85.334862) (end 115.506942 85.424861) (width 0.182) (layer "F.Cu") (net 651))
  (via (at 115.506942 85.424861) (size 0.45) (drill 0.1) (layers "F.Cu" "B.Cu") (net 651))
  (segment (start 116.121943 85.378057) (end 116.075139 85.424861) (width 0.4) (layer "B.Cu") (net 651))
  (segment (start 116.121943 85.4) (end 116.121943 85.378057) (width 0.4) (layer "B.Cu") (net 651))
  (segment (start 116.075139 85.424861) (end 115.506942 85.424861) (width 0.4) (layer "B.Cu") (net 651))
  (segment (start 127.907742 81.334862) (end 128.478737 81.334862) (width 0.182) (layer "F.Cu") (net 652))
  (segment (start 128.478737 81.334862) (end 128.818885 81.67501) (width 0.182) (layer "F.Cu") (net 652))
  (via (at 128.818885 81.67501) (size 0.45) (drill 0.1) (layers "F.Cu" "B.Cu") (net 652))
  (segment (start 128.62486 81.32486) (end 128.818885 81.518885) (width 0.4) (layer "B.Cu") (net 652))
  (segment (start 128.818885 81.518885) (end 128.818885 81.67501) (width 0.4) (layer "B.Cu") (net 652))
  (segment (start 128.151942 81.32486) (end 128.62486 81.32486) (width 0.4) (layer "B.Cu") (net 652))
  (segment (start 128.684861 80.934861) (end 129.274861 81.524861) (width 0.182) (layer "F.Cu") (net 653))
  (segment (start 129.465 81.8) (end 129.465 81.715) (width 0.182) (layer "F.Cu") (net 653))
  (segment (start 127.907742 80.934861) (end 128.684861 80.934861) (width 0.182) (layer "F.Cu") (net 653))
  (segment (start 129.465 81.715) (end 129.274861 81.524861) (width 0.182) (layer "F.Cu") (net 653))
  (segment (start 127.907742 80.534861) (end 128.784861 80.534861) (width 0.182) (layer "F.Cu") (net 654))
  (segment (start 128.784861 80.534861) (end 129.05 80.8) (width 0.182) (layer "F.Cu") (net 654))
  (segment (start 129.05 80.8) (end 129.465 80.8) (width 0.182) (layer "F.Cu") (net 654))
  (segment (start 126.91894 90.323661) (end 126.91894 90.79394) (width 0.182) (layer "F.Cu") (net 655))
  (segment (start 127.025 90.9) (end 127.025 91.16) (width 0.182) (layer "F.Cu") (net 655))
  (segment (start 127.025 91.16) (end 127.345 91.48) (width 0.182) (layer "F.Cu") (net 655))
  (segment (start 126.91894 90.79394) (end 127.025 90.9) (width 0.182) (layer "F.Cu") (net 655))
  (segment (start 119.717017 77.84447) (end 119.718941 77.846394) (width 0.182) (layer "F.Cu") (net 656))
  (segment (start 119.718941 77.846394) (end 119.718941 78.74606) (width 0.182) (layer "F.Cu") (net 656))
  (via (at 119.717017 77.84447) (size 0.45) (drill 0.1) (layers "F.Cu" "B.Cu") (net 656))
  (segment (start 119.3 78.3) (end 119.3 78.446804) (width 0.4) (layer "B.Cu") (net 656))
  (segment (start 119.717017 77.84447) (end 119.717017 77.882983) (width 0.4) (layer "B.Cu") (net 656))
  (segment (start 119.717017 77.882983) (end 119.3 78.3) (width 0.4) (layer "B.Cu") (net 656))
  (segment (start 119.318943 78.079367) (end 119.269788 78.030212) (width 0.182) (layer "F.Cu") (net 657))
  (segment (start 119.269788 77.272708) (end 119.269788 78.030212) (width 0.182) (layer "F.Cu") (net 657))
  (segment (start 119.318943 78.746061) (end 119.318943 78.079367) (width 0.182) (layer "F.Cu") (net 657))
  (segment (start 118.853277 77.832285) (end 118.853277 78.149083) (width 0.182) (layer "F.Cu") (net 658))
  (segment (start 118.918943 78.214749) (end 118.918943 78.746061) (width 0.182) (layer "F.Cu") (net 658))
  (segment (start 118.853277 78.149083) (end 118.918943 78.214749) (width 0.182) (layer "F.Cu") (net 658))
  (via (at 118.853277 77.832285) (size 0.45) (drill 0.1) (layers "F.Cu" "B.Cu") (net 658))
  (segment (start 118.841116 77.832285) (end 118.406942 78.266459) (width 0.4) (layer "B.Cu") (net 658))
  (segment (start 118.853277 77.832285) (end 118.841116 77.832285) (width 0.4) (layer "B.Cu") (net 658))
  (segment (start 118.518942 78.118942) (end 118.437776 78.037776) (width 0.182) (layer "F.Cu") (net 659))
  (segment (start 118.437776 77.340696) (end 118.437776 78.037776) (width 0.182) (layer "F.Cu") (net 659))
  (segment (start 118.518942 78.746061) (end 118.518942 78.118942) (width 0.182) (layer "F.Cu") (net 659))
  (segment (start 118.306942 77.209862) (end 118.437776 77.340696) (width 0.182) (layer "F.Cu") (net 659))
  (segment (start 118.011653 77.860521) (end 118.118942 77.96781) (width 0.182) (layer "F.Cu") (net 660))
  (segment (start 118.118942 77.96781) (end 118.118942 78.746061) (width 0.182) (layer "F.Cu") (net 660))
  (via (at 118.011653 77.860521) (size 0.45) (drill 0.1) (layers "F.Cu" "B.Cu") (net 660))
  (segment (start 117.639479 77.860521) (end 117.2 78.3) (width 0.4) (layer "B.Cu") (net 660))
  (segment (start 118.011653 77.860521) (end 117.639479 77.860521) (width 0.4) (layer "B.Cu") (net 660))
  (segment (start 117.2 78.3) (end 117.2 78.44) (width 0.4) (layer "B.Cu") (net 660))
  (segment (start 117.718943 78.158943) (end 117.718943 78.74606) (width 0.182) (layer "F.Cu") (net 661))
  (segment (start 117.41 77.85) (end 117.718943 78.158943) (width 0.182) (layer "F.Cu") (net 661))
  (segment (start 117.41 77.398058) (end 117.41 77.85) (width 0.182) (layer "F.Cu") (net 661))
  (segment (start 117.286942 77.275) (end 117.41 77.398058) (width 0.182) (layer "F.Cu") (net 661))
  (segment (start 117.318944 78.318944) (end 116.678574 77.678574) (width 0.182) (layer "F.Cu") (net 662))
  (segment (start 117.318944 78.746061) (end 117.318944 78.318944) (width 0.182) (layer "F.Cu") (net 662))
  (segment (start 116.678574 77.678574) (end 116.588576 77.678574) (width 0.182) (layer "F.Cu") (net 662))
  (via (at 116.588576 77.678574) (size 0.45) (drill 0.1) (layers "F.Cu" "B.Cu") (net 662))
  (segment (start 116.588576 77.678574) (end 116.588576 78.111424) (width 0.4) (layer "B.Cu") (net 662))
  (segment (start 116.26 78.44) (end 116.2 78.44) (width 0.4) (layer "B.Cu") (net 662))
  (segment (start 116.588576 78.111424) (end 116.26 78.44) (width 0.4) (layer "B.Cu") (net 662))
  (segment (start 128.765122 88.93486) (end 128.765131 88.934869) (width 0.182) (layer "F.Cu") (net 663))
  (segment (start 127.907742 88.93486) (end 128.765122 88.93486) (width 0.182) (layer "F.Cu") (net 663))
  (via (at 128.765131 88.934869) (size 0.5) (drill 0.15) (layers "F.Cu" "B.Cu") (net 663))
  (segment (start 128.151943 88.601943) (end 128.151943 88.55) (width 0.4) (layer "B.Cu") (net 663))
  (segment (start 128.765131 88.934869) (end 128.75 88.95) (width 0.4) (layer "B.Cu") (net 663))
  (segment (start 128.75 88.95) (end 128.5 88.95) (width 0.4) (layer "B.Cu") (net 663))
  (segment (start 128.755122 88.92486) (end 128.765131 88.934869) (width 0.4) (layer "B.Cu") (net 663))
  (segment (start 128.5 88.95) (end 128.151943 88.601943) (width 0.4) (layer "B.Cu") (net 663))
  (segment (start 129.13208 88.435) (end 129.421942 88.724862) (width 0.182) (layer "F.Cu") (net 664))
  (segment (start 127.907742 88.534861) (end 128.395139 88.534861) (width 0.182) (layer "F.Cu") (net 664))
  (segment (start 128.495 88.435) (end 129.13208 88.435) (width 0.182) (layer "F.Cu") (net 664))
  (segment (start 128.395139 88.534861) (end 128.495 88.435) (width 0.182) (layer "F.Cu") (net 664))
  (segment (start 128.743844 84.704354) (end 128.513338 84.93486) (width 0.182) (layer "F.Cu") (net 665))
  (segment (start 128.513338 84.93486) (end 127.907742 84.93486) (width 0.182) (layer "F.Cu") (net 665))
  (segment (start 128.912622 84.704354) (end 128.743844 84.704354) (width 0.182) (layer "F.Cu") (net 665))
  (via (at 128.912622 84.704354) (size 0.45) (drill 0.1) (layers "F.Cu" "B.Cu") (net 665))
  (segment (start 128.805646 84.704354) (end 128.63 84.88) (width 0.4) (layer "B.Cu") (net 665))
  (segment (start 128.912622 84.704354) (end 128.805646 84.704354) (width 0.4) (layer "B.Cu") (net 665))
  (segment (start 128.63 84.88) (end 128.135 84.88) (width 0.4) (layer "B.Cu") (net 665))
  (segment (start 114.866001 91.258999) (end 114.866001 89.956001) (width 0.182) (layer "F.Cu") (net 666))
  (segment (start 115.665141 89.334859) (end 116.330142 89.334859) (width 0.182) (layer "F.Cu") (net 666))
  (segment (start 113.429855 91.514815) (end 112.724815 91.514815) (width 0.182) (layer "F.Cu") (net 666))
  (segment (start 114.785 89.875) (end 115.125 89.875) (width 0.182) (layer "F.Cu") (net 666))
  (segment (start 114.866001 89.956001) (end 114.785 89.875) (width 0.182) (layer "F.Cu") (net 666))
  (segment (start 112.724815 91.514815) (end 112.43 91.22) (width 0.182) (layer "F.Cu") (net 666))
  (segment (start 113.429855 91.514815) (end 114.610185 91.514815) (width 0.182) (layer "F.Cu") (net 666))
  (segment (start 115.125 89.875) (end 115.665141 89.334859) (width 0.182) (layer "F.Cu") (net 666))
  (segment (start 114.610185 91.514815) (end 114.866001 91.258999) (width 0.182) (layer "F.Cu") (net 666))
  (segment (start 112.425165 92.240165) (end 112.425 92.24) (width 0.182) (layer "F.Cu") (net 667))
  (segment (start 114.154074 92.240165) (end 112.425165 92.240165) (width 0.182) (layer "F.Cu") (net 667))
  (segment (start 115.359835 92.240165) (end 115.535 92.065) (width 0.182) (layer "F.Cu") (net 667))
  (segment (start 115.535 92.065) (end 116.45 92.065) (width 0.182) (layer "F.Cu") (net 667))
  (segment (start 117.318941 90.32366) (end 117.318941 91.196059) (width 0.182) (layer "F.Cu") (net 667))
  (segment (start 114.154074 92.240165) (end 115.359835 92.240165) (width 0.182) (layer "F.Cu") (net 667))
  (segment (start 116.45 92.065) (end 117.318941 91.196059) (width 0.182) (layer "F.Cu") (net 667))
  (segment (start 123.1151 97.459) (end 124.109 97.459) (width 0.182) (layer "F.Cu") (net 668))
  (segment (start 124.109 97.459) (end 124.164 97.404) (width 0.182) (layer "F.Cu") (net 668))
  (segment (start 121.911 95.889) (end 121.911 96.7629) (width 0.182) (layer "F.Cu") (net 669))
  (segment (start 122.485 95.315) (end 121.911 95.889) (width 0.182) (layer "F.Cu") (net 669))
  (segment (start 122.485 95.3) (end 122.485 95.315) (width 0.182) (layer "F.Cu") (net 669))
  (segment (start 153.242637 87.964037) (end 153.676522 87.530152) (width 0.182) (layer "F.Cu") (net 670))
  (segment (start 152.245912 87.964037) (end 153.242637 87.964037) (width 0.182) (layer "F.Cu") (net 670))
  (segment (start 145.455 84.435) (end 145.24 84.435) (width 0.182) (layer "F.Cu") (net 671))
  (segment (start 146.095911 85.075911) (end 145.455 84.435) (width 0.182) (layer "F.Cu") (net 671))
  (segment (start 146.095911 85.314034) (end 146.095911 85.075911) (width 0.182) (layer "F.Cu") (net 671))
  (segment (start 142.665 91.21) (end 142.910964 90.964036) (width 0.182) (layer "F.Cu") (net 672))
  (segment (start 142.26 91.21) (end 142.665 91.21) (width 0.182) (layer "F.Cu") (net 672))
  (segment (start 142.910964 90.964036) (end 145.44591 90.964036) (width 0.182) (layer "F.Cu") (net 672))
  (segment (start 142.326877 89.21) (end 143.91 89.21) (width 0.182) (layer "F.Cu") (net 673))
  (segment (start 143.91 89.21) (end 144.162 89.462) (width 0.182) (layer "F.Cu") (net 673))
  (segment (start 144.162 89.462) (end 145.371 89.462) (width 0.182) (layer "F.Cu") (net 673))
  (segment (start 142.280911 89.164034) (end 142.326877 89.21) (width 0.182) (layer "F.Cu") (net 673))
  (segment (start 144.064037 90.464037) (end 145.44591 90.464037) (width 0.182) (layer "F.Cu") (net 674))
  (segment (start 143.82 90.22) (end 144.064037 90.464037) (width 0.182) (layer "F.Cu") (net 674))
  (segment (start 142.436875 90.22) (end 143.82 90.22) (width 0.182) (layer "F.Cu") (net 674))
  (segment (start 142.280911 90.064036) (end 142.436875 90.22) (width 0.182) (layer "F.Cu") (net 674))
  (segment (start 109.903981 140.8) (end 110.383889 141.279908) (width 0.182) (layer "F.Cu") (net 675))
  (segment (start 110.383889 141.279908) (end 110.383889 141.349735) (width 0.182) (layer "F.Cu") (net 675))
  (segment (start 111.14 141.1) (end 110.75 141.1) (width 0.182) (layer "F.Cu") (net 675))
  (segment (start 108.995 140.8) (end 109.903981 140.8) (width 0.182) (layer "F.Cu") (net 675))
  (segment (start 110.75 141.1) (end 110.500265 141.349735) (width 0.182) (layer "F.Cu") (net 675))
  (segment (start 110.500265 141.349735) (end 110.383889 141.349735) (width 0.182) (layer "F.Cu") (net 675))
  (via (at 110.383889 141.349735) (size 0.45) (drill 0.1) (layers "F.Cu" "B.Cu") (net 675))
  (segment (start 110.4 141.365846) (end 110.383889 141.349735) (width 0.182) (layer "B.Cu") (net 675))
  (segment (start 110.4 141.915) (end 110.4 141.365846) (width 0.182) (layer "B.Cu") (net 675))
  (segment (start 112.6 142.56) (end 112.6 143.3) (width 0.182) (layer "F.Cu") (net 676))
  (segment (start 112.775 143.475) (end 113.1 143.475) (width 0.182) (layer "F.Cu") (net 676))
  (segment (start 112.6 143.3) (end 112.775 143.475) (width 0.182) (layer "F.Cu") (net 676))
  (segment (start 109.55 144.575) (end 109.835 144.29) (width 0.182) (layer "F.Cu") (net 676))
  (segment (start 108.82 144.575) (end 109.55 144.575) (width 0.182) (layer "F.Cu") (net 676))
  (via (at 113.1 143.475) (size 0.45) (drill 0.1) (layers "F.Cu" "B.Cu") (net 676))
  (via (at 109.835 144.29) (size 0.45) (drill 0.1) (layers "F.Cu" "B.Cu") (net 676))
  (segment (start 113.1 143.475) (end 110.65 143.475) (width 0.109) (layer "In6.Cu") (net 676))
  (segment (start 110.65 143.475) (end 109.835 144.29) (width 0.109) (layer "In6.Cu") (net 676))
  (segment (start 110.465 144.2) (end 109.925 144.2) (width 0.109) (layer "B.Cu") (net 676))
  (segment (start 109.925 144.2) (end 109.835 144.29) (width 0.109) (layer "B.Cu") (net 676))
  (segment (start 110.084595 140.4) (end 110.343192 140.141403) (width 0.182) (layer "F.Cu") (net 677))
  (segment (start 108.995 140.4) (end 110.084595 140.4) (width 0.182) (layer "F.Cu") (net 677))
  (segment (start 110.343192 140.141403) (end 110.374865 140.141403) (width 0.182) (layer "F.Cu") (net 677))
  (segment (start 111.14 140.1) (end 110.416268 140.1) (width 0.182) (layer "F.Cu") (net 677))
  (segment (start 110.416268 140.1) (end 110.374865 140.141403) (width 0.182) (layer "F.Cu") (net 677))
  (via (at 110.374865 140.141403) (size 0.45) (drill 0.1) (layers "F.Cu" "B.Cu") (net 677))
  (segment (start 109.65 140.15) (end 110.366268 140.15) (width 0.182) (layer "B.Cu") (net 677))
  (segment (start 110.366268 140.15) (end 110.374865 140.141403) (width 0.182) (layer "B.Cu") (net 677))
  (segment (start 114.272264 140.6) (end 114.326087 140.653823) (width 0.182) (layer "F.Cu") (net 678))
  (segment (start 113.56 140.6) (end 114.272264 140.6) (width 0.182) (layer "F.Cu") (net 678))
  (segment (start 109.444968 139.550032) (end 110.389057 139.550032) (width 0.182) (layer "F.Cu") (net 678))
  (segment (start 108.995 140) (end 109.444968 139.550032) (width 0.182) (layer "F.Cu") (net 678))
  (via (at 114.326087 140.653823) (size 0.45) (drill 0.1) (layers "F.Cu" "B.Cu") (net 678))
  (via (at 110.389057 139.550032) (size 0.45) (drill 0.1) (layers "F.Cu" "B.Cu") (net 678))
  (segment (start 114.854501 140.125409) (end 114.326087 140.653823) (width 0.109) (layer "In6.Cu") (net 678))
  (segment (start 110.389057 139.550032) (end 111.439089 138.5) (width 0.109) (layer "In6.Cu") (net 678))
  (segment (start 111.439089 138.5) (end 113.386662 138.5) (width 0.109) (layer "In6.Cu") (net 678))
  (segment (start 114.854501 139.967839) (end 114.854501 140.125409) (width 0.109) (layer "In6.Cu") (net 678))
  (segment (start 113.386662 138.5) (end 114.854501 139.967839) (width 0.109) (layer "In6.Cu") (net 678))
  (segment (start 114.646177 140.653823) (end 115.2 140.1) (width 0.4) (layer "B.Cu") (net 678))
  (segment (start 114.326087 140.653823) (end 114.646177 140.653823) (width 0.4) (layer "B.Cu") (net 678))
  (segment (start 108.35 139.755) (end 108.35 139.2) (width 0.182) (layer "F.Cu") (net 679))
  (segment (start 108.35 139.2) (end 108.55 139) (width 0.182) (layer "F.Cu") (net 679))
  (segment (start 108.55 139) (end 108.650002 139) (width 0.182) (layer "F.Cu") (net 679))
  (segment (start 114.156497 141.6) (end 114.399186 141.842689) (width 0.182) (layer "F.Cu") (net 679))
  (segment (start 113.56 141.6) (end 114.156497 141.6) (width 0.182) (layer "F.Cu") (net 679))
  (via (at 108.650002 139) (size 0.45) (drill 0.1) (layers "F.Cu" "B.Cu") (net 679))
  (via (at 114.399186 141.842689) (size 0.45) (drill 0.1) (layers "F.Cu" "B.Cu") (net 679))
  (segment (start 109.079503 138.570499) (end 110.507161 138.570499) (width 0.109) (layer "In6.Cu") (net 679))
  (segment (start 110.886671 138.190989) (end 114.186575 138.190989) (width 0.109) (layer "In6.Cu") (net 679))
  (segment (start 115.175 139.179414) (end 115.175 141.066875) (width 0.109) (layer "In6.Cu") (net 679))
  (segment (start 115.175 141.066875) (end 114.399186 141.842689) (width 0.109) (layer "In6.Cu") (net 679))
  (segment (start 114.186575 138.190989) (end 115.175 139.179414) (width 0.109) (layer "In6.Cu") (net 679))
  (segment (start 108.650002 139) (end 109.079503 138.570499) (width 0.109) (layer "In6.Cu") (net 679))
  (segment (start 110.507161 138.570499) (end 110.886671 138.190989) (width 0.109) (layer "In6.Cu") (net 679))
  (segment (start 114.399186 141.842689) (end 114.957689 141.842689) (width 0.4) (layer "B.Cu") (net 679))
  (segment (start 114.957689 141.842689) (end 115.215 142.1) (width 0.4) (layer "B.Cu") (net 679))
  (segment (start 148.253 113.858605) (end 148.120933 113.726538) (width 0.182) (layer "F.Cu") (net 680))
  (segment (start 148.253 113.860855) (end 148.253 113.858605) (width 0.182) (layer "F.Cu") (net 680))
  (segment (start 148.253 113.860855) (end 148.230706 113.838561) (width 0.182) (layer "F.Cu") (net 680))
  (segment (start 148.253 114.406) (end 148.253 113.860855) (width 0.182) (layer "F.Cu") (net 680))
  (via (at 148.120933 113.726538) (size 0.45) (drill 0.1) (layers "F.Cu" "B.Cu") (net 680))
  (segment (start 148.25 114.46) (end 148.25 113.855605) (width 0.4) (layer "B.Cu") (net 680))
  (segment (start 148.230706 113.838561) (end 148.120933 113.728788) (width 0.4) (layer "B.Cu") (net 680))
  (segment (start 148.25 113.855605) (end 148.120933 113.726538) (width 0.4) (layer "B.Cu") (net 680))
  (segment (start 148.120933 113.728788) (end 148.120933 113.726538) (width 0.4) (layer "B.Cu") (net 680))
  (segment (start 144.361 116.298) (end 143.583 116.298) (width 0.182) (layer "F.Cu") (net 681))
  (segment (start 143.583 116.298) (end 143.485 116.2) (width 0.182) (layer "F.Cu") (net 681))
  (segment (start 141.95176 111.829792) (end 141.955763 111.833794) (width 0.182) (layer "F.Cu") (net 682))
  (segment (start 141.955763 111.833794) (end 142.541763 111.833794) (width 0.182) (layer "F.Cu") (net 682))
  (segment (start 143.153411 111.222147) (end 143.153411 111.210908) (width 0.182) (layer "F.Cu") (net 682))
  (segment (start 142.541763 111.833794) (end 143.153411 111.222147) (width 0.182) (layer "F.Cu") (net 682))
  (segment (start 142.220051 110.31) (end 143.120959 111.210908) (width 0.182) (layer "F.Cu") (net 682))
  (segment (start 143.120959 111.210908) (end 143.153411 111.210908) (width 0.182) (layer "F.Cu") (net 682))
  (segment (start 141.635 110.31) (end 142.220051 110.31) (width 0.182) (layer "F.Cu") (net 682))
  (segment (start 141.151077 129.031873) (end 141.093409 128.974205) (width 0.182) (layer "F.Cu") (net 683))
  (segment (start 141.093409 128.974205) (end 141.093409 128.118647) (width 0.182) (layer "F.Cu") (net 683))
  (segment (start 140.771786 126.869767) (end 140.779379 126.877359) (width 0.182) (layer "F.Cu") (net 683))
  (segment (start 140.779379 126.877359) (end 140.779379 127.804617) (width 0.182) (layer "F.Cu") (net 683))
  (segment (start 140.779379 127.804617) (end 141.093409 128.118647) (width 0.182) (layer "F.Cu") (net 683))
  (segment (start 139.651076 129.031873) (end 139.594975 128.975772) (width 0.182) (layer "F.Cu") (net 684))
  (segment (start 139.594975 128.975772) (end 139.594975 128.122183) (width 0.182) (layer "F.Cu") (net 684))
  (segment (start 140.371787 126.869766) (end 140.371787 127.345371) (width 0.182) (layer "F.Cu") (net 684))
  (segment (start 140.371787 127.345371) (end 139.594975 128.122183) (width 0.182) (layer "F.Cu") (net 684))
  (segment (start 147.85 75.2) (end 147.925 75) (width 0.182) (layer "F.Cu") (net 685))
  (segment (start 147.925 75) (end 147.925 74.385) (width 0.182) (layer "F.Cu") (net 685))
  (via (at 147.85 75.2) (size 0.45) (drill 0.1) (layers "F.Cu" "B.Cu") (net 685))
  (segment (start 147.85 75.2) (end 147.87 75.055) (width 0.182) (layer "B.Cu") (net 685))
  (segment (start 147.87 75.055) (end 147.87 74.396) (width 0.182) (layer "B.Cu") (net 685))
  (segment (start 172.9 126.1) (end 172.9 127.2) (width 0.182) (layer "F.Cu") (net 686))
  (segment (start 172.9 127.2) (end 173.05 127.35) (width 0.182) (layer "F.Cu") (net 686))
  (via (at 173.05 127.35) (size 0.45) (drill 0.1) (layers "F.Cu" "B.Cu") (net 686))
  (segment (start 173.05 127.35) (end 173.225 127.175) (width 0.2) (layer "B.Cu") (net 686))
  (segment (start 173.225 127.175) (end 173.225 125.835) (width 0.2) (layer "B.Cu") (net 686))
  (via (at 142.795 81.624996) (size 0.45) (drill 0.1) (layers "F.Cu" "B.Cu") (net 687))
  (via (at 139.315 91.865) (size 0.45) (drill 0.1) (layers "F.Cu" "B.Cu") (net 687))
  (via (at 139.725 86.175) (size 0.45) (drill 0.1) (layers "F.Cu" "B.Cu") (net 687))
  (segment (start 140.875 87.1) (end 141.5 87.725) (width 0.109) (layer "In4.Cu") (net 687))
  (segment (start 139.96 86.41) (end 139.725 86.175) (width 0.109) (layer "In4.Cu") (net 687))
  (segment (start 141.602498 85.682502) (end 141.602498 82.817498) (width 0.109) (layer "In4.Cu") (net 687))
  (segment (start 140.875 86.41) (end 141.602498 85.682502) (width 0.109) (layer "In4.Cu") (net 687))
  (segment (start 139.96 86.41) (end 140.875 86.41) (width 0.109) (layer "In4.Cu") (net 687))
  (segment (start 141.15 91.425) (end 139.755 91.425) (width 0.109) (layer "In4.Cu") (net 687))
  (segment (start 141.5 91.075) (end 141.15 91.425) (width 0.109) (layer "In4.Cu") (net 687))
  (segment (start 140.875 86.41) (end 140.875 87.1) (width 0.109) (layer "In4.Cu") (net 687))
  (segment (start 139.755 91.425) (end 139.315 91.865) (width 0.109) (layer "In4.Cu") (net 687))
  (segment (start 141.602498 82.817498) (end 142.795 81.624996) (width 0.109) (layer "In4.Cu") (net 687))
  (segment (start 141.5 87.725) (end 141.5 91.075) (width 0.109) (layer "In4.Cu") (net 687))
  (segment (start 138.65 91.25) (end 139.265 91.865) (width 0.2) (layer "B.Cu") (net 687))
  (segment (start 139.5 86.85) (end 139.5 86.4) (width 0.182) (layer "B.Cu") (net 687))
  (segment (start 139.515 86.865) (end 139.5 86.85) (width 0.182) (layer "B.Cu") (net 687))
  (segment (start 139.265 91.865) (end 139.315 91.865) (width 0.2) (layer "B.Cu") (net 687))
  (segment (start 138.35 91.25) (end 138.65 91.25) (width 0.2) (layer "B.Cu") (net 687))
  (segment (start 139.725 86.175) (end 139.5 86.4) (width 0.182) (layer "B.Cu") (net 687))
  (segment (start 142.120004 80.95) (end 142.795 81.624996) (width 0.2) (layer "B.Cu") (net 687))
  (segment (start 141.8 80.95) (end 142.120004 80.95) (width 0.2) (layer "B.Cu") (net 687))
  (segment (start 139.55 86.865) (end 139.515 86.865) (width 0.182) (layer "B.Cu") (net 687))
  (segment (start 143.035 79.95) (end 143.05 79.965) (width 0.2) (layer "B.Cu") (net 689))
  (segment (start 143.035001 79.05) (end 143.035 79.95) (width 0.2) (layer "B.Cu") (net 689))
  (segment (start 143.015 80) (end 143.05 79.965) (width 0.2) (layer "B.Cu") (net 689))
  (segment (start 141.800001 80) (end 143.015 80) (width 0.2) (layer "B.Cu") (net 689))
  (segment (start 138.35 90.3) (end 139.565 90.3) (width 0.2) (layer "B.Cu") (net 692))
  (segment (start 139.565 90.3) (end 139.6 90.265001) (width 0.2) (layer "B.Cu") (net 692))
  (segment (start 139.584999 89.35) (end 139.584999 90.25) (width 0.2) (layer "B.Cu") (net 692))
  (segment (start 139.584999 90.25) (end 139.6 90.265001) (width 0.2) (layer "B.Cu") (net 692))
  (segment (start 138.394005 136.844005) (end 138.8 137.25) (width 0.109) (layer "F.Cu") (net 695))
  (segment (start 137.733001 136.844005) (end 138.394005 136.844005) (width 0.109) (layer "F.Cu") (net 695))
  (segment (start 137.733001 137.114001) (end 137.733001 136.844005) (width 0.109) (layer "F.Cu") (net 695))
  (segment (start 138.8 137.25) (end 138.8 137.535) (width 0.109) (layer "F.Cu") (net 695))
  (segment (start 139.265 138) (end 139.3 138.035) (width 0.109) (layer "F.Cu") (net 695))
  (segment (start 139.3 138.035) (end 139.3 139.3508) (width 0.109) (layer "F.Cu") (net 695))
  (segment (start 138.8 137.535) (end 139.265 138) (width 0.109) (layer "F.Cu") (net 695))
  (segment (start 128.88 84.148663) (end 128.493802 84.534861) (width 0.182) (layer "F.Cu") (net 696))
  (segment (start 128.493802 84.534861) (end 127.907742 84.534861) (width 0.182) (layer "F.Cu") (net 696))
  (segment (start 128.88 83.45) (end 128.88 84.148663) (width 0.182) (layer "F.Cu") (net 696))
  (via (at 128.88 83.45) (size 0.45) (drill 0.1) (layers "F.Cu" "B.Cu") (net 696))
  (segment (start 129.67 83.45) (end 129.97 83.15) (width 0.182) (layer "B.Cu") (net 696))
  (segment (start 128.88 83.45) (end 129.67 83.45) (width 0.182) (layer "B.Cu") (net 696))
  (segment (start 129.97 83.15) (end 129.97 82.395) (width 0.182) (layer "B.Cu") (net 696))
  (segment (start 134.67 70.95) (end 134.67 69.98) (width 0.182) (layer "F.Cu") (net 697))
  (segment (start 131.085139 88.134861) (end 131.75 87.47) (width 0.182) (layer "F.Cu") (net 697))
  (segment (start 132.86 63.25) (end 130.96 63.25) (width 0.182) (layer "F.Cu") (net 697))
  (segment (start 133.78 76.160976) (end 133.78 71.84) (width 0.182) (layer "F.Cu") (net 697))
  (segment (start 134.39 68.2) (end 134.67 67.92) (width 0.182) (layer "F.Cu") (net 697))
  (segment (start 134.39 69.7) (end 134.39 68.2) (width 0.182) (layer "F.Cu") (net 697))
  (segment (start 131.75 79.03) (end 133.48 77.3) (width 0.182) (layer "F.Cu") (net 697))
  (segment (start 130.96 63.25) (end 130.34 62.63) (width 0.182) (layer "F.Cu") (net 697))
  (segment (start 133.48 76.460976) (end 133.78 76.160976) (width 0.182) (layer "F.Cu") (net 697))
  (segment (start 134.67 65.06) (end 132.86 63.25) (width 0.182) (layer "F.Cu") (net 697))
  (segment (start 127.907742 88.134861) (end 131.085139 88.134861) (width 0.182) (layer "F.Cu") (net 697))
  (segment (start 133.48 77.3) (end 133.48 76.460976) (width 0.182) (layer "F.Cu") (net 697))
  (segment (start 134.67 67.92) (end 134.67 65.06) (width 0.182) (layer "F.Cu") (net 697))
  (segment (start 134.67 69.98) (end 134.39 69.7) (width 0.182) (layer "F.Cu") (net 697))
  (segment (start 133.78 71.84) (end 134.67 70.95) (width 0.182) (layer "F.Cu") (net 697))
  (segment (start 131.75 87.47) (end 131.75 79.03) (width 0.182) (layer "F.Cu") (net 697))
  (via (at 130.34 62.63) (size 0.45) (drill 0.1) (layers "F.Cu" "B.Cu") (net 697))
  (segment (start 130.33 62.64) (end 130.34 62.63) (width 0.182) (layer "B.Cu") (net 697))
  (segment (start 129.3 63.265) (end 130.33 63.265) (width 0.182) (layer "B.Cu") (net 697))
  (segment (start 130.33 63.265) (end 130.33 62.64) (width 0.182) (layer "B.Cu") (net 697))
  (segment (start 110.835 97.885) (end 110.835 99.225) (width 0.182) (layer "F.Cu") (net 698))
  (segment (start 110.175 97.225) (end 110.835 97.885) (width 0.182) (layer "F.Cu") (net 698))
  (segment (start 109.75 97.225) (end 110.175 97.225) (width 0.182) (layer "F.Cu") (net 698))
  (via (at 110.525 97.6) (size 0.45) (drill 0.1) (layers "F.Cu" "B.Cu") (net 698))
  (segment (start 110.425 97.5) (end 110.525 97.6) (width 0.182) (layer "B.Cu") (net 698))
  (segment (start 110.425 96.935) (end 110.425 97.5) (width 0.182) (layer "B.Cu") (net 698))
  (segment (start 153.8 150.825) (end 153.8 150.2) (width 0.182) (layer "F.Cu") (net 699))
  (segment (start 153.15 122.1) (end 153.15 122.05) (width 0.182) (layer "F.Cu") (net 699))
  (segment (start 151.46 122.175) (end 151.46 122.56) (width 0.182) (layer "F.Cu") (net 699))
  (segment (start 152.55 122.7) (end 153.15 122.1) (width 0.182) (layer "F.Cu") (net 699))
  (segment (start 151.46 122.56) (end 151.6 122.7) (width 0.182) (layer "F.Cu") (net 699))
  (segment (start 151.6 122.7) (end 152.55 122.7) (width 0.182) (layer "F.Cu") (net 699))
  (via (at 153.8 150.2) (size 0.45) (drill 0.1) (layers "F.Cu" "B.Cu") (net 699))
  (via (at 152.45 131.9) (size 0.45) (drill 0.1) (layers "F.Cu" "B.Cu") (net 699))
  (via (at 153.15 122.05) (size 0.45) (drill 0.1) (layers "F.Cu" "B.Cu") (net 699))
  (segment (start 152.45 145.85) (end 153.8 147.2) (width 0.182) (layer "In4.Cu") (net 699))
  (segment (start 153.8 147.2) (end 153.8 150.2) (width 0.182) (layer "In4.Cu") (net 699))
  (segment (start 152.45 131.9) (end 152.45 145.85) (width 0.182) (layer "In4.Cu") (net 699))
  (segment (start 153.55 122.05) (end 154.05 122.55) (width 0.182) (layer "In6.Cu") (net 699))
  (segment (start 153.15 122.05) (end 153.55 122.05) (width 0.182) (layer "In6.Cu") (net 699))
  (segment (start 154.05 128.5) (end 152.45 130.1) (width 0.182) (layer "In6.Cu") (net 699))
  (segment (start 154.05 122.55) (end 154.05 128.5) (width 0.182) (layer "In6.Cu") (net 699))
  (segment (start 152.45 130.1) (end 152.45 131.9) (width 0.182) (layer "In6.Cu") (net 699))
  (segment (start 152.135 121.5) (end 153.15 121.5) (width 0.182) (layer "F.Cu") (net 700))
  (segment (start 154.8 150.8) (end 154.8 150.2) (width 0.182) (layer "F.Cu") (net 700))
  (via (at 153.15 121.5) (size 0.45) (drill 0.1) (layers "F.Cu" "B.Cu") (net 700))
  (via (at 153.1 132.4) (size 0.45) (drill 0.1) (layers "F.Cu" "B.Cu") (net 700))
  (via (at 154.8 150.2) (size 0.45) (drill 0.1) (layers "F.Cu" "B.Cu") (net 700))
  (segment (start 154.8 145.87) (end 154.8 150.2) (width 0.182) (layer "In4.Cu") (net 700))
  (segment (start 153.1 144.17) (end 154.8 145.87) (width 0.182) (layer "In4.Cu") (net 700))
  (segment (start 153.1 132.4) (end 153.1 144.17) (width 0.182) (layer "In4.Cu") (net 700))
  (segment (start 154.65 128.95) (end 153.1 130.5) (width 0.182) (layer "In6.Cu") (net 700))
  (segment (start 153.1 130.5) (end 153.1 132.4) (width 0.182) (layer "In6.Cu") (net 700))
  (segment (start 154.65 122.1) (end 154.65 128.95) (width 0.182) (layer "In6.Cu") (net 700))
  (segment (start 154.05 121.5) (end 154.65 122.1) (width 0.182) (layer "In6.Cu") (net 700))
  (segment (start 153.15 121.5) (end 154.05 121.5) (width 0.182) (layer "In6.Cu") (net 700))
  (segment (start 168.415 115.8) (end 168.415 115.010002) (width 0.182) (layer "F.Cu") (net 765))
  (segment (start 168.415 115.010002) (end 168.425 115.000002) (width 0.182) (layer "F.Cu") (net 765))
  (segment (start 178.4 115.45) (end 178.015 115.835) (width 0.2) (layer "F.Cu") (net 765))
  (segment (start 164.65 132.1) (end 165.445705 131.304295) (width 0.182) (layer "F.Cu") (net 765))
  (segment (start 164.65 132.1) (end 164.65 135.85) (width 0.182) (layer "F.Cu") (net 765))
  (segment (start 168.399992 130.6) (end 168.399992 130.865008) (width 0.182) (layer "F.Cu") (net 765))
  (segment (start 170.660001 132.14) (end 170.895001 132.375) (width 0.182) (layer "F.Cu") (net 765))
  (segment (start 168.399992 130.865008) (end 168.015 131.25) (width 0.182) (layer "F.Cu") (net 765))
  (segment (start 170.56 132.14) (end 170.305 132.14) (width 0.182) (layer "F.Cu") (net 765))
  (segment (start 167.960705 131.304295) (end 168.015 131.25) (width 0.182) (layer "F.Cu") (net 765))
  (segment (start 170.305 132.14) (end 170.205 132.04) (width 0.182) (layer "F.Cu") (net 765))
  (segment (start 178.4 115.25) (end 178.4 115.45) (width 0.2) (layer "F.Cu") (net 765))
  (segment (start 178.015 115.835) (end 178.015 115.875) (width 0.2) (layer "F.Cu") (net 765))
  (segment (start 165.445705 131.304295) (end 167.960705 131.304295) (width 0.182) (layer "F.Cu") (net 765))
  (segment (start 170.56 132.14) (end 170.660001 132.14) (width 0.182) (layer "F.Cu") (net 765))
  (segment (start 164.65 135.85) (end 164.835 136.035) (width 0.182) (layer "F.Cu") (net 765))
  (segment (start 164.835 136.035) (end 167.2 136.035) (width 0.182) (layer "F.Cu") (net 765))
  (via (at 168.425 115.000002) (size 0.5) (drill 0.15) (layers "F.Cu" "B.Cu") (net 765))
  (via (at 168.399992 130.6) (size 0.45) (drill 0.1) (layers "F.Cu" "B.Cu") (net 765))
  (via (at 178.4 115.25) (size 0.45) (drill 0.1) (layers "F.Cu" "B.Cu") (net 765))
  (via (at 167.55 138) (size 0.45) (drill 0.1) (layers "F.Cu" "B.Cu") (net 765))
  (via (at 170.205 132.04) (size 0.5) (drill 0.15) (layers "F.Cu" "B.Cu") (net 765))
  (segment (start 176.6 118.2) (end 170.88119 118.2) (width 0.2) (layer "In4.Cu") (net 765))
  (segment (start 178.4 116.4) (end 176.6 118.2) (width 0.2) (layer "In4.Cu") (net 765))
  (segment (start 170.290595 129.515595) (end 170.290595 118.790595) (width 0.182) (layer "In4.Cu") (net 765))
  (segment (start 169.20619 130.6) (end 170.290595 129.515595) (width 0.182) (layer "In4.Cu") (net 765))
  (segment (start 178.4 115.25) (end 178.4 116.4) (width 0.2) (layer "In4.Cu") (net 765))
  (segment (start 168.425 116.925) (end 168.425 115.000002) (width 0.182) (layer "In4.Cu") (net 765))
  (segment (start 170.290595 118.790595) (end 168.425 116.925) (width 0.182) (layer "In4.Cu") (net 765))
  (segment (start 170.88119 118.2) (end 170.290595 118.790595) (width 0.2) (layer "In4.Cu") (net 765))
  (segment (start 168.399992 130.6) (end 169.20619 130.6) (width 0.182) (layer "In4.Cu") (net 765))
  (segment (start 167.55 138) (end 167.55 137.15) (width 0.182) (layer "In6.Cu") (net 765))
  (segment (start 167.55 137.15) (end 170.205 134.495) (width 0.182) (layer "In6.Cu") (net 765))
  (segment (start 170.205 134.495) (end 170.205 132.04) (width 0.182) (layer "In6.Cu") (net 765))
  (segment (start 143.35435 81.598037) (end 143.35435 81.55435) (width 0.2) (layer "F.Cu") (net 766))
  (segment (start 138.55 84.7992) (end 138.1492 85.2) (width 0.182) (layer "F.Cu") (net 766))
  (segment (start 140.3 81.15) (end 136.65 84.8) (width 0.2) (layer "F.Cu") (net 766))
  (segment (start 143.35435 81.55435) (end 142.95 81.15) (width 0.2) (layer "F.Cu") (net 766))
  (segment (start 142.95 81.15) (end 140.3 81.15) (width 0.2) (layer "F.Cu") (net 766))
  (segment (start 139.3 90.51) (end 141.05 92.26) (width 0.182) (layer "F.Cu") (net 766))
  (segment (start 139.3 86.45) (end 139.3 90.51) (width 0.182) (layer "F.Cu") (net 766))
  (segment (start 138.05 85.2) (end 139.3 86.45) (width 0.182) (layer "F.Cu") (net 766))
  (segment (start 138.1492 85.2) (end 138.05 85.2) (width 0.182) (layer "F.Cu") (net 766))
  (segment (start 136.65 84.8) (end 135.6 84.8) (width 0.2) (layer "F.Cu") (net 766))
  (segment (start 137.65 84.8) (end 138.05 85.2) (width 0.182) (layer "F.Cu") (net 766))
  (segment (start 141.05 92.26) (end 141.05 92.6) (width 0.182) (layer "F.Cu") (net 766))
  (via (at 137.65 84.8) (size 0.45) (drill 0.1) (layers "F.Cu" "B.Cu") (net 766))
  (via (at 135.6 84.8) (size 0.45) (drill 0.1) (layers "F.Cu" "B.Cu") (net 766))
  (via (at 143.35435 81.598037) (size 0.45) (drill 0.1) (layers "F.Cu" "B.Cu") (net 766))
  (via (at 141.05 92.6) (size 0.5) (drill 0.15) (layers "F.Cu" "B.Cu") (net 766))
  (segment (start 143.35435 81.23935) (end 143.35435 81.598037) (width 0.2) (layer "B.Cu") (net 766))
  (segment (start 140.385 92.6) (end 141.05 92.6) (width 0.182) (layer "B.Cu") (net 766))
  (segment (start 143.05 80.935) (end 143.35435 81.23935) (width 0.2) (layer "B.Cu") (net 766))
  (segment (start 182.6 120.89) (end 182.6 120.275) (width 0.182) (layer "F.Cu") (net 767))
  (segment (start 182.6 118.8) (end 182.6 118.25) (width 0.182) (layer "F.Cu") (net 767))
  (segment (start 182.6 118.25) (end 182.7 118.15) (width 0.182) (layer "F.Cu") (net 767))
  (via (at 182.6 120.275) (size 0.45) (drill 0.1) (layers "F.Cu" "B.Cu") (net 767))
  (via (at 182.6 118.8) (size 0.45) (drill 0.1) (layers "F.Cu" "B.Cu") (net 767))
  (via (at 176.775 114.8) (size 0.45) (drill 0.1) (layers "F.Cu" "B.Cu") (net 767))
  (via (at 176.325 116.15) (size 0.45) (drill 0.1) (layers "F.Cu" "B.Cu") (net 767))
  (segment (start 182.6 119.6) (end 182.6 120.275) (width 0.182) (layer "In6.Cu") (net 767))
  (segment (start 181.8 118.8) (end 182.6 119.6) (width 0.182) (layer "In6.Cu") (net 767))
  (segment (start 181.8 118.3) (end 181.8 118.8) (width 0.182) (layer "In6.Cu") (net 767))
  (segment (start 180.45 116.95) (end 181.8 118.3) (width 0.182) (layer "In6.Cu") (net 767))
  (segment (start 181.1 116) (end 182.6 117.5) (width 0.182) (layer "In6.Cu") (net 767))
  (segment (start 176.325 116.15) (end 177.125 116.95) (width 0.182) (layer "In6.Cu") (net 767))
  (segment (start 177.975 116) (end 181.1 116) (width 0.182) (layer "In6.Cu") (net 767))
  (segment (start 177.125 116.95) (end 180.45 116.95) (width 0.182) (layer "In6.Cu") (net 767))
  (segment (start 176.775 114.8) (end 177.975 116) (width 0.182) (layer "In6.Cu") (net 767))
  (segment (start 182.6 117.5) (end 182.6 118.8) (width 0.182) (layer "In6.Cu") (net 767))
  (segment (start 171.35 116.2) (end 171.075 115.925) (width 0.182) (layer "F.Cu") (net 768))
  (segment (start 171.075 115.925) (end 171.075 115) (width 0.182) (layer "F.Cu") (net 768))
  (segment (start 167.55 115.2) (end 167.55 116.755) (width 0.182) (layer "F.Cu") (net 768))
  (segment (start 170.625 114.55) (end 168.2 114.55) (width 0.182) (layer "F.Cu") (net 768))
  (segment (start 171.075 115) (end 170.625 114.55) (width 0.182) (layer "F.Cu") (net 768))
  (segment (start 173 117) (end 173 116.85) (width 0.182) (layer "F.Cu") (net 768))
  (segment (start 173 116.85) (end 172.35 116.2) (width 0.182) (layer "F.Cu") (net 768))
  (segment (start 168.2 114.55) (end 167.55 115.2) (width 0.182) (layer "F.Cu") (net 768))
  (segment (start 172.35 116.2) (end 171.35 116.2) (width 0.182) (layer "F.Cu") (net 768))
  (segment (start 172.7 119.995) (end 173.37 119.995) (width 0.182) (layer "F.Cu") (net 768))
  (segment (start 173.37 119.995) (end 173.375 120) (width 0.182) (layer "F.Cu") (net 768))
  (via (at 165.19 117.16) (size 0.5) (drill 0.15) (layers "F.Cu" "B.Cu") (net 768))
  (via (at 173.375 120) (size 0.5) (drill 0.15) (layers "F.Cu" "B.Cu") (net 768))
  (segment (start 170.025 120) (end 173.375 120) (width 0.182) (layer "In6.Cu") (net 768))
  (segment (start 167.185 117.16) (end 170.025 120) (width 0.182) (layer "In6.Cu") (net 768))
  (segment (start 165.19 117.16) (end 167.185 117.16) (width 0.182) (layer "In6.Cu") (net 768))
  (segment (start 137.56 96.35) (end 137.8008 96.3492) (width 0.182) (layer "F.Cu") (net 769))
  (segment (start 137.8008 96.3492) (end 138.6 96.3492) (width 0.182) (layer "F.Cu") (net 769))
  (via (at 137.56 96.35) (size 0.45) (drill 0.1) (layers "F.Cu" "B.Cu") (net 769))
  (via (at 139.945 91.865) (size 0.45) (drill 0.1) (layers "F.Cu" "B.Cu") (net 769))
  (via (at 135.55 95.7) (size 0.45) (drill 0.1) (layers "F.Cu" "B.Cu") (net 769))
  (segment (start 139.945 91.865) (end 136.11 95.7) (width 0.182) (layer "In4.Cu") (net 769))
  (segment (start 136.11 95.7) (end 135.55 95.7) (width 0.182) (layer "In4.Cu") (net 769))
  (segment (start 138.495 96.35) (end 137.079 96.35) (width 0.182) (layer "B.Cu") (net 769))
  (segment (start 139.406 95.269) (end 139.384 95.269) (width 0.182) (layer "B.Cu") (net 769))
  (segment (start 138.724 95.929) (end 138.724 96.121) (width 0.182) (layer "B.Cu") (net 769))
  (segment (start 139.6 91.234999) (end 139.734999 91.234999) (width 0.4) (layer "B.Cu") (net 769))
  (segment (start 138.724 96.121) (end 138.495 96.35) (width 0.182) (layer "B.Cu") (net 769))
  (segment (start 139.384 95.269) (end 138.724 95.929) (width 0.182) (layer "B.Cu") (net 769))
  (segment (start 139.734999 91.234999) (end 139.945 91.445) (width 0.4) (layer "B.Cu") (net 769))
  (segment (start 139.945 91.445) (end 139.945 91.865) (width 0.4) (layer "B.Cu") (net 769))
  (segment (start 137.079 96.35) (end 136.544 95.815) (width 0.182) (layer "B.Cu") (net 769))
  (segment (start 180.8 137.9) (end 180.8 138.4492) (width 0.2) (layer "F.Cu") (net 770))
  (segment (start 182.235 136.7) (end 182.16 136.625) (width 0.182) (layer "F.Cu") (net 770))
  (segment (start 175.375 133.084709) (end 175.358327 133.101382) (width 0.182) (layer "F.Cu") (net 770))
  (segment (start 180.8 138.4492) (end 181.35 138.9992) (width 0.2) (layer "F.Cu") (net 770))
  (segment (start 175.375 132.545) (end 175.375 133.084709) (width 0.182) (layer "F.Cu") (net 770))
  (segment (start 182.9 136) (end 182.9 135.9) (width 0.182) (layer "F.Cu") (net 770))
  (segment (start 183 136.7) (end 182.235 136.7) (width 0.182) (layer "F.Cu") (net 770))
  (segment (start 182.275 136.625) (end 182.9 136) (width 0.182) (layer "F.Cu") (net 770))
  (segment (start 188.96 138.19) (end 188.95 138.2) (width 0.182) (layer "F.Cu") (net 770))
  (segment (start 182.16 136.625) (end 182.275 136.625) (width 0.182) (layer "F.Cu") (net 770))
  (segment (start 188.96 137.575) (end 188.96 138.19) (width 0.182) (layer "F.Cu") (net 770))
  (via (at 188.95 138.2) (size 0.5) (drill 0.15) (layers "F.Cu" "B.Cu") (net 770))
  (via (at 175.358327 133.101382) (size 0.45) (drill 0.1) (layers "F.Cu" "B.Cu") (net 770))
  (via (at 183 136.7) (size 0.45) (drill 0.1) (layers "F.Cu" "B.Cu") (net 770))
  (via (at 182.9 135.9) (size 0.45) (drill 0.1) (layers "F.Cu" "B.Cu") (net 770))
  (segment (start 184.5 138.2) (end 188.95 138.2) (width 0.182) (layer "In4.Cu") (net 770))
  (segment (start 184.5 138.2) (end 183 136.7) (width 0.182) (layer "In4.Cu") (net 770))
  (segment (start 175.133328 133.713328) (end 175.133328 133.326381) (width 0.182) (layer "In6.Cu") (net 770))
  (segment (start 177.32 135.9) (end 182.9 135.9) (width 0.182) (layer "In6.Cu") (net 770))
  (segment (start 175.133328 133.326381) (end 175.358327 133.101382) (width 0.182) (layer "In6.Cu") (net 770))
  (segment (start 175.133328 133.713328) (end 177.32 135.9) (width 0.182) (layer "In6.Cu") (net 770))
  (segment (start 190 136.561396) (end 189.985356 136.546752) (width 0.2) (layer "F.Cu") (net 771))
  (segment (start 184.4 135.7) (end 184.4 135.1) (width 0.182) (layer "F.Cu") (net 771))
  (segment (start 184.525 132.47) (end 184.525 132.952934) (width 0.182) (layer "F.Cu") (net 771))
  (segment (start 184.525 132.952934) (end 184.586033 133.013967) (width 0.182) (layer "F.Cu") (net 771))
  (via (at 184.4 135.7) (size 0.5) (drill 0.15) (layers "F.Cu" "B.Cu") (net 771))
  (via (at 190.6 137.15) (size 0.45) (drill 0.1) (layers "F.Cu" "B.Cu") (net 771))
  (via (at 184.586033 133.013967) (size 0.5) (drill 0.15) (layers "F.Cu" "B.Cu") (net 771))
  (via (at 190.525 137.9) (size 0.45) (drill 0.1) (layers "F.Cu" "B.Cu") (net 771))
  (segment (start 189.15 135.7) (end 190.6 137.15) (width 0.182) (layer "In4.Cu") (net 771))
  (segment (start 184.4 135.7) (end 189.15 135.7) (width 0.182) (layer "In4.Cu") (net 771))
  (segment (start 185.85 133.825) (end 185.038967 133.013967) (width 0.182) (layer "In6.Cu") (net 771))
  (segment (start 190.525 137.9) (end 190.025 137.4) (width 0.182) (layer "In6.Cu") (net 771))
  (segment (start 185.85 135.65) (end 185.85 133.825) (width 0.182) (layer "In6.Cu") (net 771))
  (segment (start 185.038967 133.013967) (end 184.586033 133.013967) (width 0.182) (layer "In6.Cu") (net 771))
  (segment (start 190.025 137.4) (end 187.6 137.4) (width 0.182) (layer "In6.Cu") (net 771))
  (segment (start 187.6 137.4) (end 185.85 135.65) (width 0.182) (layer "In6.Cu") (net 771))
  (segment (start 149.435 77.835) (end 149.75 78.15) (width 0.182) (layer "F.Cu") (net 772))
  (segment (start 149.75 78.95) (end 149.75 78.15) (width 0.182) (layer "F.Cu") (net 772))
  (segment (start 148.625 77.835) (end 149.435 77.835) (width 0.182) (layer "F.Cu") (net 772))
  (via (at 149.75 78.15) (size 0.45) (drill 0.1) (layers "F.Cu" "B.Cu") (net 772))
  (segment (start 144.56 76.53) (end 145.56 76.53) (width 0.4) (layer "B.Cu") (net 772))
  (segment (start 145.57 76.485) (end 145.57 77.046041) (width 0.2) (layer "B.Cu") (net 772))
  (segment (start 146.623959 78.1) (end 148.375 78.1) (width 0.2) (layer "B.Cu") (net 772))
  (segment (start 148.375 78.1) (end 149.075 77.4) (width 0.2) (layer "B.Cu") (net 772))
  (segment (start 145.57 77.046041) (end 146.623959 78.1) (width 0.2) (layer "B.Cu") (net 772))
  (segment (start 165.4 129.675) (end 164.625 128.9) (width 0.182) (layer "F.Cu") (net 773))
  (segment (start 165.45 129.675) (end 165.4 129.675) (width 0.182) (layer "F.Cu") (net 773))
  (via (at 164.9 129.925) (size 0.45) (drill 0.1) (layers "F.Cu" "B.Cu") (net 773))
  (via (at 175.55 129.5) (size 0.45) (drill 0.1) (layers "F.Cu" "B.Cu") (net 773))
  (via (at 165.45 129.675) (size 0.45) (drill 0.1) (layers "F.Cu" "B.Cu") (net 773))
  (segment (start 165.45 129.675) (end 165.45 131.125) (width 0.182) (layer "In4.Cu") (net 773))
  (segment (start 175.1 129.95) (end 175.55 129.5) (width 0.182) (layer "In4.Cu") (net 773))
  (segment (start 165.6 131.275) (end 171.2 131.275) (width 0.182) (layer "In4.Cu") (net 773))
  (segment (start 165.45 131.125) (end 165.6 131.275) (width 0.182) (layer "In4.Cu") (net 773))
  (segment (start 172.525 129.95) (end 175.1 129.95) (width 0.182) (layer "In4.Cu") (net 773))
  (segment (start 171.2 131.275) (end 172.525 129.95) (width 0.182) (layer "In4.Cu") (net 773))
  (segment (start 173 130.775) (end 173.5 131.275) (width 0.2) (layer "B.Cu") (net 773))
  (segment (start 171.275 131.275) (end 171.775 130.775) (width 0.2) (layer "B.Cu") (net 773))
  (segment (start 165.6 131.275) (end 171.275 131.275) (width 0.2) (layer "B.Cu") (net 773))
  (segment (start 175.54 129.51) (end 174.95 129.51) (width 0.182) (layer "B.Cu") (net 773))
  (segment (start 164.9 129.925) (end 164.9 130.575) (width 0.2) (layer "B.Cu") (net 773))
  (segment (start 171.775 130.775) (end 173 130.775) (width 0.2) (layer "B.Cu") (net 773))
  (segment (start 164.9 130.575) (end 165.6 131.275) (width 0.2) (layer "B.Cu") (net 773))
  (segment (start 175.55 129.5) (end 175.54 129.51) (width 0.182) (layer "B.Cu") (net 773))
  (segment (start 176.15 127.295) (end 175.805 126.95) (width 0.2) (layer "B.Cu") (net 773))
  (segment (start 176.15 130.325) (end 176.15 127.295) (width 0.2) (layer "B.Cu") (net 773))
  (segment (start 175.2 131.275) (end 176.15 130.325) (width 0.2) (layer "B.Cu") (net 773))
  (segment (start 173.5 131.275) (end 175.2 131.275) (width 0.2) (layer "B.Cu") (net 773))
  (segment (start 173.825 128.21) (end 174.775 128.21) (width 0.182) (layer "F.Cu") (net 774))
  (segment (start 173.11 128.21) (end 173.825 128.21) (width 0.182) (layer "F.Cu") (net 774))
  (segment (start 173.1 128.2) (end 173.11 128.21) (width 0.182) (layer "F.Cu") (net 774))
  (via (at 173.1 128.2) (size 0.45) (drill 0.1) (layers "F.Cu" "B.Cu") (net 774))
  (segment (start 173.925 128.54) (end 174.95 128.54) (width 0.2) (layer "B.Cu") (net 774))
  (segment (start 173.1 128.2) (end 173.44 128.54) (width 0.2) (layer "B.Cu") (net 774))
  (segment (start 173.44 128.54) (end 173.925 128.54) (width 0.2) (layer "B.Cu") (net 774))
  (segment (start 116.537785 150.877785) (end 116.583 150.923) (width 0.109) (layer "F.Cu") (net 799))
  (segment (start 107.029215 150.877785) (end 116.537785 150.877785) (width 0.109) (layer "F.Cu") (net 799))
  (segment (start 106.984 150.923) (end 107.029215 150.877785) (width 0.109) (layer "F.Cu") (net 799))
  (segment (start 93.775 66.793198) (end 93.775 67.35) (width 0.182) (layer "F.Cu") (net 804))
  (segment (start 93.763 66.781198) (end 93.775 66.793198) (width 0.182) (layer "F.Cu") (net 804))
  (segment (start 93.763 65.618) (end 93.763 66.781198) (width 0.182) (layer "F.Cu") (net 804))
  (segment (start 93.775 67.35) (end 94.35 67.925) (width 0.182) (layer "F.Cu") (net 804))

  (zone (net 691) (net_name "Net-(U52-FB)") (layer "F.Cu") (hatch edge 0.508)
    (priority 4)
    (connect_pads yes (clearance 0.254))
    (min_thickness 0.254) (filled_areas_thickness no)
    (fill yes (thermal_gap 0.508) (thermal_bridge_width 0.508) (smoothing fillet) (radius 0.127))
    (polygon
      (pts
        (xy 174.025 121.475)
        (xy 170.825 121.475)
        (xy 170.825 120.5)
        (xy 174.025 120.5)
      )
    )
  )
  (zone (net 314) (net_name "Net-(U52-BST)") (layer "F.Cu") (hatch edge 0.508)
    (priority 3)
    (connect_pads yes (clearance 0.254))
    (min_thickness 0.254) (filled_areas_thickness no)
    (fill yes (thermal_gap 0.508) (thermal_bridge_width 0.508) (smoothing fillet) (radius 0.127))
    (polygon
      (pts
        (xy 173.15 119.55)
        (xy 170.8 119.55)
        (xy 170.8 118.575)
        (xy 171.25 118.575)
        (xy 171.25 117.475)
        (xy 173.15 117.475)
      )
    )
  )
  (zone (net 1) (net_name "GND") (layer "F.Cu") (hatch edge 0.508)
    (priority 1)
    (connect_pads yes (clearance 0.254))
    (min_thickness 0.254) (filled_areas_thickness no)
    (fill yes (thermal_gap 0.508) (thermal_bridge_width 0.508) (smoothing fillet) (radius 0.127))
    (polygon
      (pts
        (xy 168.05 118.375)
        (xy 169.65 118.375)
        (xy 169.65 119.6)
        (xy 168.15 119.6)
        (xy 168.15 120.475)
        (xy 163.2 120.475)
        (xy 163.2 117.475)
        (xy 168.05 117.475)
      )
    )
  )
  (zone (net 312) (net_name "/Power Supply/DC/DC conventers/SW_PS_1V2") (layer "F.Cu") (hatch edge 0.508)
    (priority 2)
    (connect_pads yes (clearance 0.254))
    (min_thickness 0.254) (filled_areas_thickness no)
    (fill yes (thermal_gap 0.508) (thermal_bridge_width 0.508) (smoothing fillet) (radius 0.127))
    (polygon
      (pts
        (xy 172.15 117.475)
        (xy 171.25 117.475)
        (xy 171.25 118.475)
        (xy 170.75 118.475)
        (xy 170.75 120.475)
        (xy 168.15 120.475)
        (xy 168.15 119.7)
        (xy 169.65 119.7)
        (xy 169.65 116.275)
        (xy 172.15 116.275)
      )
    )
  )
  (zone (net 768) (net_name "/Power Supply/DC/DC conventers/PS_1V2_OUT") (layer "F.Cu") (hatch edge 0.508)
    (connect_pads yes (clearance 0.254))
    (min_thickness 0.254) (filled_areas_thickness no)
    (fill yes (thermal_gap 0.508) (thermal_bridge_width 0.508) (smoothing fillet) (radius 0.127))
    (polygon
      (pts
        (xy 168 115.3375)
        (xy 168 116.275)
        (xy 169.55 116.275)
        (xy 169.55 118.275)
        (xy 168.15 118.275)
        (xy 168.15 117.375)
        (xy 163.2 117.375)
        (xy 163.2 116.3)
        (xy 166.4 116.3)
        (xy 166.4 115.2)
        (xy 168 115.2)
      )
    )
  )
  (zone (net 690) (net_name "Net-(U51-FB)") (layer "F.Cu") (hatch edge 0.508)
    (priority 1)
    (connect_pads yes (clearance 0.254))
    (min_thickness 0.254) (filled_areas_thickness no)
    (fill yes (thermal_gap 0.508) (thermal_bridge_width 0.508) (smoothing fillet) (radius 0.127))
    (polygon
      (pts
        (xy 181.3 121.425)
        (xy 180.375 121.425)
        (xy 180.375 120.7)
        (xy 182.075 120.7)
        (xy 182.075 121.4)
        (xy 183.1 121.4)
        (xy 183.1 122.35)
        (xy 182.475 122.975)
        (xy 181.3 122.975)
      )
    )
  )
  (zone (net 276) (net_name "Net-(U51-BST)") (layer "F.Cu") (hatch edge 0.508)
    (priority 4)
    (connect_pads yes (clearance 0.254))
    (min_thickness 0.254) (filled_areas_thickness no)
    (fill yes (thermal_gap 0.508) (thermal_bridge_width 0.508) (smoothing fillet) (radius 0.127))
    (polygon
      (pts
        (xy 182.05 119.525)
        (xy 180.35 119.525)
        (xy 180.35 118.625)
        (xy 180.75 118.625)
        (xy 180.75 117.525)
        (xy 182.05 117.525)
      )
    )
  )
  (zone (net 1) (net_name "GND") (layer "F.Cu") (hatch edge 0.508)
    (priority 2)
    (connect_pads yes (clearance 0.254))
    (min_thickness 0.254) (filled_areas_thickness no)
    (fill yes (thermal_gap 0.508) (thermal_bridge_width 0.508) (smoothing fillet) (radius 0.127))
    (polygon
      (pts
        (xy 177.55 118.425)
        (xy 179.1 118.425)
        (xy 179.1 119.625)
        (xy 177.65 119.625)
        (xy 177.65 120.425)
        (xy 175.45 120.425)
        (xy 175.45 117.525)
        (xy 177.55 117.525)
      )
    )
  )
  (zone (net 767) (net_name "/Power Supply/DC/DC conventers/PS_1V8_OUT") (layer "F.Cu") (hatch edge 0.508)
    (priority 1)
    (connect_pads yes (clearance 0.254))
    (min_thickness 0.254) (filled_areas_thickness no)
    (fill yes (thermal_gap 0.508) (thermal_bridge_width 0.508) (smoothing fillet) (radius 0.127))
    (polygon
      (pts
        (xy 178.55 115.4)
        (xy 178.55 116.325)
        (xy 179.05 116.325)
        (xy 179.05 118.325)
        (xy 177.65 118.325)
        (xy 177.65 117.425)
        (xy 175.45 117.425)
        (xy 175.45 116.4)
        (xy 176 116.4)
        (xy 176.5 115.9)
        (xy 176.5 114.775)
        (xy 176.75 114.525)
        (xy 178.55 114.525)
      )
    )
  )
  (zone (net 311) (net_name "/Power Supply/DC/DC conventers/SW_PS_1V8") (layer "F.Cu") (hatch edge 0.508)
    (priority 3)
    (connect_pads yes (clearance 0.254))
    (min_thickness 0.254) (filled_areas_thickness no)
    (fill yes (thermal_gap 0.508) (thermal_bridge_width 0.508) (smoothing fillet) (radius 0.127))
    (polygon
      (pts
        (xy 181.8 117.475)
        (xy 180.75 117.475)
        (xy 180.75 118.525)
        (xy 180.2 118.525)
        (xy 180.2 120.575)
        (xy 177.7 120.575)
        (xy 177.675 119.675)
        (xy 179.125 119.675)
        (xy 179.125 116.375)
        (xy 181.8 116.375)
      )
    )
  )
  (zone (net 249) (net_name "Net-(U48-PVCC)") (layer "F.Cu") (hatch edge 0.508)
    (priority 8)
    (connect_pads yes (clearance 0.127))
    (min_thickness 0.1) (filled_areas_thickness no)
    (fill yes (thermal_gap 0.508) (thermal_bridge_width 0.508) (smoothing fillet) (radius 0.2))
    (polygon
      (pts
        (xy 175.225 124.55)
        (xy 176.25 124.55)
        (xy 176.25 125.35)
        (xy 175.5 125.35)
        (xy 175.15 125)
        (xy 173.45 125)
        (xy 173.45 124.7)
        (xy 174.3 124.7)
        (xy 174.3 124.075)
        (xy 175.225 124.075)
      )
    )
  )
  (zone (net 773) (net_name "/Power Supply/DC/DC conventers/SOM_5V_OUT") (layer "F.Cu") (hatch edge 0.508)
    (priority 4)
    (connect_pads yes (clearance 0.1))
    (min_thickness 0.1) (filled_areas_thickness no)
    (fill yes (thermal_gap 0.508) (thermal_bridge_width 0.508) (smoothing fillet) (radius 0.2))
    (polygon
      (pts
        (xy 170.425 126.825)
        (xy 170.425 128.5)
        (xy 166.275 128.5)
        (xy 166.275 129.275)
        (xy 165.3 130.25)
        (xy 163.175 130.25)
        (xy 163.175 128.425)
        (xy 164.875 128.425)
        (xy 165.375 127.925)
        (xy 165.375 122.575)
        (xy 167.925 122.575)
        (xy 167.925 126.825)
      )
    )
  )
  (zone (net 255) (net_name "Net-(U48-FB)") (layer "F.Cu") (hatch edge 0.508)
    (priority 6)
    (connect_pads yes (clearance 0.127))
    (min_thickness 0.1) (filled_areas_thickness no)
    (fill yes (thermal_gap 0.508) (thermal_bridge_width 0.508) (smoothing fillet) (radius 0.2))
    (polygon
      (pts
        (xy 173.55 126.55)
        (xy 173.75 126.75)
        (xy 175.3 126.75)
        (xy 175.525 126.525)
        (xy 176.25 126.525)
        (xy 176.25 127.4)
        (xy 175.225 127.4)
        (xy 175.225 127.675)
        (xy 173.25 127.675)
        (xy 173.25 125.825)
        (xy 173.55 125.825)
      )
    )
  )
  (zone (net 774) (net_name "/Power Supply/DC/DC conventers/SOM_5V_FB") (layer "F.Cu") (hatch edge 0.508)
    (priority 5)
    (connect_pads yes (clearance 0.127))
    (min_thickness 0.1) (filled_areas_thickness no)
    (fill yes (thermal_gap 0.508) (thermal_bridge_width 0.508) (smoothing fillet) (radius 0.2))
    (polygon
      (pts
        (xy 175.225 128.575)
        (xy 172.825 128.575)
        (xy 172.825 127.75)
        (xy 175.225 127.75)
      )
    )
  )
  (zone (net 251) (net_name "Net-(U48-SS)") (layer "F.Cu") (hatch edge 0.508)
    (priority 7)
    (connect_pads yes (clearance 0.127))
    (min_thickness 0.1) (filled_areas_thickness no)
    (fill yes (thermal_gap 0.508) (thermal_bridge_width 0.508) (smoothing fillet) (radius 0.2))
    (polygon
      (pts
        (xy 175.475 125.5)
        (xy 176.25 125.5)
        (xy 176.25 126.475)
        (xy 174.2 126.475)
        (xy 174.2 125.65)
        (xy 174.05 125.5)
        (xy 173.25 125.5)
        (xy 173.25 125.225)
        (xy 175.4 125.225)
      )
    )
  )
  (zone (net 253) (net_name "Net-(U48-BOOT)") (layer "F.Cu") (hatch edge 0.508)
    (priority 2)
    (connect_pads yes (clearance 0.127))
    (min_thickness 0.1) (filled_areas_thickness no)
    (fill yes (thermal_gap 0.508) (thermal_bridge_width 0.508) (smoothing fillet) (radius 0.2))
    (polygon
      (pts
        (xy 172.1 124.65)
        (xy 171.249 124.65)
        (xy 171.25 124.367)
        (xy 171.25 124.1)
        (xy 171.25 122.5)
        (xy 172.1 122.5)
      )
    )
  )
  (zone (net 366) (net_name "/Power Supply/DC/DC conventers/SW_SOM_5V") (layer "F.Cu") (hatch edge 0.508)
    (priority 1)
    (connect_pads yes (clearance 0.127))
    (min_thickness 0.1) (filled_areas_thickness no)
    (fill yes (thermal_gap 0.508) (thermal_bridge_width 0.508) (smoothing fillet) (radius 0.2))
    (polygon
      (pts
        (xy 171.15 123.4)
        (xy 171.15 124.575)
        (xy 171.25 124.725)
        (xy 172.65 124.725)
        (xy 172.65 125.325)
        (xy 171.25 125.325)
        (xy 170.15 126.45)
        (xy 168.775 126.45)
        (xy 168.775 122.875)
        (xy 170.25 122.875)
        (xy 170.6 122.5)
        (xy 171.15 122.5)
      )
    )
  )
  (zone (net 1) (net_name "GND") (layer "F.Cu") (hatch edge 0.508)
    (priority 3)
    (connect_pads yes (clearance 0.1))
    (min_thickness 0.1) (filled_areas_thickness no)
    (fill yes (thermal_gap 0.508) (thermal_bridge_width 0.508) (smoothing fillet) (radius 0.2))
    (polygon
      (pts
        (xy 172.975 126.625)
        (xy 172.775 126.825)
        (xy 172.775 128.6)
        (xy 175.3 128.6)
        (xy 175.3 127.5)
        (xy 176.3 127.5)
        (xy 176.3 124.5)
        (xy 175.5 124.5)
        (xy 175.5 123.5)
        (xy 178.46 123.505)
        (xy 178.46 126.565)
        (xy 175.575 129.45)
        (xy 173.5125 129.4525)
        (xy 172.7875 130.1775)
        (xy 167.3 130.175)
        (xy 167.3 130.775)
        (xy 165.31 130.775)
        (xy 165.3125 130.4125)
        (xy 166.275 129.45)
        (xy 166.275 128.525)
        (xy 170.475 128.525)
        (xy 170.475 126.575)
        (xy 171.4 125.65)
        (xy 172.975 125.65)
      )
    )
  )
  (zone (net 1) (net_name "GND") (layer "F.Cu") (hatch edge 0.508)
    (priority 3)
    (connect_pads yes (clearance 0.2))
    (min_thickness 0.1) (filled_areas_thickness no)
    (fill yes (thermal_gap 0.508) (thermal_bridge_width 0.508) (smoothing fillet) (radius 0.127))
    (polygon
      (pts
        (xy 83.975 119.65)
        (xy 82.125 119.65)
        (xy 82.125 117.9)
        (xy 83.975 117.9)
      )
    )
  )
  (zone (net 322) (net_name "PL_1V8") (layer "F.Cu") (hatch edge 0.508)
    (priority 2)
    (connect_pads yes (clearance 0.2))
    (min_thickness 0.1) (filled_areas_thickness no)
    (fill yes (thermal_gap 0.508) (thermal_bridge_width 0.508) (smoothing fillet) (radius 0.127))
    (polygon
      (pts
        (xy 83.875 117.85)
        (xy 82.125 117.85)
        (xy 82.125 116.35)
        (xy 83.875 116.35)
      )
    )
  )
  (zone (net 20) (net_name "PL_3V3") (layer "F.Cu") (hatch edge 0.508)
    (priority 1)
    (connect_pads yes (clearance 0.1))
    (min_thickness 0.1) (filled_areas_thickness no)
    (fill yes (thermal_gap 0.508) (thermal_bridge_width 0.508) (smoothing fillet) (radius 0.127))
    (polygon
      (pts
        (xy 85.025 119.6)
        (xy 84.075 119.6)
        (xy 84.075 116.35)
        (xy 85.025 116.35)
      )
    )
  )
  (zone (net 1) (net_name "GND") (layer "F.Cu") (hatch edge 0.508)
    (priority 4)
    (connect_pads yes (clearance 0.2))
    (min_thickness 0.2) (filled_areas_thickness no)
    (fill yes (thermal_gap 0.508) (thermal_bridge_width 0.508) (smoothing fillet) (radius 0.127))
    (polygon
      (pts
        (xy 163.385 140.9)
        (xy 169.9 140.9)
        (xy 169.9 141.9)
        (xy 167.5 141.9)
        (xy 167.4 141.8)
        (xy 163.385 141.8)
        (xy 163.385 149.075)
        (xy 179.685 149.075)
        (xy 179.685 142.35)
        (xy 181.8 140.225)
        (xy 191.885 140.225)
        (xy 191.86 152.15)
        (xy 151.49 152.05)
        (xy 151.485 140.9)
      )
    )
  )
  (zone (net 20) (net_name "PL_3V3") (layer "F.Cu") (hatch edge 0.508)
    (priority 2)
    (connect_pads yes (clearance 0.2))
    (min_thickness 0.2) (filled_areas_thickness no)
    (fill yes (thermal_gap 0.508) (thermal_bridge_width 0.508) (smoothing fillet) (radius 0.127))
    (polygon
      (pts
        (xy 169.9 142.8)
        (xy 167.4 142.8)
        (xy 166.75 143.45)
        (xy 166.75 148.8)
        (xy 163.65 148.8)
        (xy 163.65 142)
        (xy 169.9 142)
      )
    )
  )
  (zone (net 1) (net_name "GND") (layer "F.Cu") (hatch edge 0.508)
    (priority 2)
    (connect_pads yes (clearance 0.7))
    (min_thickness 0.2) (filled_areas_thickness no)
    (fill yes (thermal_gap 0.508) (thermal_bridge_width 0.508) (smoothing fillet) (radius 0.127))
    (polygon
      (pts
        (xy 133.2 138.9)
        (xy 138.35 138.9)
        (xy 138.35 152.05)
        (xy 122.95 152.04)
        (xy 122.95 149.8)
        (xy 122.95 142)
        (xy 126.15 142)
        (xy 126.15 138.35)
        (xy 132.65 138.35)
      )
    )
  )
  (zone (net 318) (net_name "SH_DOWN") (layer "F.Cu") (hatch edge 0.508)
    (priority 1)
    (connect_pads yes (clearance 0.6))
    (min_thickness 0.5) (filled_areas_thickness no)
    (fill yes (thermal_gap 0.508) (thermal_bridge_width 0.508) (smoothing fillet) (radius 0.127))
    (polygon
      (pts
        (xy 150.5 152)
        (xy 139.4 152)
        (xy 139.4 143.7)
        (xy 140.7 143.7)
        (xy 140.7 146.2)
        (xy 148 146.2)
        (xy 148 143.7)
        (xy 150.5 143.7)
      )
    )
  )
  (zone (net 1) (net_name "GND") (layer "F.Cu") (hatch edge 0.508)
    (priority 2)
    (connect_pads yes (clearance 0.2))
    (min_thickness 0.1) (filled_areas_thickness no)
    (fill yes (thermal_gap 0.508) (thermal_bridge_width 0.508) (smoothing fillet) (radius 0.127))
    (polygon
      (pts
        (xy 143.9 63.5)
        (xy 140 63.5)
        (xy 143.1 60.4)
        (xy 143.1 58.7)
        (xy 143.9 58.7)
      )
    )
  )
  (zone (net 319) (net_name "SH_UP") (layer "F.Cu") (hatch edge 0.508)
    (priority 1)
    (connect_pads yes (clearance 0.6))
    (min_thickness 0.5) (filled_areas_thickness no)
    (fill yes (thermal_gap 0.508) (thermal_bridge_width 0.508) (smoothing fillet) (radius 0.127))
    (polygon
      (pts
        (xy 173.36 51.88)
        (xy 173.36 67.08)
        (xy 170.76 67.08)
        (xy 170.76 60.98)
        (xy 157.36 60.98)
        (xy 157.31 66.98)
        (xy 155.01 66.98)
        (xy 155.06 62.28)
        (xy 152.56 59.78)
        (xy 150.36 59.78)
        (xy 150.36 56.98)
        (xy 149.86 56.48)
        (xy 143.76 56.48)
        (xy 143.16 57.08)
        (xy 143.16 59.58)
        (xy 139.36 63.38)
        (xy 139.36 70.68)
        (xy 137.86 70.68)
        (xy 135.06 70.68)
        (xy 135.06 61.98)
        (xy 124.66 61.98)
        (xy 124.66 70.83)
        (xy 115.58 70.83)
        (xy 115.56 61.68)
        (xy 105.56 61.68)
        (xy 105.56 70.78)
        (xy 98.76 70.78)
        (xy 98.76 66.28)
        (xy 96.06 63.58)
        (xy 84.86 63.58)
        (xy 83.56 64.88)
        (xy 80.96 64.88)
        (xy 80.96 51.98)
        (xy 105.56 51.98)
      )
    )
  )
  (zone (net 20) (net_name "PL_3V3") (layer "F.Cu") (hatch edge 0.508)
    (priority 4)
    (connect_pads yes (clearance 0.127))
    (min_thickness 0.254) (filled_areas_thickness no)
    (fill yes (thermal_gap 0.508) (thermal_bridge_width 0.508) (smoothing fillet) (radius 0.127))
    (polygon
      (pts
        (xy 80.3 123.55)
        (xy 88.3 123.55)
        (xy 88.3 140.7)
        (xy 83.1 140.7)
        (xy 83.1 137.85)
        (xy 85.05 137.85)
        (xy 86.35 136.55)
        (xy 86.35 129)
        (xy 87.35 128)
        (xy 87.35 127.45)
        (xy 84.9 125)
        (xy 78.375 125)
        (xy 74.8 121.45)
        (xy 74.8 92.6)
        (xy 76.25 92.6)
        (xy 78 92.6)
        (xy 80.35 92.59)
        (xy 80.35 90.6)
        (xy 82.6 90.6)
        (xy 86.4 94.4)
        (xy 86.4 96.675)
        (xy 77.625063 96.651538)
        (xy 77.05 97.225)
        (xy 77.05 120.3)
      )
    )
  )
  (zone (net 14) (net_name "/Power Supply/DC/DC conventers/DC_MAIN_BUS") (layer "F.Cu") (hatch edge 0.508)
    (connect_pads yes (clearance 0.2))
    (min_thickness 0.254) (filled_areas_thickness no)
    (fill yes (thermal_gap 0.508) (thermal_bridge_width 0.508) (smoothing fillet) (radius 0.127))
    (polygon
      (pts
        (xy 191.975 131.9)
        (xy 191.975 132.925)
        (xy 189.4625 132.53125)
        (xy 175.7375 132.51875)
        (xy 175.7 138.7)
        (xy 171.3875 138.7)
        (xy 171.375 132.925)
        (xy 171.375 125.1)
        (xy 171 125.1)
        (xy 171 123.8)
        (xy 170.85 123.8)
        (xy 170.85 122.6)
        (xy 168 122.6)
        (xy 167.8 122.4)
        (xy 165.375 122.4)
        (xy 164.8375 121.8625)
        (xy 163.175 121.85)
        (xy 163.175 120.7)
        (xy 186.8375 120.7)
        (xy 186.8625 119.9)
        (xy 192 119.9)
      )
    )
  )
  (zone (net 693) (net_name "Net-(U54-FB)") (layer "F.Cu") (hatch edge 0.508)
    (priority 1)
    (connect_pads yes (clearance 0.254))
    (min_thickness 0.254) (filled_areas_thickness no)
    (fill yes (thermal_gap 0.508) (thermal_bridge_width 0.508) (smoothing fillet) (radius 0.127))
    (polygon
      (pts
        (xy 175.8 132.075)
        (xy 174.9 132.075)
        (xy 174.9 131.2)
        (xy 174.95 131.15)
        (xy 176.7 131.15)
        (xy 176.6875 130.225)
        (xy 177.5 130.225)
        (xy 177.5 131.575)
        (xy 177.5 131.5875)
        (xy 177.5 132.5)
        (xy 175.8 132.5)
      )
    )
  )
  (zone (net 694) (net_name "Net-(U55-FB)") (layer "F.Cu") (hatch edge 0.508)
    (priority 1)
    (connect_pads yes (clearance 0.254))
    (min_thickness 0.254) (filled_areas_thickness no)
    (fill yes (thermal_gap 0.508) (thermal_bridge_width 0.508) (smoothing fillet) (radius 0.127))
    (polygon
      (pts
        (xy 184.95 132)
        (xy 184.05 132)
        (xy 184.055 130.59)
        (xy 184.635 130.01)
        (xy 186.1 130.0125)
        (xy 186.1 131.9)
        (xy 186.4 131.9)
        (xy 186.4 132.825001)
        (xy 184.95 132.825)
      )
    )
  )
  (zone (net 326) (net_name "Net-(U55-BST)") (layer "F.Cu") (hatch edge 0.508)
    (priority 4)
    (connect_pads yes (clearance 0.254))
    (min_thickness 0.254) (filled_areas_thickness no)
    (fill yes (thermal_gap 0.508) (thermal_bridge_width 0.508) (smoothing fillet) (radius 0.127))
    (polygon
      (pts
        (xy 185.102513 133.827512)
        (xy 186.1 133.827513)
        (xy 186.1 135.827513)
        (xy 185.102513 135.827513)
      )
    )
  )
  (zone (net 771) (net_name "/Power Supply/DC/DC conventers/PL_1V2_OUT") (layer "F.Cu") (hatch edge 0.508)
    (priority 5)
    (connect_pads yes (clearance 0.254))
    (min_thickness 0.254) (filled_areas_thickness no)
    (fill yes (thermal_gap 0.508) (thermal_bridge_width 0.508) (smoothing fillet) (radius 0.127))
    (polygon
      (pts
        (xy 189.349999 137.952512)
        (xy 189.350001 137.027513)
        (xy 188.002512 137.027513)
        (xy 188.002513 135.027513)
        (xy 189.402512 135.027513)
        (xy 189.402512 135.927513)
        (xy 191.602513 135.927513)
        (xy 191.602513 138)
        (xy 189.350001 138)
      )
    )
  )
  (zone (net 316) (net_name "/Power Supply/DC/DC conventers/SW_PL_1V2") (layer "F.Cu") (hatch edge 0.508)
    (priority 3)
    (connect_pads yes (clearance 0.254))
    (min_thickness 0.254) (filled_areas_thickness no)
    (fill yes (thermal_gap 0.508) (thermal_bridge_width 0.508) (smoothing fillet) (radius 0.127))
    (polygon
      (pts
        (xy 185.2 135.8)
        (xy 186.302513 135.827513)
        (xy 186.3 134.5)
        (xy 186.5 134.25)
        (xy 186.5 132.40031)
        (xy 189.098743 132.4)
        (xy 189.101257 133.400001)
        (xy 187.6 133.4)
        (xy 187.600001 137.013757)
        (xy 185.2 137)
      )
    )
  )
  (zone (net 1) (net_name "GND") (layer "F.Cu") (hatch edge 0.508)
    (priority 2)
    (connect_pads yes (clearance 0.254))
    (min_thickness 0.254) (filled_areas_thickness no)
    (fill yes (thermal_gap 0.508) (thermal_bridge_width 0.508) (smoothing fillet) (radius 0.127))
    (polygon
      (pts
        (xy 189.502513 134.927513)
        (xy 187.902512 134.927512)
        (xy 187.902512 133.827512)
        (xy 189.402514 133.827513)
        (xy 189.402512 132.927512)
        (xy 191.602513 132.927512)
        (xy 191.602513 135.827513)
        (xy 189.502513 135.827512)
      )
    )
  )
  (zone (net 1) (net_name "GND") (layer "F.Cu") (hatch edge 0.508)
    (priority 3)
    (connect_pads yes (clearance 0.254))
    (min_thickness 0.254) (filled_areas_thickness no)
    (fill yes (thermal_gap 0.508) (thermal_bridge_width 0.508) (smoothing fillet) (radius 0.127))
    (polygon
      (pts
        (xy 180.375 135.025)
        (xy 178.775 135.025)
        (xy 178.774999 133.475)
        (xy 180.275001 133.475)
        (xy 180.275 133.025)
        (xy 182.475 133.025)
        (xy 182.475 135.75)
        (xy 180.375 135.75)
      )
    )
  )
  (zone (net 325) (net_name "Net-(U54-BST)") (layer "F.Cu") (hatch edge 0.508)
    (priority 4)
    (connect_pads yes (clearance 0.254))
    (min_thickness 0.254) (filled_areas_thickness no)
    (fill yes (thermal_gap 0.508) (thermal_bridge_width 0.508) (smoothing fillet) (radius 0.127))
    (polygon
      (pts
        (xy 175.775 133.51875)
        (xy 177.3 133.5)
        (xy 177.3 134.3)
        (xy 176.8 134.8)
        (xy 176.8 135.65)
        (xy 175.775 135.65)
      )
    )
  )
  (zone (net 770) (net_name "/Power Supply/DC/DC conventers/PL_3V3_OUT") (layer "F.Cu") (hatch edge 0.508)
    (priority 6)
    (connect_pads yes (clearance 0.254))
    (min_thickness 0.254) (filled_areas_thickness no)
    (fill yes (thermal_gap 0.508) (thermal_bridge_width 0.508) (smoothing fillet) (radius 0.127))
    (polygon
      (pts
        (xy 179.375 138.05)
        (xy 179.375 137.125)
        (xy 178.875 137.125)
        (xy 178.875 135.125)
        (xy 180.275 135.125001)
        (xy 180.275 136.025)
        (xy 182.2 136.025)
        (xy 182.5 135.8)
        (xy 183.075 135.8)
        (xy 183.075 137.1)
        (xy 181.6 137.1)
        (xy 181.2 137.5)
        (xy 181.2 138.425)
        (xy 181.1125 138.425)
        (xy 179.75 138.425)
      )
    )
  )
  (zone (net 315) (net_name "/Power Supply/DC/DC conventers/SW_PL_3V3") (layer "F.Cu") (hatch edge 0.508)
    (priority 2)
    (connect_pads yes (clearance 0.254))
    (min_thickness 0.254) (filled_areas_thickness no)
    (fill yes (thermal_gap 0.508) (thermal_bridge_width 0.508) (smoothing fillet) (radius 0.127))
    (polygon
      (pts
        (xy 175.775 135.925)
        (xy 176.805 135.925)
        (xy 176.8 134.89)
        (xy 177.45 134.45)
        (xy 177.45003 132.54737)
        (xy 180.025 132.5375)
        (xy 180.025001 133.4)
        (xy 178.5875 133.4)
        (xy 177.89 137.09)
        (xy 175.775 137.125)
      )
    )
  )
  (zone (net 688) (net_name "Net-(U49-FB)") (layer "F.Cu") (hatch edge 0.508)
    (priority 1)
    (connect_pads yes (clearance 0.254))
    (min_thickness 0.254) (filled_areas_thickness no)
    (fill yes (thermal_gap 0.508) (thermal_bridge_width 0.508) (smoothing fillet) (radius 0.127))
    (polygon
      (pts
        (xy 173.3 132.6)
        (xy 172.35 132.6)
        (xy 172.35 134.05)
        (xy 171.4 134.05)
        (xy 171.4 131.7)
        (xy 173.3 131.7)
      )
    )
  )
  (zone (net 257) (net_name "Net-(U49-BST)") (layer "F.Cu") (hatch edge 0.508)
    (connect_pads yes (clearance 0.1))
    (min_thickness 0.1) (filled_areas_thickness no)
    (fill yes (thermal_gap 0.508) (thermal_bridge_width 0.508) (smoothing fillet) (radius 0.127))
    (polygon
      (pts
        (xy 170.2875 134.2)
        (xy 169.5625 134.2)
        (xy 169.55 132.95)
        (xy 168.65 132.95)
        (xy 168.65 131.85)
        (xy 169.3 131.85)
        (xy 169.3125 132.325)
        (xy 170.2875 132.325)
      )
    )
  )
  (zone (net 1) (net_name "GND") (layer "F.Cu") (hatch edge 0.508)
    (priority 9)
    (connect_pads yes (clearance 0.2))
    (min_thickness 0.2) (filled_areas_thickness no)
    (fill yes (thermal_gap 0.254) (thermal_bridge_width 0.254) (smoothing fillet) (radius 0.127))
    (polygon
      (pts
        (xy 170.3 136.7)
        (xy 171.7 136.7)
        (xy 171.7 139.275)
        (xy 169.5 139.275)
        (xy 169.5 135.3)
        (xy 170.3 135.3)
      )
    )
  )
  (zone (net 765) (net_name "/Power Supply/DC/DC conventers/PS_3V3_OUT") (layer "F.Cu") (hatch edge 0.508)
    (priority 3)
    (connect_pads yes (clearance 0.2))
    (min_thickness 0.2) (filled_areas_thickness no)
    (fill yes (thermal_gap 0.254) (thermal_bridge_width 0.254) (smoothing fillet) (radius 0.127))
    (polygon
      (pts
        (xy 169.4 139.25)
        (xy 166.975 139.25)
        (xy 166.975 137.025)
        (xy 164.975 137.025)
        (xy 164.975 135.3)
        (xy 169.4 135.3)
      )
    )
  )
  (zone (net 309) (net_name "/Power Supply/DC/DC conventers/SW_PS_3V3") (layer "F.Cu") (hatch edge 0.508)
    (priority 2)
    (connect_pads yes (clearance 0.2))
    (min_thickness 0.2) (filled_areas_thickness no)
    (fill yes (thermal_gap 0.254) (thermal_bridge_width 0.254) (smoothing fillet) (radius 0.127))
    (polygon
      (pts
        (xy 169.4 134.1)
        (xy 171.3 134.1)
        (xy 171.3 136.6)
        (xy 170.4 136.6)
        (xy 170.4 135.2)
        (xy 164.975 135.2)
        (xy 164.975 132.2)
        (xy 167.1 132.2)
        (xy 167.5 131.8)
        (xy 168.5 131.8)
        (xy 168.5 133)
        (xy 169.4 133)
      )
    )
  )
  (zone (net 15) (net_name "PS_3V3") (layer "F.Cu") (hatch edge 0.508)
    (priority 1)
    (connect_pads yes (clearance 0.127))
    (min_thickness 0.1) (filled_areas_thickness no)
    (fill yes (thermal_gap 0.254) (thermal_bridge_width 0.254) (smoothing fillet) (radius 0.127))
    (polygon
      (pts
        (xy 155.1 106)
        (xy 151.75 106)
        (xy 142.5 106)
        (xy 134.25 114.25)
        (xy 134.275 119.7)
        (xy 133.225 120.775)
        (xy 133.25 132.35)
        (xy 124.55 132.35)
        (xy 123.45 131.25)
        (xy 122.525 131.25)
        (xy 122.550353 132.925)
        (xy 124.099648 134.475001)
        (xy 124.1 141.9)
        (xy 122.825 141.9)
        (xy 122.825 144.35)
        (xy 119.8 144.35)
        (xy 119.8 127.65)
        (xy 119.8 113.17)
        (xy 121.92 111.045008)
        (xy 127.675 111.05)
        (xy 134.6 104.05)
        (xy 155.1 104.05)
      )
    )
  )
  (zone (net 18) (net_name "PS_1V2") (layer "F.Cu") (hatch edge 0.508)
    (priority 2)
    (connect_pads yes (clearance 0.254))
    (min_thickness 0.254) (filled_areas_thickness no)
    (fill yes (thermal_gap 0.508) (thermal_bridge_width 0.508) (smoothing fillet) (radius 0.127))
    (polygon
      (pts
        (xy 163.7 113.8)
        (xy 164.9 115)
        (xy 165.58 115)
        (xy 165.58 116)
        (xy 163.075 116)
        (xy 163.075 117.35)
        (xy 160.9 117.35)
        (xy 160.9 98.18)
        (xy 153.75 98.18)
        (xy 153.75 96.5)
        (xy 156.95 96.5)
        (xy 159.55 93.9)
        (xy 163.675 93.9)
      )
    )
  )
  (zone (net 15) (net_name "PS_3V3") (layer "F.Cu") (hatch edge 0.508)
    (priority 2)
    (connect_pads yes (clearance 0.1))
    (min_thickness 0.1) (filled_areas_thickness no)
    (fill yes (thermal_gap 0.254) (thermal_bridge_width 0.254) (smoothing fillet) (radius 0.127))
    (polygon
      (pts
        (xy 155.1 100.1)
        (xy 131.4 100.1)
        (xy 125.2 106.3)
        (xy 117.475 106.3)
        (xy 114.875 103.7)
        (xy 113.5875 103.7)
        (xy 113.59 101.605)
        (xy 116.5 101.6)
        (xy 119 104.1)
        (xy 123.9 104.1)
        (xy 129.5 98.5)
        (xy 155.1 98.5)
      )
    )
  )
  (zone (net 1) (net_name "GND") (layer "F.Cu") (hatch edge 0.508)
    (priority 3)
    (connect_pads yes (clearance 0.1))
    (min_thickness 0.1) (filled_areas_thickness no)
    (fill yes (thermal_gap 0.254) (thermal_bridge_width 0.254) (smoothing fillet) (radius 0.127))
    (polygon
      (pts
        (xy 189.7 124.7)
        (xy 187.9 124.7)
        (xy 187.9 123)
        (xy 189.7 123)
      )
    )
  )
  (zone (net 1) (net_name "GND") (layer "F.Cu") (hatch edge 0.508)
    (priority 1)
    (connect_pads yes (clearance 0.2))
    (min_thickness 0.2) (filled_areas_thickness no)
    (fill yes (thermal_gap 0.254) (thermal_bridge_width 0.254) (smoothing fillet) (radius 0.127))
    (polygon
      (pts
        (xy 192 119.8)
        (xy 186.95 119.8)
        (xy 186.95 115.25)
        (xy 186.95 114.35)
        (xy 184.9 112.3)
        (xy 184.9 109.5)
        (xy 192 109.5)
      )
    )
  )
  (zone (net 13) (net_name "/Power Supply/PoE/POE_12V") (layer "F.Cu") (hatch edge 0.508)
    (priority 9)
    (connect_pads yes (clearance 0.2))
    (min_thickness 0.2) (filled_areas_thickness no)
    (fill yes (thermal_gap 0.254) (thermal_bridge_width 0.254) (smoothing fillet) (radius 0.127))
    (polygon
      (pts
        (xy 186.7 123.95)
        (xy 186.975 124.23)
        (xy 186.975 126.75)
        (xy 183.15 126.75)
        (xy 183.15 119.6)
        (xy 184.2 118.55)
        (xy 184.2 116.7)
        (xy 181.8 114.3)
        (xy 176 114.3)
        (xy 175.85 114.15)
        (xy 172.6 114.15)
        (xy 172.45 114.3)
        (xy 168 114.3)
        (xy 167.6 114.7)
        (xy 165 114.7)
        (xy 164 113.7)
        (xy 164 109.1)
        (xy 170 109.1)
        (xy 173.6 112.7)
        (xy 184.9 112.7)
        (xy 186.7 114.5)
      )
    )
  )
  (zone (net 266) (net_name "/Debug and JTAG/USBB_VBUS") (layer "F.Cu") (hatch edge 0.508)
    (priority 7)
    (connect_pads yes (clearance 0.2))
    (min_thickness 0.2) (filled_areas_thickness no)
    (fill yes (thermal_gap 0.254) (thermal_bridge_width 0.254) (smoothing fillet) (radius 0.127))
    (polygon
      (pts
        (xy 155.1 112.8)
        (xy 153.3 112.8)
        (xy 153.3 111.5)
        (xy 155.1 111.5)
      )
    )
  )
  (zone (net 1) (net_name "GND") (layer "F.Cu") (hatch edge 0.508)
    (priority 4)
    (connect_pads yes (clearance 0.2))
    (min_thickness 0.1) (filled_areas_thickness no)
    (fill yes (thermal_gap 0.254) (thermal_bridge_width 0.254) (smoothing fillet) (radius 0.127))
    (polygon
      (pts
        (xy 152.5 63.25)
        (xy 151.3 63.25)
        (xy 149.5 61.4)
        (xy 149.5 60.2)
        (xy 149.7 60)
        (xy 150.4 60)
        (xy 150.66 60.26)
        (xy 151.46 60.26)
        (xy 151.725 60)
        (xy 152.5 60)
      )
    )
  )
  (zone (net 265) (net_name "/Debug and JTAG/USBC_VBUS") (layer "F.Cu") (hatch edge 0.508)
    (priority 3)
    (connect_pads yes (clearance 0.2))
    (min_thickness 0.1) (filled_areas_thickness no)
    (fill yes (thermal_gap 0.254) (thermal_bridge_width 0.254) (smoothing fillet) (radius 0.127))
    (polygon
      (pts
        (xy 149.45 61.475)
        (xy 152.425 64.45)
        (xy 152.425 65.45)
        (xy 149.425 65.45)
        (xy 149.425 64.85)
        (xy 147.7 63.125)
        (xy 147.7 61)
        (xy 148.275 61)
        (xy 148.275 60.15)
        (xy 148.775 60.15)
        (xy 148.9 60.025)
        (xy 149.3 60.025)
        (xy 149.45 60.175)
      )
    )
  )
  (zone (net 228) (net_name "/Power Supply/Supply ORing/PD_VBUS") (layer "F.Cu") (hatch edge 0.508)
    (priority 4)
    (connect_pads yes (clearance 0.1))
    (min_thickness 0.1) (filled_areas_thickness no)
    (fill yes (thermal_gap 0.254) (thermal_bridge_width 0.254) (smoothing fillet) (radius 0.127))
    (polygon
      (pts
        (xy 148.325 65.45)
        (xy 147.325 66.45)
        (xy 146.5 66.45)
        (xy 146.5 64.35)
        (xy 144.55 64.35)
        (xy 144.55 66.55)
        (xy 143.625 66.55)
        (xy 142.525 67.65)
        (xy 140.85 67.65)
        (xy 140.85 63.825)
        (xy 148.225 63.825)
        (xy 149.35 64.95)
        (xy 149.35 65.45)
      )
    )
  )
  (zone (net 8) (net_name "SOM_5V0") (layer "F.Cu") (hatch edge 0.508)
    (priority 3)
    (connect_pads yes (clearance 0.2))
    (min_thickness 0.1) (filled_areas_thickness no)
    (fill yes (thermal_gap 0.254) (thermal_bridge_width 0.254) (smoothing fillet) (radius 0.3))
    (polygon
      (pts
        (xy 155.12 103.725)
        (xy 134.27 103.7125)
        (xy 127.23 110.77)
        (xy 121.6575 110.7475)
        (xy 119.8025 112.5925)
        (xy 94.92 112.67)
        (xy 94.9 100.7)
        (xy 94.05 99.85)
        (xy 93.62 99.85)
        (xy 93.62 98.59)
        (xy 91.97 98.59)
        (xy 91.97 99.73)
        (xy 91.1 99.73)
        (xy 91.1 98.59)
        (xy 91.07 98.59)
        (xy 90.135 98.59)
        (xy 89.72 98.59)
        (xy 88.978699 99.329988)
        (xy 88.95 102.7)
        (xy 88.4 102.7)
        (xy 87.1 102.7)
        (xy 87.1 100.35)
        (xy 86.6 99.85)
        (xy 86.6 94.25)
        (xy 82.5 90.175)
        (xy 81.35 90.175)
        (xy 81.35 89.625)
        (xy 80.325 88.6)
        (xy 79.575 88.6)
        (xy 79.575 87.95)
        (xy 82.35 87.95)
        (xy 83.65 89.25)
        (xy 88.615557 94.176723)
        (xy 96 94.2)
        (xy 96 97.5)
        (xy 96.7 97.5)
        (xy 97.875 97.5)
        (xy 97.875 99.5)
        (xy 97.875 106.6)
        (xy 113.590557 106.601723)
        (xy 113.590557 103.901723)
        (xy 114.6 103.905)
        (xy 117.3 106.605)
        (xy 125.4 106.6)
        (xy 131.7 100.45)
        (xy 155.1 100.45)
      )
    )
  )
  (zone (net 18) (net_name "PS_1V2") (layer "F.Cu") (hatch edge 0.508)
    (connect_pads (clearance 0.1))
    (min_thickness 0.1) (filled_areas_thickness no)
    (fill yes (thermal_gap 0.254) (thermal_bridge_width 0.254) (smoothing fillet) (radius 0.127))
    (polygon
      (pts
        (xy 133.2 96.5)
        (xy 155.1 96.5)
        (xy 155.1 97.2)
        (xy 155.1 98.18)
        (xy 129.57 98.18)
        (xy 129.57 95.1)
        (xy 131.8 95.1)
      )
    )
  )
  (zone (net 10) (net_name "/Power Supply/PoE/VSS_POE_IN") (layer "F.Cu") (hatch edge 0.508)
    (priority 1)
    (connect_pads yes (clearance 0.254))
    (min_thickness 0.254) (filled_areas_thickness no)
    (fill yes (thermal_gap 0.508) (thermal_bridge_width 0.508) (smoothing fillet) (radius 0.127))
    (polygon
      (pts
        (xy 182.3 74.1)
        (xy 186.3 74.1)
        (xy 186.3 73)
        (xy 188.1 73)
        (xy 188.1 75.6)
        (xy 187.2 75.6)
        (xy 187.2 79.5)
        (xy 191.7 79.5)
        (xy 191.7 82.6)
        (xy 187 82.6)
        (xy 187 80.6)
        (xy 186.2 80.6)
        (xy 186.2 79.3)
        (xy 186.2 77.4)
        (xy 182.6 77.4)
        (xy 182.6 75.8)
        (xy 181.6 74.8)
        (xy 179.6 74.8)
        (xy 179.6 73.5)
        (xy 181.7 73.5)
      )
    )
  )
  (zone (net 9) (net_name "/Power Supply/PoE/VDD_POE_IN") (layer "F.Cu") (hatch edge 0.508)
    (connect_pads yes (clearance 0.254))
    (min_thickness 0.254) (filled_areas_thickness no)
    (fill yes (thermal_gap 0.508) (thermal_bridge_width 0.508) (smoothing fillet) (radius 0.127))
    (polygon
      (pts
        (xy 192 79.3)
        (xy 189.9 79.3)
        (xy 189.9 75.6)
        (xy 188.2 75.6)
        (xy 188.2 72.6)
        (xy 186 72.6)
        (xy 186 73.4)
        (xy 183 73.4)
        (xy 181.6 72)
        (xy 179.6 72)
        (xy 179.6 70.5)
        (xy 192 70.5)
      )
    )
  )
  (zone (net 237) (net_name "/Ethernet/POE_VC4") (layer "F.Cu") (hatch edge 0.508)
    (priority 3)
    (connect_pads yes (clearance 0.254))
    (min_thickness 0.254) (filled_areas_thickness no)
    (fill yes (thermal_gap 0.508) (thermal_bridge_width 0.508) (smoothing fillet) (radius 0.127))
    (polygon
      (pts
        (xy 176 77.9)
        (xy 173.8 77.9)
        (xy 173.2 77.4)
        (xy 173.2 76.3)
        (xy 173.6 75.9)
        (xy 176 75.9)
      )
    )
  )
  (zone (net 238) (net_name "/Ethernet/POE_VC3") (layer "F.Cu") (hatch edge 0.508)
    (priority 3)
    (connect_pads yes (clearance 0.254))
    (min_thickness 0.254) (filled_areas_thickness no)
    (fill yes (thermal_gap 0.508) (thermal_bridge_width 0.508) (smoothing fillet) (radius 0.127))
    (polygon
      (pts
        (xy 176 75.4)
        (xy 173.8 75.4)
        (xy 173.2 74.9)
        (xy 173.2 73.8)
        (xy 174.1 72.9)
        (xy 176 72.9)
      )
    )
  )
  (zone (net 235) (net_name "/Ethernet/POE_VC2") (layer "F.Cu") (hatch edge 0.508)
    (priority 3)
    (connect_pads yes (clearance 0.254))
    (min_thickness 0.254) (filled_areas_thickness no)
    (fill yes (thermal_gap 0.508) (thermal_bridge_width 0.508) (smoothing fillet) (radius 0.127))
    (polygon
      (pts
        (xy 176 72.6)
        (xy 173.8 72.6)
        (xy 173.2 72)
        (xy 173.2 70.9)
        (xy 174 70.1)
        (xy 176 70.1)
      )
    )
  )
  (zone (net 14) (net_name "/Power Supply/DC/DC conventers/DC_MAIN_BUS") (layer "F.Cu") (hatch edge 0.508)
    (priority 3)
    (connect_pads yes (clearance 0.254))
    (min_thickness 0.254) (filled_areas_thickness no)
    (fill yes (thermal_gap 0.508) (thermal_bridge_width 0.508) (smoothing fillet) (radius 0.127))
    (polygon
      (pts
        (xy 188.9 66.5)
        (xy 189.8 67.4)
        (xy 189.8 68.1)
        (xy 186.9 68.1)
        (xy 186.9 63)
        (xy 188.9 63)
      )
    )
  )
  (zone (net 1) (net_name "GND") (layer "F.Cu") (hatch edge 0.508)
    (connect_pads yes (clearance 0.254))
    (min_thickness 0.254) (filled_areas_thickness no)
    (fill yes (thermal_gap 0.508) (thermal_bridge_width 0.508) (smoothing fillet) (radius 0.127))
    (polygon
      (pts
        (xy 192.000324 62.1)
        (xy 186.9 62.1)
        (xy 186.9 61.3)
        (xy 187.700324 61.3)
        (xy 187.7 59)
        (xy 183.599838 59)
        (xy 183.6 61.5)
        (xy 182.3 62.8)
        (xy 177 62.8)
        (xy 177 52)
        (xy 192 52)
      )
    )
  )
  (zone (net 22) (net_name "/Power Supply/DC Input/DC_IN") (layer "F.Cu") (hatch edge 0.508)
    (priority 1)
    (connect_pads yes (clearance 0.254))
    (min_thickness 0.254) (filled_areas_thickness no)
    (fill yes (thermal_gap 0.508) (thermal_bridge_width 0.508) (smoothing fillet) (radius 0.127))
    (polygon
      (pts
        (xy 190.05 64.868425)
        (xy 188.899953 64.870246)
        (xy 188.9 63)
        (xy 187 63.000951)
        (xy 186.999958 64.873257)
        (xy 185.9 64.875)
        (xy 185.9 68.5)
        (xy 186.1 68.7)
        (xy 186.1 69.5)
        (xy 184.9 69.5)
        (xy 184.5 69.1)
        (xy 184.5 66.875)
        (xy 177 66.875)
        (xy 177 62.925)
        (xy 182.4 62.92721)
        (xy 183.775 61.55)
        (xy 183.774908 59.125)
        (xy 187.575093 59.125)
        (xy 187.575 61.1)
        (xy 186.7 61.1)
        (xy 186.7 62.175)
        (xy 190.05 62.175)
      )
    )
  )
  (zone (net 11) (net_name "GNDD") (layer "F.Cu") (hatch edge 0.508)
    (priority 2)
    (connect_pads yes (clearance 0.5))
    (min_thickness 0.1) (filled_areas_thickness no)
    (fill yes (thermal_gap 0.508) (thermal_bridge_width 0.508) (smoothing fillet) (radius 0.127))
    (polygon
      (pts
        (xy 191.7 89.1)
        (xy 186.1 89.1)
        (xy 186.1 92.1)
        (xy 177.7 92.1)
        (xy 177.7 89.2)
        (xy 183.7 89.2)
        (xy 185.75 87.169048)
        (xy 185.75 82.55)
        (xy 185.1 81.9)
        (xy 162.5 81.9)
        (xy 162.5 79.1)
        (xy 163.9 77.7)
        (xy 186.1 77.7)
        (xy 186.1 80.9)
        (xy 186.8 80.9)
        (xy 186.8 82.8)
        (xy 191.7 82.8)
      )
    )
  )
  (zone (net 9) (net_name "/Power Supply/PoE/VDD_POE_IN") (layer "F.Cu") (hatch edge 0.508)
    (connect_pads yes (clearance 0.254))
    (min_thickness 0.1) (filled_areas_thickness no)
    (fill yes (thermal_gap 0.508) (thermal_bridge_width 0.508) (smoothing fillet) (radius 0.127))
    (polygon
      (pts
        (xy 185.55 86.873287)
        (xy 183.7 88.7)
        (xy 177.4 88.7)
        (xy 177.4 92.1)
        (xy 167.6 92.1)
        (xy 162.5 87)
        (xy 162.5 84.2)
        (xy 185.55 84.226714)
      )
    )
  )
  (zone (net 14) (net_name "/Power Supply/DC/DC conventers/DC_MAIN_BUS") (layer "F.Cu") (hatch edge 0.508)
    (priority 5)
    (connect_pads yes (clearance 0.2))
    (min_thickness 0.2) (filled_areas_thickness no)
    (fill yes (thermal_gap 0.508) (thermal_bridge_width 0.508) (smoothing fillet) (radius 0.127))
    (polygon
      (pts
        (xy 146.5 66.1)
        (xy 146.5 66.65)
        (xy 147.55 66.65)
        (xy 147.55 66.95)
        (xy 149.25 66.95)
        (xy 150.825 68.55)
        (xy 150.825 69.5)
        (xy 144.525 69.50625)
        (xy 144.5 64.45)
        (xy 146.5 64.45)
      )
    )
  )
  (zone (net 21) (net_name "PL_1V2") (layer "F.Cu") (hatch edge 0.508)
    (priority 1)
    (connect_pads yes (clearance 0.127))
    (min_thickness 0.254) (filled_areas_thickness no)
    (fill yes (thermal_gap 0.508) (thermal_bridge_width 0.508) (smoothing fillet) (radius 0.1))
    (polygon
      (pts
        (xy 90.025 138.375)
        (xy 90.35 138.7)
        (xy 93.77 138.705)
        (xy 93.77 140.655)
        (xy 88.825 140.65)
        (xy 88.825 138.6625)
        (xy 88.825 135.625)
        (xy 89.3 135.625)
        (xy 89.3 136.6)
        (xy 90.025 137.325)
      )
    )
  )
  (zone (net 313) (net_name "/Debug and JTAG/USB_VBUS") (layer "F.Cu") (hatch edge 0.508)
    (priority 8)
    (connect_pads yes (clearance 0.2))
    (min_thickness 0.2) (filled_areas_thickness no)
    (fill yes (thermal_gap 0.254) (thermal_bridge_width 0.254) (smoothing fillet) (radius 0.127))
    (polygon
      (pts
        (xy 153.25 107.8)
        (xy 153.85 108.4)
        (xy 155.15 108.4)
        (xy 155.15 110.35)
        (xy 153.5 110.35)
        (xy 152.8 109.65)
        (xy 150.95 109.65)
        (xy 150.95 109.25)
        (xy 153.1 109.25)
        (xy 153.25 109.1)
        (xy 153.25 108.75)
        (xy 152.85 108.35)
        (xy 152.85 106.55)
        (xy 151.6 106.55)
        (xy 151.45 106.7)
        (xy 151.45 107.2)
        (xy 150.45 107.2)
        (xy 150.45 106.1)
        (xy 153.25 106.1)
      )
    )
  )
  (zone (net 15) (net_name "PS_3V3") (layer "F.Cu") (hatch edge 0.508)
    (priority 4)
    (connect_pads yes (clearance 0.2))
    (min_thickness 0.2) (filled_areas_thickness no)
    (fill yes (thermal_gap 0.254) (thermal_bridge_width 0.254) (smoothing fillet) (radius 0.127))
    (polygon
      (pts
        (xy 164.475 135.9)
        (xy 164.9 136.325)
        (xy 164.9 137.075)
        (xy 166.925 137.075)
        (xy 166.925 137.995)
        (xy 166.4 138.52)
        (xy 166.4 139.2)
        (xy 163.175 139.2)
        (xy 163.175 135.225)
        (xy 164.475 135.225)
      )
    )
  )
  (zone (net 21) (net_name "PL_1V2") (layer "F.Cu") (hatch edge 0.508)
    (priority 5)
    (connect_pads yes (clearance 0.254))
    (min_thickness 0.254) (filled_areas_thickness no)
    (fill yes (thermal_gap 0.508) (thermal_bridge_width 0.508) (smoothing fillet) (radius 0.127))
    (polygon
      (pts
        (xy 191.6 139.65)
        (xy 190.7 139.65)
        (xy 190.2 140.15)
        (xy 187.75 140.15)
        (xy 187.75 138.4)
        (xy 190.45 138.4)
        (xy 190.85 138.8)
        (xy 191.6 138.8)
      )
    )
  )
  (zone (net 1) (net_name "GND") (layer "F.Cu") (hatch edge 0.508)
    (connect_pads yes (clearance 0.127))
    (min_thickness 0.254) (filled_areas_thickness no)
    (fill yes (thermal_gap 0.508) (thermal_bridge_width 0.508))
    (polygon
      (pts
        (xy 93.78 144.46)
        (xy 88.8 144.46)
        (xy 88.8125 140.76875)
        (xy 93.7875 140.77125)
      )
    )
  )
  (zone (net 1) (net_name "GND") (layer "F.Cu") (hatch edge 0.508)
    (priority 5)
    (connect_pads yes (clearance 0.254))
    (min_thickness 0.2) (filled_areas_thickness no)
    (fill yes (thermal_gap 0.254) (thermal_bridge_width 0.254) (smoothing fillet) (radius 0.127))
    (polygon
      (pts
        (xy 86.4 99.8)
        (xy 87 100.4)
        (xy 87 102.7)
        (xy 83.95 102.7)
        (xy 83.175 101.9)
        (xy 83.175 96.8)
        (xy 86.4 96.8)
      )
    )
  )
  (zone (net 8) (net_name "SOM_5V0") (layer "F.Cu") (hatch edge 0.508)
    (priority 4)
    (connect_pads yes (clearance 0.1))
    (min_thickness 0.1) (filled_areas_thickness no)
    (fill yes (thermal_gap 0.508) (thermal_bridge_width 0.508) (smoothing fillet) (radius 0.2))
    (polygon
      (pts
        (xy 165.125 127.85)
        (xy 163.175 127.85)
        (xy 163.175 122.1)
        (xy 164.65 122.1)
        (xy 165.125 122.575)
      )
    )
  )
  (zone (net 17) (net_name "PS_1V8") (layer "F.Cu") (hatch edge 0.508)
    (priority 2)
    (connect_pads yes (clearance 0.254))
    (min_thickness 0.254) (filled_areas_thickness no)
    (fill yes (thermal_gap 0.508) (thermal_bridge_width 0.508) (smoothing fillet) (radius 0.127))
    (polygon
      (pts
        (xy 176 114.6)
        (xy 176 115.95)
        (xy 175.6 116.35)
        (xy 175.25 116.35)
        (xy 175.25 117.25)
        (xy 174.5 117.25)
        (xy 174.5 116.4)
        (xy 174.1 116)
        (xy 174.1 115.55)
        (xy 173.85 115.3)
        (xy 172.45 115.3)
        (xy 172.45 114.5)
        (xy 172.65 114.3)
        (xy 175.7 114.3)
      )
    )
  )
  (zone (net 1) (net_name "GND") (layer "F.Cu") (hatch edge 0.508)
    (priority 7)
    (connect_pads yes (clearance 0.2))
    (min_thickness 0.2) (filled_areas_thickness no)
    (fill yes (thermal_gap 0.254) (thermal_bridge_width 0.254) (smoothing fillet) (radius 0.127))
    (polygon
      (pts
        (xy 150.25 107.25)
        (xy 150.45 107.45)
        (xy 152.6 107.45)
        (xy 152.6 108.2)
        (xy 150.4 108.2)
        (xy 150.4 109.35)
        (xy 150.85 109.8)
        (xy 150.85 110.4)
        (xy 151 110.55)
        (xy 152.65 110.55)
        (xy 152.65 111.25)
        (xy 150.25 111.25)
        (xy 149.95 110.95)
        (xy 149.95 110.3)
        (xy 149.75 110.1)
        (xy 149.15 110.1)
        (xy 148.95 109.9)
        (xy 148.95 106.1)
        (xy 150.25 106.1)
      )
    )
  )
  (zone (net 20) (net_name "PL_3V3") (layer "F.Cu") (hatch edge 0.508)
    (priority 7)
    (connect_pads yes (clearance 0.254))
    (min_thickness 0.254) (filled_areas_thickness no)
    (fill yes (thermal_gap 0.508) (thermal_bridge_width 0.508) (smoothing fillet) (radius 0.127))
    (polygon
      (pts
        (xy 184.15 138.25)
        (xy 184.15 139.15)
        (xy 183.45 139.85)
        (xy 181.8 139.85)
        (xy 181.8 137.35)
        (xy 183.25 137.35)
      )
    )
  )
  (zone (net 9) (net_name "/Power Supply/PoE/VDD_POE_IN") (layer "F.Cu") (hatch edge 0.508)
    (connect_pads yes (clearance 0.2))
    (min_thickness 0.254) (filled_areas_thickness no)
    (fill yes (thermal_gap 0.508) (thermal_bridge_width 0.508) (smoothing fillet) (radius 0.127))
    (polygon
      (pts
        (xy 181.7 77.3)
        (xy 178.3 77.3)
        (xy 178.3 75.9)
        (xy 181.7 75.9)
      )
    )
  )
  (zone (net 265) (net_name "/Debug and JTAG/USBC_VBUS") (layer "F.Cu") (hatch edge 0.508)
    (priority 7)
    (connect_pads yes (clearance 0.2))
    (min_thickness 0.2) (filled_areas_thickness no)
    (fill yes (thermal_gap 0.254) (thermal_bridge_width 0.254) (smoothing fillet) (radius 0.127))
    (polygon
      (pts
        (xy 155.1 107.45)
        (xy 153.4 107.45)
        (xy 153.4 106.15)
        (xy 155.1 106.15)
      )
    )
  )
  (zone (net 306) (net_name "USB_5V") (layer "F.Cu") (hatch edge 0.508)
    (priority 3)
    (connect_pads yes (clearance 0.1))
    (min_thickness 0.254) (filled_areas_thickness no)
    (fill yes (thermal_gap 0.508) (thermal_bridge_width 0.508) (smoothing fillet) (radius 0.127))
    (polygon
      (pts
        (xy 150.725 78.475)
        (xy 150.725 78.85)
        (xy 150.575 79)
        (xy 145.975 79)
        (xy 145.85 78.875)
        (xy 145.85 78.4)
        (xy 145.975 78.275)
        (xy 150.525 78.275)
      )
    )
  )
  (zone (net 0) (net_name "") (layers "F.Cu" "In1.Cu" "In2.Cu" "In3.Cu" "In4.Cu" "In5.Cu" "In6.Cu" "B.Cu") (hatch edge 0.508)
    (connect_pads (clearance 0))
    (min_thickness 0.254) (filled_areas_thickness no)
    (keepout (tracks allowed) (vias allowed) (pads allowed) (copperpour not_allowed) (footprints allowed))
    (fill (thermal_gap 0.508) (thermal_bridge_width 0.508))
    (polygon
      (pts
        (xy 172.9 68.11)
        (xy 174.35 68.11)
        (xy 175.825 69.55)
        (xy 175.825 69.995)
        (xy 170.568 69.9745)
        (xy 170.56 69.98)
        (xy 168.79 68.22)
        (xy 157.625 68.22)
        (xy 157 67.58)
        (xy 157 64.87)
        (xy 157.75 64.125)
        (xy 168.92 64.12)
      )
    )
  )
  (zone (net 0) (net_name "") (layers "F.Cu" "In1.Cu" "In3.Cu" "In5.Cu" "In6.Cu") (hatch edge 0.508)
    (connect_pads yes (clearance 0))
    (min_thickness 0.1) (filled_areas_thickness no)
    (keepout (tracks allowed) (vias allowed) (pads allowed) (copperpour not_allowed) (footprints allowed))
    (fill (thermal_gap 0.254) (thermal_bridge_width 0.254))
    (polygon
      (pts
        (xy 134.292657 118.377047)
        (xy 134.333913 118.383167)
        (xy 134.37437 118.393301)
        (xy 134.41364 118.407352)
        (xy 134.451343 118.425184)
        (xy 134.487117 118.446626)
        (xy 134.520617 118.471471)
        (xy 134.55152 118.49948)
        (xy 134.579529 118.530383)
        (xy 134.604374 118.563882)
        (xy 134.625816 118.599657)
        (xy 134.643647 118.63736)
        (xy 134.657699 118.67663)
        (xy 134.667833 118.717087)
        (xy 134.673953 118.758343)
        (xy 134.676 118.8)
        (xy 134.675803 118.804)
        (xy 134.676 118.804)
        (xy 134.676 119.373447)
        (xy 134.676648 119.38664)
        (xy 134.674601 119.428296)
        (xy 134.668481 119.469553)
        (xy 134.658347 119.51001)
        (xy 134.644296 119.54928)
        (xy 134.626464 119.586982)
        (xy 134.605022 119.622757)
        (xy 134.580177 119.656257)
        (xy 134.552168 119.68716)
        (xy 134.521266 119.715169)
        (xy 134.487765 119.740015)
        (xy 134.451991 119.761455)
        (xy 134.414287 119.779288)
        (xy 134.375018 119.793339)
        (xy 134.334561 119.803472)
        (xy 134.293305 119.809592)
        (xy 134.251648 119.81164)
        (xy 134.209991 119.809593)
        (xy 134.168735 119.803473)
        (xy 134.128278 119.793339)
        (xy 134.089008 119.779288)
        (xy 134.051305 119.761456)
        (xy 134.015531 119.740014)
        (xy 133.982032 119.715169)
        (xy 133.951128 119.68716)
        (xy 133.923119 119.656256)
        (xy 133.898274 119.622756)
        (xy 133.876832 119.586983)
        (xy 133.859 119.54928)
        (xy 133.844949 119.51001)
        (xy 133.834815 119.469553)
        (xy 133.828695 119.428297)
        (xy 133.826648 119.38664)
        (xy 133.828068 119.357747)
        (xy 133.828927 118.847587)
        (xy 133.828047 118.841657)
        (xy 133.826 118.8)
        (xy 133.828047 118.758342)
        (xy 133.834166 118.717087)
        (xy 133.844301 118.67663)
        (xy 133.858352 118.63736)
        (xy 133.876183 118.599657)
        (xy 133.897626 118.563883)
        (xy 133.922471 118.530383)
        (xy 133.95048 118.49948)
        (xy 133.981383 118.471471)
        (xy 134.014883 118.446626)
        (xy 134.050657 118.425183)
        (xy 134.08836 118.407352)
        (xy 134.12763 118.393301)
        (xy 134.168087 118.383166)
        (xy 134.209343 118.377046)
        (xy 134.251 118.375)
      )
    )
  )
  (zone (net 0) (net_name "") (layer "In1.Cu") (hatch edge 0.508)
    (connect_pads yes (clearance 0))
    (min_thickness 0.1) (filled_areas_thickness no)
    (keepout (tracks allowed) (vias allowed) (pads allowed) (copperpour not_allowed) (footprints allowed))
    (fill (thermal_gap 0.254) (thermal_bridge_width 0.254))
    (polygon
      (pts
        (xy 98.518977 116.94)
        (xy 96.918977 116.94)
        (xy 96.918977 116.265)
        (xy 98.518977 116.265)
      )
    )
  )
  (zone (net 0) (net_name "") (layer "In1.Cu") (hatch edge 0.508)
    (connect_pads no (clearance 0))
    (min_thickness 0.5) (filled_areas_thickness no)
    (keepout (tracks allowed) (vias allowed) (pads allowed) (copperpour not_allowed) (footprints allowed))
    (fill (thermal_gap 0.508) (thermal_bridge_width 0.508))
    (polygon
      (pts
        (xy 93.025 74.55)
        (xy 91.475 74.55)
        (xy 91.475 71.075)
        (xy 93.025 71.075)
      )
    )
  )
  (zone (net 1) (net_name "GND") (layer "In1.Cu") (hatch edge 0.508)
    (connect_pads yes (clearance 0.131))
    (min_thickness 0.1) (filled_areas_thickness no)
    (fill yes (thermal_gap 0.254) (thermal_bridge_width 0.254) (smoothing fillet) (radius 0.45))
    (polygon
      (pts
        (xy 192 152)
        (xy 74 152)
        (xy 74 52)
        (xy 192 52)
      )
    )
  )
  (zone (net 0) (net_name "") (layer "In1.Cu") (hatch edge 0.508)
    (connect_pads yes (clearance 0))
    (min_thickness 0.1) (filled_areas_thickness no)
    (keepout (tracks allowed) (vias allowed) (pads allowed) (copperpour not_allowed) (footprints allowed))
    (fill (thermal_gap 0.254) (thermal_bridge_width 0.254))
    (polygon
      (pts
        (xy 88.025 72.25)
        (xy 86.175 72.25)
        (xy 86.175 70.375)
        (xy 88.025 70.375)
      )
    )
  )
  (zone (net 0) (net_name "") (layer "In1.Cu") (hatch edge 0.508)
    (connect_pads yes (clearance 0))
    (min_thickness 0.1) (filled_areas_thickness no)
    (keepout (tracks allowed) (vias allowed) (pads allowed) (copperpour not_allowed) (footprints allowed))
    (fill (thermal_gap 0.254) (thermal_bridge_width 0.254))
    (polygon
      (pts
        (xy 145.025 143.175)
        (xy 143.675 143.175)
        (xy 143.675 141.05)
        (xy 145.025 141.05)
      )
    )
  )
  (zone (net 0) (net_name "") (layer "In1.Cu") (hatch edge 0.508)
    (connect_pads no (clearance 0))
    (min_thickness 0.5) (filled_areas_thickness no)
    (keepout (tracks allowed) (vias allowed) (pads allowed) (copperpour not_allowed) (footprints allowed))
    (fill (thermal_gap 0.508) (thermal_bridge_width 0.508))
    (polygon
      (pts
        (xy 98.52 116.035)
        (xy 96.925 116.03)
        (xy 96.925 115.36)
        (xy 98.52 115.365)
      )
    )
  )
  (zone (net 0) (net_name "") (layer "In1.Cu") (hatch edge 0.508)
    (connect_pads yes (clearance 0))
    (min_thickness 0.1) (filled_areas_thickness no)
    (keepout (tracks allowed) (vias allowed) (pads allowed) (copperpour not_allowed) (footprints allowed))
    (fill (thermal_gap 0.254) (thermal_bridge_width 0.254))
    (polygon
      (pts
        (xy 147.375 63.025)
        (xy 146 63.025)
        (xy 146 60.825)
        (xy 147.375 60.825)
      )
    )
  )
  (zone (net 0) (net_name "") (layer "In1.Cu") (hatch edge 0.508)
    (connect_pads yes (clearance 0))
    (min_thickness 0.1) (filled_areas_thickness no)
    (keepout (tracks allowed) (vias allowed) (pads allowed) (copperpour not_allowed) (footprints allowed))
    (fill (thermal_gap 0.254) (thermal_bridge_width 0.254))
    (polygon
      (pts
        (xy 85.85 72.25)
        (xy 84 72.25)
        (xy 84 72.225)
        (xy 84 72.2)
        (xy 84 70.4)
        (xy 85.85 70.4)
      )
    )
  )
  (zone (net 0) (net_name "") (layer "In1.Cu") (hatch edge 0.508)
    (connect_pads yes (clearance 0))
    (min_thickness 0.1) (filled_areas_thickness no)
    (keepout (tracks allowed) (vias allowed) (pads allowed) (copperpour not_allowed) (footprints allowed))
    (fill (thermal_gap 0.254) (thermal_bridge_width 0.254))
    (polygon
      (pts
        (xy 112.075 76.075)
        (xy 110.225 76.075)
        (xy 110.225 74.225)
        (xy 112.075 74.225)
      )
    )
  )
  (zone (net 0) (net_name "") (layer "In1.Cu") (hatch edge 0.508)
    (connect_pads no (clearance 0))
    (min_thickness 0.5) (filled_areas_thickness no)
    (keepout (tracks allowed) (vias allowed) (pads allowed) (copperpour not_allowed) (footprints allowed))
    (fill (thermal_gap 0.508) (thermal_bridge_width 0.508))
    (polygon
      (pts
        (xy 111.35 122.025)
        (xy 110.65 122.025)
        (xy 110.65 120.575)
        (xy 111.35 120.575)
      )
    )
  )
  (zone (net 0) (net_name "") (layer "In1.Cu") (hatch edge 0.508)
    (connect_pads no (clearance 0))
    (min_thickness 0.5) (filled_areas_thickness no)
    (keepout (tracks allowed) (vias allowed) (pads allowed) (copperpour not_allowed) (footprints allowed))
    (fill (thermal_gap 0.508) (thermal_bridge_width 0.508))
    (polygon
      (pts
        (xy 110.375 122.375)
        (xy 109.225 122.375)
        (xy 109.225 120.225)
        (xy 110.375 120.225)
      )
    )
  )
  (zone (net 0) (net_name "") (layers "In1.Cu" "In2.Cu") (hatch edge 0.508)
    (connect_pads no (clearance 0))
    (min_thickness 0.5) (filled_areas_thickness no)
    (keepout (tracks allowed) (vias allowed) (pads allowed) (copperpour not_allowed) (footprints allowed))
    (fill (thermal_gap 0.508) (thermal_bridge_width 0.508))
    (polygon
      (pts
        (xy 103.1075 105.1225)
        (xy 98.6325 105.1175)
        (xy 98.63 102.98)
        (xy 103.11 102.985)
      )
    )
  )
  (zone (net 0) (net_name "") (layers "In1.Cu" "In2.Cu") (hatch edge 0.508)
    (connect_pads yes (clearance 0))
    (min_thickness 0.1) (filled_areas_thickness no)
    (keepout (tracks allowed) (vias allowed) (pads allowed) (copperpour not_allowed) (footprints allowed))
    (fill (thermal_gap 0.254) (thermal_bridge_width 0.254))
    (polygon
      (pts
        (xy 125.975 93.825)
        (xy 124.125 93.825)
        (xy 124.125 91.975)
        (xy 125.975 91.975)
      )
    )
  )
  (zone (net 0) (net_name "") (layers "In1.Cu" "In2.Cu") (hatch edge 0.508)
    (connect_pads no (clearance 0))
    (min_thickness 0.5) (filled_areas_thickness no)
    (keepout (tracks allowed) (vias allowed) (pads allowed) (copperpour not_allowed) (footprints allowed))
    (fill (thermal_gap 0.508) (thermal_bridge_width 0.508))
    (polygon
      (pts
        (xy 111.175 100.26)
        (xy 110.485 100.26)
        (xy 110.49 98.175)
        (xy 111.18 98.175)
      )
    )
  )
  (zone (net 0) (net_name "") (layers "In1.Cu" "In2.Cu") (hatch edge 0.508)
    (connect_pads no (clearance 0))
    (min_thickness 0.5) (filled_areas_thickness no)
    (keepout (tracks allowed) (vias allowed) (pads allowed) (copperpour not_allowed) (footprints allowed))
    (fill (thermal_gap 0.508) (thermal_bridge_width 0.508))
    (polygon
      (pts
        (xy 101.84 97.14)
        (xy 99.62 97.145)
        (xy 99.62 95.97)
        (xy 101.84 95.97)
      )
    )
  )
  (zone (net 0) (net_name "") (layers "In1.Cu" "In2.Cu") (hatch edge 0.508)
    (connect_pads yes (clearance 0))
    (min_thickness 0.1) (filled_areas_thickness no)
    (keepout (tracks allowed) (vias allowed) (pads allowed) (copperpour not_allowed) (footprints allowed))
    (fill (thermal_gap 0.254) (thermal_bridge_width 0.254))
    (polygon
      (pts
        (xy 131.425 74.386)
        (xy 131.425 76.05)
        (xy 129.575 76.05)
        (xy 129.575 74.175)
        (xy 131.211 74.173)
      )
    )
  )
  (zone (net 0) (net_name "") (layers "In1.Cu" "In2.Cu") (hatch edge 0.508)
    (connect_pads no (clearance 0))
    (min_thickness 0.5) (filled_areas_thickness no)
    (keepout (tracks allowed) (vias allowed) (pads allowed) (copperpour not_allowed) (footprints allowed))
    (fill (thermal_gap 0.508) (thermal_bridge_width 0.508))
    (polygon
      (pts
        (xy 110.19875 97.79)
        (xy 109.28875 97.79)
        (xy 109.29 96.81)
        (xy 110.2 96.81)
      )
    )
  )
  (zone (net 0) (net_name "") (layers "In1.Cu" "In2.Cu") (hatch edge 0.508)
    (connect_pads no (clearance 0))
    (min_thickness 0.5) (filled_areas_thickness no)
    (keepout (tracks allowed) (vias allowed) (pads allowed) (copperpour not_allowed) (footprints allowed))
    (fill (thermal_gap 0.508) (thermal_bridge_width 0.508))
    (polygon
      (pts
        (xy 112.4525 105.1675)
        (xy 110.4675 105.1725)
        (xy 110.465 103.06)
        (xy 112.45 103.06)
      )
    )
  )
  (zone (net 0) (net_name "") (layers "In1.Cu" "In2.Cu" "In3.Cu" "In4.Cu" "In5.Cu" "In6.Cu") (hatch edge 0.508)
    (connect_pads yes (clearance 0))
    (min_thickness 0.1) (filled_areas_thickness no)
    (keepout (tracks allowed) (vias allowed) (pads allowed) (copperpour not_allowed) (footprints allowed))
    (fill (thermal_gap 0.254) (thermal_bridge_width 0.254))
    (polygon
      (pts
        (xy 142.07 145.4)
        (xy 142.06711 145.45881)
        (xy 142.058471 145.517054)
        (xy 142.044164 145.57417)
        (xy 142.024327 145.62961)
        (xy 141.999152 145.682838)
        (xy 141.968881 145.733342)
        (xy 141.933806 145.780635)
        (xy 141.894264 145.824264)
        (xy 141.850635 145.863806)
        (xy 141.803342 145.898881)
        (xy 141.752838 145.929152)
        (xy 141.69961 145.954327)
        (xy 141.64417 145.974164)
        (xy 141.587054 145.988471)
        (xy 141.52881 145.99711)
        (xy 141.47 146)
        (xy 141.41119 145.99711)
        (xy 141.352946 145.988471)
        (xy 141.29583 145.974164)
        (xy 141.24039 145.954327)
        (xy 141.187162 145.929152)
        (xy 141.136658 145.898881)
        (xy 141.089365 145.863806)
        (xy 141.045736 145.824264)
        (xy 141.006194 145.780635)
        (xy 140.971119 145.733342)
        (xy 140.940848 145.682838)
        (xy 140.915673 145.62961)
        (xy 140.895836 145.57417)
        (xy 140.881529 145.517054)
        (xy 140.87289 145.45881)
        (xy 140.87 145.4)
        (xy 140.87289 145.34119)
        (xy 140.881529 145.282946)
        (xy 140.895836 145.22583)
        (xy 140.915673 145.17039)
        (xy 140.940848 145.117162)
        (xy 140.971119 145.066658)
        (xy 141.006194 145.019365)
        (xy 141.045736 144.975736)
        (xy 141.089365 144.936194)
        (xy 141.136658 144.901119)
        (xy 141.187162 144.870848)
        (xy 141.24039 144.845673)
        (xy 141.29583 144.825836)
        (xy 141.352946 144.811529)
        (xy 141.41119 144.80289)
        (xy 141.47 144.8)
        (xy 141.52881 144.80289)
        (xy 141.587054 144.811529)
        (xy 141.64417 144.825836)
        (xy 141.69961 144.845673)
        (xy 141.752838 144.870848)
        (xy 141.803342 144.901119)
        (xy 141.850635 144.936194)
        (xy 141.894264 144.975736)
        (xy 141.933806 145.019365)
        (xy 141.968881 145.066658)
        (xy 141.999152 145.117162)
        (xy 142.024327 145.17039)
        (xy 142.044164 145.22583)
        (xy 142.058471 145.282946)
        (xy 142.06711 145.34119)
      )
    )
  )
  (zone (net 0) (net_name "") (layers "In1.Cu" "In2.Cu" "In3.Cu" "In4.Cu" "In5.Cu" "In6.Cu") (hatch edge 0.508)
    (connect_pads yes (clearance 0))
    (min_thickness 0.1) (filled_areas_thickness no)
    (keepout (tracks allowed) (vias allowed) (pads allowed) (copperpour not_allowed) (footprints allowed))
    (fill (thermal_gap 0.254) (thermal_bridge_width 0.254))
    (polygon
      (pts
        (xy 144.41 58.27)
        (xy 144.40711 58.32881)
        (xy 144.398471 58.387054)
        (xy 144.384164 58.44417)
        (xy 144.364327 58.49961)
        (xy 144.339152 58.552838)
        (xy 144.308881 58.603342)
        (xy 144.273806 58.650635)
        (xy 144.234264 58.694264)
        (xy 144.190635 58.733806)
        (xy 144.143342 58.768881)
        (xy 144.092838 58.799152)
        (xy 144.03961 58.824327)
        (xy 143.98417 58.844164)
        (xy 143.927054 58.858471)
        (xy 143.86881 58.86711)
        (xy 143.81 58.87)
        (xy 143.75119 58.86711)
        (xy 143.692946 58.858471)
        (xy 143.63583 58.844164)
        (xy 143.58039 58.824327)
        (xy 143.527162 58.799152)
        (xy 143.476658 58.768881)
        (xy 143.429365 58.733806)
        (xy 143.385736 58.694264)
        (xy 143.346194 58.650635)
        (xy 143.311119 58.603342)
        (xy 143.280848 58.552838)
        (xy 143.255673 58.49961)
        (xy 143.235836 58.44417)
        (xy 143.221529 58.387054)
        (xy 143.21289 58.32881)
        (xy 143.21 58.27)
        (xy 143.21289 58.21119)
        (xy 143.221529 58.152946)
        (xy 143.235836 58.09583)
        (xy 143.255673 58.04039)
        (xy 143.280848 57.987162)
        (xy 143.311119 57.936658)
        (xy 143.346194 57.889365)
        (xy 143.385736 57.845736)
        (xy 143.429365 57.806194)
        (xy 143.476658 57.771119)
        (xy 143.527162 57.740848)
        (xy 143.58039 57.715673)
        (xy 143.63583 57.695836)
        (xy 143.692946 57.681529)
        (xy 143.75119 57.67289)
        (xy 143.81 57.67)
        (xy 143.86881 57.67289)
        (xy 143.927054 57.681529)
        (xy 143.98417 57.695836)
        (xy 144.03961 57.715673)
        (xy 144.092838 57.740848)
        (xy 144.143342 57.771119)
        (xy 144.190635 57.806194)
        (xy 144.234264 57.845736)
        (xy 144.273806 57.889365)
        (xy 144.308881 57.936658)
        (xy 144.339152 57.987162)
        (xy 144.364327 58.04039)
        (xy 144.384164 58.09583)
        (xy 144.398471 58.152946)
        (xy 144.40711 58.21119)
      )
    )
  )
  (zone (net 0) (net_name "") (layers "In1.Cu" "In2.Cu" "In3.Cu" "In4.Cu" "In5.Cu" "In6.Cu") (hatch edge 0.508)
    (connect_pads (clearance 0))
    (min_thickness 0.254) (filled_areas_thickness no)
    (keepout (tracks allowed) (vias allowed) (pads allowed) (copperpour not_allowed) (footprints allowed))
    (fill (thermal_gap 0.508) (thermal_bridge_width 0.508))
    (polygon
      (pts
        (xy 175.825 78.3)
        (xy 175.675 78.45)
        (xy 172.295 78.45)
        (xy 171.955 78.11)
        (xy 171.95 71.37)
        (xy 170.56 69.98)
        (xy 175.825 69.96125)
      )
    )
  )
  (zone (net 0) (net_name "") (layers "In1.Cu" "In2.Cu" "In3.Cu" "In4.Cu" "In5.Cu" "In6.Cu") (hatch edge 0.508)
    (connect_pads yes (clearance 0))
    (min_thickness 0.1) (filled_areas_thickness no)
    (keepout (tracks allowed) (vias allowed) (pads allowed) (copperpour not_allowed) (footprints allowed))
    (fill (thermal_gap 0.254) (thermal_bridge_width 0.254))
    (polygon
      (pts
        (xy 147.83583 145.404164)
        (xy 147.83294 145.462974)
        (xy 147.824301 145.521218)
        (xy 147.809994 145.578334)
        (xy 147.790157 145.633774)
        (xy 147.764982 145.687002)
        (xy 147.734711 145.737506)
        (xy 147.699636 145.784799)
        (xy 147.660094 145.828428)
        (xy 147.616465 145.86797)
        (xy 147.569172 145.903045)
        (xy 147.518668 145.933316)
        (xy 147.46544 145.958491)
        (xy 147.41 145.978328)
        (xy 147.352884 145.992635)
        (xy 147.29464 146.001274)
        (xy 147.23583 146.004164)
        (xy 147.17702 146.001274)
        (xy 147.118776 145.992635)
        (xy 147.06166 145.978328)
        (xy 147.00622 145.958491)
        (xy 146.952992 145.933316)
        (xy 146.902488 145.903045)
        (xy 146.855195 145.86797)
        (xy 146.811566 145.828428)
        (xy 146.772024 145.784799)
        (xy 146.736949 145.737506)
        (xy 146.706678 145.687002)
        (xy 146.681503 145.633774)
        (xy 146.661666 145.578334)
        (xy 146.647359 145.521218)
        (xy 146.63872 145.462974)
        (xy 146.63583 145.404164)
        (xy 146.63872 145.345354)
        (xy 146.647359 145.28711)
        (xy 146.661666 145.229994)
        (xy 146.681503 145.174554)
        (xy 146.706678 145.121326)
        (xy 146.736949 145.070822)
        (xy 146.772024 145.023529)
        (xy 146.811566 144.9799)
        (xy 146.855195 144.940358)
        (xy 146.902488 144.905283)
        (xy 146.952992 144.875012)
        (xy 147.00622 144.849837)
        (xy 147.06166 144.83)
        (xy 147.118776 144.815693)
        (xy 147.17702 144.807054)
        (xy 147.23583 144.804164)
        (xy 147.29464 144.807054)
        (xy 147.352884 144.815693)
        (xy 147.41 144.83)
        (xy 147.46544 144.849837)
        (xy 147.518668 144.875012)
        (xy 147.569172 144.905283)
        (xy 147.616465 144.940358)
        (xy 147.660094 144.9799)
        (xy 147.699636 145.023529)
        (xy 147.734711 145.070822)
        (xy 147.764982 145.121326)
        (xy 147.790157 145.174554)
        (xy 147.809994 145.229994)
        (xy 147.824301 145.28711)
        (xy 147.83294 145.345354)
      )
    )
  )
  (zone (net 0) (net_name "") (layers "In1.Cu" "In2.Cu" "In3.Cu" "In4.Cu" "In5.Cu" "In6.Cu") (hatch edge 0.508)
    (connect_pads yes (clearance 0))
    (min_thickness 0.1) (filled_areas_thickness no)
    (keepout (tracks allowed) (vias allowed) (pads allowed) (copperpour not_allowed) (footprints allowed))
    (fill (thermal_gap 0.254) (thermal_bridge_width 0.254))
    (polygon
      (pts
        (xy 150.19 58.28)
        (xy 150.18711 58.33881)
        (xy 150.178471 58.397054)
        (xy 150.164164 58.45417)
        (xy 150.144327 58.50961)
        (xy 150.119152 58.562838)
        (xy 150.088881 58.613342)
        (xy 150.053806 58.660635)
        (xy 150.014264 58.704264)
        (xy 149.970635 58.743806)
        (xy 149.923342 58.778881)
        (xy 149.872838 58.809152)
        (xy 149.81961 58.834327)
        (xy 149.76417 58.854164)
        (xy 149.707054 58.868471)
        (xy 149.64881 58.87711)
        (xy 149.59 58.88)
        (xy 149.53119 58.87711)
        (xy 149.472946 58.868471)
        (xy 149.41583 58.854164)
        (xy 149.36039 58.834327)
        (xy 149.307162 58.809152)
        (xy 149.256658 58.778881)
        (xy 149.209365 58.743806)
        (xy 149.165736 58.704264)
        (xy 149.126194 58.660635)
        (xy 149.091119 58.613342)
        (xy 149.060848 58.562838)
        (xy 149.035673 58.50961)
        (xy 149.015836 58.45417)
        (xy 149.001529 58.397054)
        (xy 148.99289 58.33881)
        (xy 148.99 58.28)
        (xy 148.99289 58.22119)
        (xy 149.001529 58.162946)
        (xy 149.015836 58.10583)
        (xy 149.035673 58.05039)
        (xy 149.060848 57.997162)
        (xy 149.091119 57.946658)
        (xy 149.126194 57.899365)
        (xy 149.165736 57.855736)
        (xy 149.209365 57.816194)
        (xy 149.256658 57.781119)
        (xy 149.307162 57.750848)
        (xy 149.36039 57.725673)
        (xy 149.41583 57.705836)
        (xy 149.472946 57.691529)
        (xy 149.53119 57.68289)
        (xy 149.59 57.68)
        (xy 149.64881 57.68289)
        (xy 149.707054 57.691529)
        (xy 149.76417 57.705836)
        (xy 149.81961 57.725673)
        (xy 149.872838 57.750848)
        (xy 149.923342 57.781119)
        (xy 149.970635 57.816194)
        (xy 150.014264 57.855736)
        (xy 150.053806 57.899365)
        (xy 150.088881 57.946658)
        (xy 150.119152 57.997162)
        (xy 150.144327 58.05039)
        (xy 150.164164 58.10583)
        (xy 150.178471 58.162946)
        (xy 150.18711 58.22119)
      )
    )
  )
  (zone (net 0) (net_name "") (layers "In1.Cu" "In2.Cu" "In3.Cu" "In5.Cu" "In6.Cu") (hatch edge 0.508)
    (connect_pads yes (clearance 0))
    (min_thickness 0.1) (filled_areas_thickness no)
    (keepout (tracks allowed) (vias allowed) (pads allowed) (copperpour not_allowed) (footprints allowed))
    (fill (thermal_gap 0.254) (thermal_bridge_width 0.254))
    (polygon
      (pts
        (xy 124.337047 94.037343)
        (xy 124.343167 93.996087)
        (xy 124.353301 93.95563)
        (xy 124.367352 93.91636)
        (xy 124.385184 93.878657)
        (xy 124.406626 93.842883)
        (xy 124.431471 93.809383)
        (xy 124.45948 93.77848)
        (xy 124.490383 93.750471)
        (xy 124.523882 93.725626)
        (xy 124.559657 93.704184)
        (xy 124.59736 93.686353)
        (xy 124.63663 93.672301)
        (xy 124.677087 93.662167)
        (xy 124.718343 93.656047)
        (xy 124.76 93.654)
        (xy 124.763999 93.654197)
        (xy 124.764 93.654)
        (xy 125.333447 93.654)
        (xy 125.346641 93.653352)
        (xy 125.388296 93.655399)
        (xy 125.429553 93.661519)
        (xy 125.47001 93.671653)
        (xy 125.50928 93.685704)
        (xy 125.546982 93.703536)
        (xy 125.582757 93.724978)
        (xy 125.616257 93.749823)
        (xy 125.64716 93.777832)
        (xy 125.675169 93.808734)
        (xy 125.700015 93.842235)
        (xy 125.721455 93.878009)
        (xy 125.739288 93.915713)
        (xy 125.753339 93.954982)
        (xy 125.763472 93.995439)
        (xy 125.769592 94.036695)
        (xy 125.77164 94.078351)
        (xy 125.769593 94.120009)
        (xy 125.763473 94.161265)
        (xy 125.753339 94.201722)
        (xy 125.739288 94.240992)
        (xy 125.721456 94.278695)
        (xy 125.700014 94.314469)
        (xy 125.675169 94.347968)
        (xy 125.64716 94.378872)
        (xy 125.616255 94.406881)
        (xy 125.582756 94.431726)
        (xy 125.546983 94.453168)
        (xy 125.50928 94.471)
        (xy 125.47001 94.485051)
        (xy 125.429553 94.495185)
        (xy 125.388297 94.501305)
        (xy 125.34664 94.503352)
        (xy 125.317747 94.501932)
        (xy 124.807587 94.501073)
        (xy 124.801657 94.501953)
        (xy 124.759999 94.504)
        (xy 124.718342 94.501953)
        (xy 124.677087 94.495834)
        (xy 124.63663 94.485699)
        (xy 124.59736 94.471648)
        (xy 124.559657 94.453817)
        (xy 124.523883 94.432374)
        (xy 124.490383 94.407529)
        (xy 124.45948 94.37952)
        (xy 124.431471 94.348617)
        (xy 124.406626 94.315117)
        (xy 124.385183 94.279343)
        (xy 124.367352 94.24164)
        (xy 124.353301 94.20237)
        (xy 124.343166 94.161913)
        (xy 124.337046 94.120657)
        (xy 124.335 94.079001)
      )
    )
  )
  (zone (net 0) (net_name "") (layers "In1.Cu" "In2.Cu" "In3.Cu" "In5.Cu" "In6.Cu") (hatch edge 0.508)
    (connect_pads yes (clearance 0))
    (min_thickness 0.1) (filled_areas_thickness no)
    (keepout (tracks allowed) (vias allowed) (pads allowed) (copperpour not_allowed) (footprints allowed))
    (fill (thermal_gap 0.254) (thermal_bridge_width 0.254))
    (polygon
      (pts
        (xy 126.842657 83.217047)
        (xy 126.883913 83.223167)
        (xy 126.92437 83.233301)
        (xy 126.96364 83.247352)
        (xy 127.001343 83.265184)
        (xy 127.037117 83.286626)
        (xy 127.070617 83.311471)
        (xy 127.10152 83.33948)
        (xy 127.129529 83.370383)
        (xy 127.154374 83.403882)
        (xy 127.175816 83.439657)
        (xy 127.193647 83.47736)
        (xy 127.207699 83.51663)
        (xy 127.217833 83.557087)
        (xy 127.223953 83.598343)
        (xy 127.226 83.64)
        (xy 127.225803 83.644)
        (xy 127.226 83.644)
        (xy 127.226 84.213447)
        (xy 127.226648 84.22664)
        (xy 127.224601 84.268296)
        (xy 127.218481 84.309553)
        (xy 127.208347 84.35001)
        (xy 127.194296 84.38928)
        (xy 127.176464 84.426982)
        (xy 127.155022 84.462757)
        (xy 127.130177 84.496257)
        (xy 127.102168 84.52716)
        (xy 127.071266 84.555169)
        (xy 127.037765 84.580015)
        (xy 127.001991 84.601455)
        (xy 126.964287 84.619288)
        (xy 126.925018 84.633339)
        (xy 126.884561 84.643472)
        (xy 126.843305 84.649592)
        (xy 126.801648 84.65164)
        (xy 126.759991 84.649593)
        (xy 126.718735 84.643473)
        (xy 126.678278 84.633339)
        (xy 126.639008 84.619288)
        (xy 126.601305 84.601456)
        (xy 126.565531 84.580014)
        (xy 126.532032 84.555169)
        (xy 126.501128 84.52716)
        (xy 126.473119 84.496256)
        (xy 126.448274 84.462756)
        (xy 126.426832 84.426983)
        (xy 126.409 84.38928)
        (xy 126.394949 84.35001)
        (xy 126.384815 84.309553)
        (xy 126.378695 84.268297)
        (xy 126.376648 84.22664)
        (xy 126.378068 84.197747)
        (xy 126.378927 83.687587)
        (xy 126.378047 83.681657)
        (xy 126.376 83.64)
        (xy 126.378047 83.598342)
        (xy 126.384166 83.557087)
        (xy 126.394301 83.51663)
        (xy 126.408352 83.47736)
        (xy 126.426183 83.439657)
        (xy 126.447626 83.403883)
        (xy 126.472471 83.370383)
        (xy 126.50048 83.33948)
        (xy 126.531383 83.311471)
        (xy 126.564883 83.286626)
        (xy 126.600657 83.265183)
        (xy 126.63836 83.247352)
        (xy 126.67763 83.233301)
        (xy 126.718087 83.223166)
        (xy 126.759343 83.217046)
        (xy 126.801 83.215)
      )
    )
  )
  (zone (net 0) (net_name "") (layers "In1.Cu" "In2.Cu" "In3.Cu" "In5.Cu" "In6.Cu") (hatch edge 0.508)
    (connect_pads yes (clearance 0))
    (min_thickness 0.1) (filled_areas_thickness no)
    (keepout (tracks allowed) (vias allowed) (pads allowed) (copperpour not_allowed) (footprints allowed))
    (fill (thermal_gap 0.254) (thermal_bridge_width 0.254))
    (polygon
      (pts
        (xy 122.796828 79.810805)
        (xy 122.802948 79.769549)
        (xy 122.813082 79.729092)
        (xy 122.827133 79.689822)
        (xy 122.844965 79.652119)
        (xy 122.866407 79.616345)
        (xy 122.891252 79.582845)
        (xy 122.919261 79.551942)
        (xy 122.950164 79.523933)
        (xy 122.983663 79.499088)
        (xy 123.019438 79.477646)
        (xy 123.057141 79.459815)
        (xy 123.096411 79.445763)
        (xy 123.136868 79.435629)
        (xy 123.178124 79.429509)
        (xy 123.219781 79.427462)
        (xy 123.22378 79.427659)
        (xy 123.223781 79.427462)
        (xy 123.793228 79.427462)
        (xy 123.806422 79.426814)
        (xy 123.848077 79.428861)
        (xy 123.889334 79.434981)
        (xy 123.929791 79.445115)
        (xy 123.969061 79.459166)
        (xy 124.006763 79.476998)
        (xy 124.042538 79.49844)
        (xy 124.076038 79.523285)
        (xy 124.106941 79.551294)
        (xy 124.13495 79.582196)
        (xy 124.159796 79.615697)
        (xy 124.181236 79.651471)
        (xy 124.199069 79.689175)
        (xy 124.21312 79.728444)
        (xy 124.223253 79.768901)
        (xy 124.229373 79.810157)
        (xy 124.231421 79.851813)
        (xy 124.229374 79.893471)
        (xy 124.223254 79.934727)
        (xy 124.21312 79.975184)
        (xy 124.199069 80.014454)
        (xy 124.181237 80.052157)
        (xy 124.159795 80.087931)
        (xy 124.13495 80.12143)
        (xy 124.106941 80.152334)
        (xy 124.076036 80.180343)
        (xy 124.042537 80.205188)
        (xy 124.006764 80.22663)
        (xy 123.969061 80.244462)
        (xy 123.929791 80.258513)
        (xy 123.889334 80.268647)
        (xy 123.848078 80.274767)
        (xy 123.806421 80.276814)
        (xy 123.777528 80.275394)
        (xy 123.267368 80.274535)
        (xy 123.261438 80.275415)
        (xy 123.21978 80.277462)
        (xy 123.178123 80.275415)
        (xy 123.136868 80.269296)
        (xy 123.096411 80.259161)
        (xy 123.057141 80.24511)
        (xy 123.019438 80.227279)
        (xy 122.983664 80.205836)
        (xy 122.950164 80.180991)
        (xy 122.919261 80.152982)
        (xy 122.891252 80.122079)
        (xy 122.866407 80.088579)
        (xy 122.844964 80.052805)
        (xy 122.827133 80.015102)
        (xy 122.813082 79.975832)
        (xy 122.802947 79.935375)
        (xy 122.796827 79.894119)
        (xy 122.794781 79.852463)
      )
    )
  )
  (zone (net 0) (net_name "") (layers "In1.Cu" "In2.Cu" "In3.Cu" "In5.Cu" "In6.Cu") (hatch edge 0.508)
    (connect_pads yes (clearance 0))
    (min_thickness 0.1) (filled_areas_thickness no)
    (keepout (tracks allowed) (vias allowed) (pads allowed) (copperpour not_allowed) (footprints allowed))
    (fill (thermal_gap 0.254) (thermal_bridge_width 0.254))
    (polygon
      (pts
        (xy 119.407047 92.147343)
        (xy 119.413167 92.106087)
        (xy 119.423301 92.06563)
        (xy 119.437352 92.02636)
        (xy 119.455184 91.988657)
        (xy 119.476626 91.952883)
        (xy 119.501471 91.919383)
        (xy 119.52948 91.88848)
        (xy 119.560383 91.860471)
        (xy 119.593882 91.835626)
        (xy 119.629657 91.814184)
        (xy 119.66736 91.796353)
        (xy 119.70663 91.782301)
        (xy 119.747087 91.772167)
        (xy 119.788343 91.766047)
        (xy 119.83 91.764)
        (xy 119.833999 91.764197)
        (xy 119.834 91.764)
        (xy 120.403447 91.764)
        (xy 120.416641 91.763352)
        (xy 120.458296 91.765399)
        (xy 120.499553 91.771519)
        (xy 120.54001 91.781653)
        (xy 120.57928 91.795704)
        (xy 120.616982 91.813536)
        (xy 120.652757 91.834978)
        (xy 120.686257 91.859823)
        (xy 120.71716 91.887832)
        (xy 120.745169 91.918734)
        (xy 120.770015 91.952235)
        (xy 120.791455 91.988009)
        (xy 120.809288 92.025713)
        (xy 120.823339 92.064982)
        (xy 120.833472 92.105439)
        (xy 120.839592 92.146695)
        (xy 120.84164 92.188351)
        (xy 120.839593 92.230009)
        (xy 120.833473 92.271265)
        (xy 120.823339 92.311722)
        (xy 120.809288 92.350992)
        (xy 120.791456 92.388695)
        (xy 120.770014 92.424469)
        (xy 120.745169 92.457968)
        (xy 120.71716 92.488872)
        (xy 120.686255 92.516881)
        (xy 120.652756 92.541726)
        (xy 120.616983 92.563168)
        (xy 120.57928 92.581)
        (xy 120.54001 92.595051)
        (xy 120.499553 92.605185)
        (xy 120.458297 92.611305)
        (xy 120.41664 92.613352)
        (xy 120.387747 92.611932)
        (xy 119.877587 92.611073)
        (xy 119.871657 92.611953)
        (xy 119.829999 92.614)
        (xy 119.788342 92.611953)
        (xy 119.747087 92.605834)
        (xy 119.70663 92.595699)
        (xy 119.66736 92.581648)
        (xy 119.629657 92.563817)
        (xy 119.593883 92.542374)
        (xy 119.560383 92.517529)
        (xy 119.52948 92.48952)
        (xy 119.501471 92.458617)
        (xy 119.476626 92.425117)
        (xy 119.455183 92.389343)
        (xy 119.437352 92.35164)
        (xy 119.423301 92.31237)
        (xy 119.413166 92.271913)
        (xy 119.407046 92.230657)
        (xy 119.405 92.189001)
      )
    )
  )
  (zone (net 0) (net_name "") (layers "In1.Cu" "In2.Cu" "In3.Cu" "In5.Cu" "In6.Cu") (hatch edge 0.508)
    (connect_pads yes (clearance 0))
    (min_thickness 0.1) (filled_areas_thickness no)
    (keepout (tracks allowed) (vias allowed) (pads allowed) (copperpour not_allowed) (footprints allowed))
    (fill (thermal_gap 0.254) (thermal_bridge_width 0.254))
    (polygon
      (pts
        (xy 125.607047 79.807343)
        (xy 125.613167 79.766087)
        (xy 125.623301 79.72563)
        (xy 125.637352 79.68636)
        (xy 125.655184 79.648657)
        (xy 125.676626 79.612883)
        (xy 125.701471 79.579383)
        (xy 125.72948 79.54848)
        (xy 125.760383 79.520471)
        (xy 125.793882 79.495626)
        (xy 125.829657 79.474184)
        (xy 125.86736 79.456353)
        (xy 125.90663 79.442301)
        (xy 125.947087 79.432167)
        (xy 125.988343 79.426047)
        (xy 126.03 79.424)
        (xy 126.033999 79.424197)
        (xy 126.034 79.424)
        (xy 126.603447 79.424)
        (xy 126.616641 79.423352)
        (xy 126.658296 79.425399)
        (xy 126.699553 79.431519)
        (xy 126.74001 79.441653)
        (xy 126.77928 79.455704)
        (xy 126.816982 79.473536)
        (xy 126.852757 79.494978)
        (xy 126.886257 79.519823)
        (xy 126.91716 79.547832)
        (xy 126.945169 79.578734)
        (xy 126.970015 79.612235)
        (xy 126.991455 79.648009)
        (xy 127.009288 79.685713)
        (xy 127.023339 79.724982)
        (xy 127.033472 79.765439)
        (xy 127.039592 79.806695)
        (xy 127.04164 79.848351)
        (xy 127.039593 79.890009)
        (xy 127.033473 79.931265)
        (xy 127.023339 79.971722)
        (xy 127.009288 80.010992)
        (xy 126.991456 80.048695)
        (xy 126.970014 80.084469)
        (xy 126.945169 80.117968)
        (xy 126.91716 80.148872)
        (xy 126.886255 80.176881)
        (xy 126.852756 80.201726)
        (xy 126.816983 80.223168)
        (xy 126.77928 80.241)
        (xy 126.74001 80.255051)
        (xy 126.699553 80.265185)
        (xy 126.658297 80.271305)
        (xy 126.61664 80.273352)
        (xy 126.587747 80.271932)
        (xy 126.077587 80.271073)
        (xy 126.071657 80.271953)
        (xy 126.029999 80.274)
        (xy 125.988342 80.271953)
        (xy 125.947087 80.265834)
        (xy 125.90663 80.255699)
        (xy 125.86736 80.241648)
        (xy 125.829657 80.223817)
        (xy 125.793883 80.202374)
        (xy 125.760383 80.177529)
        (xy 125.72948 80.14952)
        (xy 125.701471 80.118617)
        (xy 125.676626 80.085117)
        (xy 125.655183 80.049343)
        (xy 125.637352 80.01164)
        (xy 125.623301 79.97237)
        (xy 125.613166 79.931913)
        (xy 125.607046 79.890657)
        (xy 125.605 79.849001)
      )
    )
  )
  (zone (net 0) (net_name "") (layers "In1.Cu" "In2.Cu" "In3.Cu" "In5.Cu" "In6.Cu") (hatch edge 0.508)
    (connect_pads yes (clearance 0))
    (min_thickness 0.1) (filled_areas_thickness no)
    (keepout (tracks allowed) (vias allowed) (pads allowed) (copperpour not_allowed) (footprints allowed))
    (fill (thermal_gap 0.254) (thermal_bridge_width 0.254))
    (polygon
      (pts
        (xy 122.477047 94.037343)
        (xy 122.483167 93.996087)
        (xy 122.493301 93.95563)
        (xy 122.507352 93.91636)
        (xy 122.525184 93.878657)
        (xy 122.546626 93.842883)
        (xy 122.571471 93.809383)
        (xy 122.59948 93.77848)
        (xy 122.630383 93.750471)
        (xy 122.663882 93.725626)
        (xy 122.699657 93.704184)
        (xy 122.73736 93.686353)
        (xy 122.77663 93.672301)
        (xy 122.817087 93.662167)
        (xy 122.858343 93.656047)
        (xy 122.9 93.654)
        (xy 122.903999 93.654197)
        (xy 122.904 93.654)
        (xy 123.473447 93.654)
        (xy 123.486641 93.653352)
        (xy 123.528296 93.655399)
        (xy 123.569553 93.661519)
        (xy 123.61001 93.671653)
        (xy 123.64928 93.685704)
        (xy 123.686982 93.703536)
        (xy 123.722757 93.724978)
        (xy 123.756257 93.749823)
        (xy 123.78716 93.777832)
        (xy 123.815169 93.808734)
        (xy 123.840015 93.842235)
        (xy 123.861455 93.878009)
        (xy 123.879288 93.915713)
        (xy 123.893339 93.954982)
        (xy 123.903472 93.995439)
        (xy 123.909592 94.036695)
        (xy 123.91164 94.078351)
        (xy 123.909593 94.120009)
        (xy 123.903473 94.161265)
        (xy 123.893339 94.201722)
        (xy 123.879288 94.240992)
        (xy 123.861456 94.278695)
        (xy 123.840014 94.314469)
        (xy 123.815169 94.347968)
        (xy 123.78716 94.378872)
        (xy 123.756255 94.406881)
        (xy 123.722756 94.431726)
        (xy 123.686983 94.453168)
        (xy 123.64928 94.471)
        (xy 123.61001 94.485051)
        (xy 123.569553 94.495185)
        (xy 123.528297 94.501305)
        (xy 123.48664 94.503352)
        (xy 123.457747 94.501932)
        (xy 122.947587 94.501073)
        (xy 122.941657 94.501953)
        (xy 122.899999 94.504)
        (xy 122.858342 94.501953)
        (xy 122.817087 94.495834)
        (xy 122.77663 94.485699)
        (xy 122.73736 94.471648)
        (xy 122.699657 94.453817)
        (xy 122.663883 94.432374)
        (xy 122.630383 94.407529)
        (xy 122.59948 94.37952)
        (xy 122.571471 94.348617)
        (xy 122.546626 94.315117)
        (xy 122.525183 94.279343)
        (xy 122.507352 94.24164)
        (xy 122.493301 94.20237)
        (xy 122.483166 94.161913)
        (xy 122.477046 94.120657)
        (xy 122.475 94.079001)
      )
    )
  )
  (zone (net 0) (net_name "") (layers "In1.Cu" "In3.Cu" "In5.Cu") (hatch edge 0.508)
    (connect_pads yes (clearance 0))
    (min_thickness 0.1) (filled_areas_thickness no)
    (keepout (tracks allowed) (vias allowed) (pads allowed) (copperpour not_allowed) (footprints allowed))
    (fill (thermal_gap 0.254) (thermal_bridge_width 0.254))
    (polygon
      (pts
        (xy 100.502263 105.286)
        (xy 101.268387 105.286)
        (xy 101.269343 105.285953)
        (xy 101.311 105.288)
        (xy 101.352256 105.29412)
        (xy 101.392713 105.304254)
        (xy 101.431983 105.318305)
        (xy 101.469686 105.336137)
        (xy 101.50546 105.357579)
        (xy 101.53896 105.382424)
        (xy 101.569863 105.410433)
        (xy 101.597872 105.441336)
        (xy 101.622717 105.474836)
        (xy 101.644159 105.51061)
        (xy 101.661991 105.548313)
        (xy 101.676042 105.587583)
        (xy 101.686176 105.62804)
        (xy 101.692296 105.669296)
        (xy 101.694343 105.710953)
        (xy 101.692296 105.75261)
        (xy 101.686176 105.793866)
        (xy 101.676042 105.834323)
        (xy 101.661991 105.873593)
        (xy 101.644159 105.911296)
        (xy 101.622717 105.94707)
        (xy 101.597872 105.98057)
        (xy 101.569863 106.011473)
        (xy 101.53896 106.039482)
        (xy 101.50546 106.064327)
        (xy 101.469686 106.085769)
        (xy 101.431983 106.103601)
        (xy 101.392713 106.117652)
        (xy 101.352256 106.127786)
        (xy 101.311 106.133906)
        (xy 101.27 106.135921)
        (xy 101.27 106.136)
        (xy 100.489315 106.135004)
        (xy 100.485657 106.135184)
        (xy 100.444 106.133137)
        (xy 100.402744 106.127017)
        (xy 100.362287 106.116883)
        (xy 100.323017 106.102832)
        (xy 100.285314 106.085)
        (xy 100.24954 106.063558)
        (xy 100.21604 106.038713)
        (xy 100.185137 106.010704)
        (xy 100.157128 105.979801)
        (xy 100.132283 105.946301)
        (xy 100.110841 105.910527)
        (xy 100.093009 105.872824)
        (xy 100.078958 105.833554)
        (xy 100.068824 105.793097)
        (xy 100.062704 105.751841)
        (xy 100.060657 105.710184)
        (xy 100.062704 105.668527)
        (xy 100.068824 105.627271)
        (xy 100.078958 105.586814)
        (xy 100.093009 105.547544)
        (xy 100.110841 105.509841)
        (xy 100.132283 105.474067)
        (xy 100.157128 105.440567)
        (xy 100.185137 105.409664)
        (xy 100.21604 105.381655)
        (xy 100.24954 105.35681)
        (xy 100.285314 105.335368)
        (xy 100.323017 105.317536)
        (xy 100.362287 105.303485)
        (xy 100.402744 105.293351)
        (xy 100.444 105.287231)
        (xy 100.485657 105.285184)
      )
    )
  )
  (zone (net 0) (net_name "") (layers "In1.Cu" "In3.Cu" "In5.Cu") (hatch edge 0.508)
    (connect_pads yes (clearance 0))
    (min_thickness 0.1) (filled_areas_thickness no)
    (keepout (tracks allowed) (vias allowed) (pads allowed) (copperpour not_allowed) (footprints allowed))
    (fill (thermal_gap 0.254) (thermal_bridge_width 0.254))
    (polygon
      (pts
        (xy 111.100263 105.32)
        (xy 111.866387 105.32)
        (xy 111.867343 105.319953)
        (xy 111.909 105.322)
        (xy 111.950256 105.32812)
        (xy 111.990713 105.338254)
        (xy 112.029983 105.352305)
        (xy 112.067686 105.370137)
        (xy 112.10346 105.391579)
        (xy 112.13696 105.416424)
        (xy 112.167863 105.444433)
        (xy 112.195872 105.475336)
        (xy 112.220717 105.508836)
        (xy 112.242159 105.54461)
        (xy 112.259991 105.582313)
        (xy 112.274042 105.621583)
        (xy 112.284176 105.66204)
        (xy 112.290296 105.703296)
        (xy 112.292343 105.744953)
        (xy 112.290296 105.78661)
        (xy 112.284176 105.827866)
        (xy 112.274042 105.868323)
        (xy 112.259991 105.907593)
        (xy 112.242159 105.945296)
        (xy 112.220717 105.98107)
        (xy 112.195872 106.01457)
        (xy 112.167863 106.045473)
        (xy 112.13696 106.073482)
        (xy 112.10346 106.098327)
        (xy 112.067686 106.119769)
        (xy 112.029983 106.137601)
        (xy 111.990713 106.151652)
        (xy 111.950256 106.161786)
        (xy 111.909 106.167906)
        (xy 111.868 106.169921)
        (xy 111.868 106.17)
        (xy 111.087315 106.169004)
        (xy 111.083657 106.169184)
        (xy 111.042 106.167137)
        (xy 111.000744 106.161017)
        (xy 110.960287 106.150883)
        (xy 110.921017 106.136832)
        (xy 110.883314 106.119)
        (xy 110.84754 106.097558)
        (xy 110.81404 106.072713)
        (xy 110.783137 106.044704)
        (xy 110.755128 106.013801)
        (xy 110.730283 105.980301)
        (xy 110.708841 105.944527)
        (xy 110.691009 105.906824)
        (xy 110.676958 105.867554)
        (xy 110.666824 105.827097)
        (xy 110.660704 105.785841)
        (xy 110.658657 105.744184)
        (xy 110.660704 105.702527)
        (xy 110.666824 105.661271)
        (xy 110.676958 105.620814)
        (xy 110.691009 105.581544)
        (xy 110.708841 105.543841)
        (xy 110.730283 105.508067)
        (xy 110.755128 105.474567)
        (xy 110.783137 105.443664)
        (xy 110.81404 105.415655)
        (xy 110.84754 105.39081)
        (xy 110.883314 105.369368)
        (xy 110.921017 105.351536)
        (xy 110.960287 105.337485)
        (xy 111.000744 105.327351)
        (xy 111.042 105.321231)
        (xy 111.083657 105.319184)
      )
    )
  )
  (zone (net 0) (net_name "") (layers "In1.Cu" "In3.Cu" "In5.Cu") (hatch edge 0.508)
    (connect_pads yes (clearance 0))
    (min_thickness 0.1) (filled_areas_thickness no)
    (keepout (tracks allowed) (vias allowed) (pads allowed) (copperpour not_allowed) (footprints allowed))
    (fill (thermal_gap 0.508) (thermal_bridge_width 0.508))
    (polygon
      (pts
        (xy 191.965 92.7025)
        (xy 167.36 92.7)
        (xy 161.62 86.95)
        (xy 161.61 78.59)
        (xy 163.75 76.44)
        (xy 174.935 76.425)
        (xy 174.94625 68.9175)
        (xy 192.05 68.915)
        (xy 192.05 76.955)
      )
    )
  )
  (zone (net 0) (net_name "") (layers "In1.Cu" "In3.Cu" "In5.Cu") (hatch edge 0.508)
    (connect_pads yes (clearance 0))
    (min_thickness 0.1) (filled_areas_thickness no)
    (keepout (tracks allowed) (vias allowed) (pads allowed) (copperpour not_allowed) (footprints allowed))
    (fill (thermal_gap 0.254) (thermal_bridge_width 0.254))
    (polygon
      (pts
        (xy 100.352948 97.420996)
        (xy 101.119072 97.420996)
        (xy 101.120028 97.420949)
        (xy 101.161685 97.422996)
        (xy 101.202941 97.429116)
        (xy 101.243398 97.43925)
        (xy 101.282668 97.453301)
        (xy 101.320371 97.471133)
        (xy 101.356145 97.492575)
        (xy 101.389645 97.51742)
        (xy 101.420548 97.545429)
        (xy 101.448557 97.576332)
        (xy 101.473402 97.609832)
        (xy 101.494844 97.645606)
        (xy 101.512676 97.683309)
        (xy 101.526727 97.722579)
        (xy 101.536861 97.763036)
        (xy 101.542981 97.804292)
        (xy 101.545028 97.845949)
        (xy 101.542981 97.887606)
        (xy 101.536861 97.928862)
        (xy 101.526727 97.969319)
        (xy 101.512676 98.008589)
        (xy 101.494844 98.046292)
        (xy 101.473402 98.082066)
        (xy 101.448557 98.115566)
        (xy 101.420548 98.146469)
        (xy 101.389645 98.174478)
        (xy 101.356145 98.199323)
        (xy 101.320371 98.220765)
        (xy 101.282668 98.238597)
        (xy 101.243398 98.252648)
        (xy 101.202941 98.262782)
        (xy 101.161685 98.268902)
        (xy 101.120685 98.270917)
        (xy 101.120685 98.270996)
        (xy 100.34 98.27)
        (xy 100.336342 98.27018)
        (xy 100.294685 98.268133)
        (xy 100.253429 98.262013)
        (xy 100.212972 98.251879)
        (xy 100.173702 98.237828)
        (xy 100.135999 98.219996)
        (xy 100.100225 98.198554)
        (xy 100.066725 98.173709)
        (xy 100.035822 98.1457)
        (xy 100.007813 98.114797)
        (xy 99.982968 98.081297)
        (xy 99.961526 98.045523)
        (xy 99.943694 98.00782)
        (xy 99.929643 97.96855)
        (xy 99.919509 97.928093)
        (xy 99.913389 97.886837)
        (xy 99.911342 97.84518)
        (xy 99.913389 97.803523)
        (xy 99.919509 97.762267)
        (xy 99.929643 97.72181)
        (xy 99.943694 97.68254)
        (xy 99.961526 97.644837)
        (xy 99.982968 97.609063)
        (xy 100.007813 97.575563)
        (xy 100.035822 97.54466)
        (xy 100.066725 97.516651)
        (xy 100.100225 97.491806)
        (xy 100.135999 97.470364)
        (xy 100.173702 97.452532)
        (xy 100.212972 97.438481)
        (xy 100.253429 97.428347)
        (xy 100.294685 97.422227)
        (xy 100.336342 97.42018)
      )
    )
  )
  (zone (net 0) (net_name "") (layers "In1.Cu" "In3.Cu" "In5.Cu" "In6.Cu") (hatch edge 0.508)
    (connect_pads yes (clearance 0))
    (min_thickness 0.1) (filled_areas_thickness no)
    (keepout (tracks allowed) (vias allowed) (pads allowed) (copperpour not_allowed) (footprints allowed))
    (fill (thermal_gap 0.254) (thermal_bridge_width 0.254))
    (polygon
      (pts
        (xy 150.627047 84.057343)
        (xy 150.633167 84.016087)
        (xy 150.643301 83.97563)
        (xy 150.657352 83.93636)
        (xy 150.675184 83.898657)
        (xy 150.696626 83.862883)
        (xy 150.721471 83.829383)
        (xy 150.74948 83.79848)
        (xy 150.780383 83.770471)
        (xy 150.813882 83.745626)
        (xy 150.849657 83.724184)
        (xy 150.88736 83.706353)
        (xy 150.92663 83.692301)
        (xy 150.967087 83.682167)
        (xy 151.008343 83.676047)
        (xy 151.05 83.674)
        (xy 151.053999 83.674197)
        (xy 151.054 83.674)
        (xy 151.623447 83.674)
        (xy 151.636641 83.673352)
        (xy 151.678296 83.675399)
        (xy 151.719553 83.681519)
        (xy 151.76001 83.691653)
        (xy 151.79928 83.705704)
        (xy 151.836982 83.723536)
        (xy 151.872757 83.744978)
        (xy 151.906257 83.769823)
        (xy 151.93716 83.797832)
        (xy 151.965169 83.828734)
        (xy 151.990015 83.862235)
        (xy 152.011455 83.898009)
        (xy 152.029288 83.935713)
        (xy 152.043339 83.974982)
        (xy 152.053472 84.015439)
        (xy 152.059592 84.056695)
        (xy 152.06164 84.098351)
        (xy 152.059593 84.140009)
        (xy 152.053473 84.181265)
        (xy 152.043339 84.221722)
        (xy 152.029288 84.260992)
        (xy 152.011456 84.298695)
        (xy 151.990014 84.334469)
        (xy 151.965169 84.367968)
        (xy 151.93716 84.398872)
        (xy 151.906255 84.426881)
        (xy 151.872756 84.451726)
        (xy 151.836983 84.473168)
        (xy 151.79928 84.491)
        (xy 151.76001 84.505051)
        (xy 151.719553 84.515185)
        (xy 151.678297 84.521305)
        (xy 151.63664 84.523352)
        (xy 151.607747 84.521932)
        (xy 151.097587 84.521073)
        (xy 151.091657 84.521953)
        (xy 151.049999 84.524)
        (xy 151.008342 84.521953)
        (xy 150.967087 84.515834)
        (xy 150.92663 84.505699)
        (xy 150.88736 84.491648)
        (xy 150.849657 84.473817)
        (xy 150.813883 84.452374)
        (xy 150.780383 84.427529)
        (xy 150.74948 84.39952)
        (xy 150.721471 84.368617)
        (xy 150.696626 84.335117)
        (xy 150.675183 84.299343)
        (xy 150.657352 84.26164)
        (xy 150.643301 84.22237)
        (xy 150.633166 84.181913)
        (xy 150.627046 84.140657)
        (xy 150.625 84.099001)
      )
    )
  )
  (zone (net 0) (net_name "") (layers "In1.Cu" "In3.Cu" "In5.Cu" "In6.Cu") (hatch edge 0.508)
    (connect_pads yes (clearance 0))
    (min_thickness 0.1) (filled_areas_thickness no)
    (keepout (tracks allowed) (vias allowed) (pads allowed) (copperpour not_allowed) (footprints allowed))
    (fill (thermal_gap 0.254) (thermal_bridge_width 0.254))
    (polygon
      (pts
        (xy 145.977047 63.507343)
        (xy 145.983167 63.466087)
        (xy 145.993301 63.42563)
        (xy 146.007352 63.38636)
        (xy 146.025184 63.348657)
        (xy 146.046626 63.312883)
        (xy 146.071471 63.279383)
        (xy 146.09948 63.24848)
        (xy 146.130383 63.220471)
        (xy 146.163882 63.195626)
        (xy 146.199657 63.174184)
        (xy 146.23736 63.156353)
        (xy 146.27663 63.142301)
        (xy 146.317087 63.132167)
        (xy 146.358343 63.126047)
        (xy 146.4 63.124)
        (xy 146.403999 63.124197)
        (xy 146.404 63.124)
        (xy 146.973447 63.124)
        (xy 146.986641 63.123352)
        (xy 147.028296 63.125399)
        (xy 147.069553 63.131519)
        (xy 147.11001 63.141653)
        (xy 147.14928 63.155704)
        (xy 147.186982 63.173536)
        (xy 147.222757 63.194978)
        (xy 147.256257 63.219823)
        (xy 147.28716 63.247832)
        (xy 147.315169 63.278734)
        (xy 147.340015 63.312235)
        (xy 147.361455 63.348009)
        (xy 147.379288 63.385713)
        (xy 147.393339 63.424982)
        (xy 147.403472 63.465439)
        (xy 147.409592 63.506695)
        (xy 147.41164 63.548351)
        (xy 147.409593 63.590009)
        (xy 147.403473 63.631265)
        (xy 147.393339 63.671722)
        (xy 147.379288 63.710992)
        (xy 147.361456 63.748695)
        (xy 147.340014 63.784469)
        (xy 147.315169 63.817968)
        (xy 147.28716 63.848872)
        (xy 147.256255 63.876881)
        (xy 147.222756 63.901726)
        (xy 147.186983 63.923168)
        (xy 147.14928 63.941)
        (xy 147.11001 63.955051)
        (xy 147.069553 63.965185)
        (xy 147.028297 63.971305)
        (xy 146.98664 63.973352)
        (xy 146.957747 63.971932)
        (xy 146.447587 63.971073)
        (xy 146.441657 63.971953)
        (xy 146.399999 63.974)
        (xy 146.358342 63.971953)
        (xy 146.317087 63.965834)
        (xy 146.27663 63.955699)
        (xy 146.23736 63.941648)
        (xy 146.199657 63.923817)
        (xy 146.163883 63.902374)
        (xy 146.130383 63.877529)
        (xy 146.09948 63.84952)
        (xy 146.071471 63.818617)
        (xy 146.046626 63.785117)
        (xy 146.025183 63.749343)
        (xy 146.007352 63.71164)
        (xy 145.993301 63.67237)
        (xy 145.983166 63.631913)
        (xy 145.977046 63.590657)
        (xy 145.975 63.549001)
      )
    )
  )
  (zone (net 0) (net_name "") (layers "In1.Cu" "In3.Cu" "In5.Cu" "In6.Cu") (hatch edge 0.508)
    (connect_pads yes (clearance 0))
    (min_thickness 0.1) (filled_areas_thickness no)
    (keepout (tracks allowed) (vias allowed) (pads allowed) (copperpour not_allowed) (footprints allowed))
    (fill (thermal_gap 0.254) (thermal_bridge_width 0.254))
    (polygon
      (pts
        (xy 112.49846 72.55027)
        (xy 112.50458 72.509014)
        (xy 112.514714 72.468557)
        (xy 112.528765 72.429287)
        (xy 112.546597 72.391584)
        (xy 112.568039 72.35581)
        (xy 112.592884 72.32231)
        (xy 112.620893 72.291407)
        (xy 112.651796 72.263398)
        (xy 112.685295 72.238553)
        (xy 112.72107 72.217111)
        (xy 112.758773 72.19928)
        (xy 112.798043 72.185228)
        (xy 112.8385 72.175094)
        (xy 112.879756 72.168974)
        (xy 112.921413 72.166927)
        (xy 112.925412 72.167124)
        (xy 112.925413 72.166927)
        (xy 113.49486 72.166927)
        (xy 113.508054 72.166279)
        (xy 113.549709 72.168326)
        (xy 113.590966 72.174446)
        (xy 113.631423 72.18458)
        (xy 113.670693 72.198631)
        (xy 113.708395 72.216463)
        (xy 113.74417 72.237905)
        (xy 113.77767 72.26275)
        (xy 113.808573 72.290759)
        (xy 113.836582 72.321661)
        (xy 113.861428 72.355162)
        (xy 113.882868 72.390936)
        (xy 113.900701 72.42864)
        (xy 113.914752 72.467909)
        (xy 113.924885 72.508366)
        (xy 113.931005 72.549622)
        (xy 113.933053 72.591278)
        (xy 113.931006 72.632936)
        (xy 113.924886 72.674192)
        (xy 113.914752 72.714649)
        (xy 113.900701 72.753919)
        (xy 113.882869 72.791622)
        (xy 113.861427 72.827396)
        (xy 113.836582 72.860895)
        (xy 113.808573 72.891799)
        (xy 113.777668 72.919808)
        (xy 113.744169 72.944653)
        (xy 113.708396 72.966095)
        (xy 113.670693 72.983927)
        (xy 113.631423 72.997978)
        (xy 113.590966 73.008112)
        (xy 113.54971 73.014232)
        (xy 113.508053 73.016279)
        (xy 113.47916 73.014859)
        (xy 112.969 73.014)
        (xy 112.96307 73.01488)
        (xy 112.921412 73.016927)
        (xy 112.879755 73.01488)
        (xy 112.8385 73.008761)
        (xy 112.798043 72.998626)
        (xy 112.758773 72.984575)
        (xy 112.72107 72.966744)
        (xy 112.685296 72.945301)
        (xy 112.651796 72.920456)
        (xy 112.620893 72.892447)
        (xy 112.592884 72.861544)
        (xy 112.568039 72.828044)
        (xy 112.546596 72.79227)
        (xy 112.528765 72.754567)
        (xy 112.514714 72.715297)
        (xy 112.504579 72.67484)
        (xy 112.498459 72.633584)
        (xy 112.496413 72.591928)
      )
    )
  )
  (zone (net 0) (net_name "") (layers "In1.Cu" "In3.Cu" "In5.Cu" "In6.Cu") (hatch edge 0.508)
    (connect_pads yes (clearance 0))
    (min_thickness 0.1) (filled_areas_thickness no)
    (keepout (tracks allowed) (vias allowed) (pads allowed) (copperpour not_allowed) (footprints allowed))
    (fill (thermal_gap 0.254) (thermal_bridge_width 0.254))
    (polygon
      (pts
        (xy 149.127047 84.057343)
        (xy 149.133167 84.016087)
        (xy 149.143301 83.97563)
        (xy 149.157352 83.93636)
        (xy 149.175184 83.898657)
        (xy 149.196626 83.862883)
        (xy 149.221471 83.829383)
        (xy 149.24948 83.79848)
        (xy 149.280383 83.770471)
        (xy 149.313882 83.745626)
        (xy 149.349657 83.724184)
        (xy 149.38736 83.706353)
        (xy 149.42663 83.692301)
        (xy 149.467087 83.682167)
        (xy 149.508343 83.676047)
        (xy 149.55 83.674)
        (xy 149.553999 83.674197)
        (xy 149.554 83.674)
        (xy 150.123447 83.674)
        (xy 150.136641 83.673352)
        (xy 150.178296 83.675399)
        (xy 150.219553 83.681519)
        (xy 150.26001 83.691653)
        (xy 150.29928 83.705704)
        (xy 150.336982 83.723536)
        (xy 150.372757 83.744978)
        (xy 150.406257 83.769823)
        (xy 150.43716 83.797832)
        (xy 150.465169 83.828734)
        (xy 150.490015 83.862235)
        (xy 150.511455 83.898009)
        (xy 150.529288 83.935713)
        (xy 150.543339 83.974982)
        (xy 150.553472 84.015439)
        (xy 150.559592 84.056695)
        (xy 150.56164 84.098351)
        (xy 150.559593 84.140009)
        (xy 150.553473 84.181265)
        (xy 150.543339 84.221722)
        (xy 150.529288 84.260992)
        (xy 150.511456 84.298695)
        (xy 150.490014 84.334469)
        (xy 150.465169 84.367968)
        (xy 150.43716 84.398872)
        (xy 150.406255 84.426881)
        (xy 150.372756 84.451726)
        (xy 150.336983 84.473168)
        (xy 150.29928 84.491)
        (xy 150.26001 84.505051)
        (xy 150.219553 84.515185)
        (xy 150.178297 84.521305)
        (xy 150.13664 84.523352)
        (xy 150.107747 84.521932)
        (xy 149.597587 84.521073)
        (xy 149.591657 84.521953)
        (xy 149.549999 84.524)
        (xy 149.508342 84.521953)
        (xy 149.467087 84.515834)
        (xy 149.42663 84.505699)
        (xy 149.38736 84.491648)
        (xy 149.349657 84.473817)
        (xy 149.313883 84.452374)
        (xy 149.280383 84.427529)
        (xy 149.24948 84.39952)
        (xy 149.221471 84.368617)
        (xy 149.196626 84.335117)
        (xy 149.175183 84.299343)
        (xy 149.157352 84.26164)
        (xy 149.143301 84.22237)
        (xy 149.133166 84.181913)
        (xy 149.127046 84.140657)
        (xy 149.125 84.099001)
      )
    )
  )
  (zone (net 0) (net_name "") (layers "In1.Cu" "In3.Cu" "In5.Cu" "In6.Cu") (hatch edge 0.508)
    (connect_pads yes (clearance 0))
    (min_thickness 0.1) (filled_areas_thickness no)
    (keepout (tracks allowed) (vias allowed) (pads allowed) (copperpour not_allowed) (footprints allowed))
    (fill (thermal_gap 0.254) (thermal_bridge_width 0.254))
    (polygon
      (pts
        (xy 134.377047 72.447343)
        (xy 134.383167 72.406087)
        (xy 134.393301 72.36563)
        (xy 134.407352 72.32636)
        (xy 134.425184 72.288657)
        (xy 134.446626 72.252883)
        (xy 134.471471 72.219383)
        (xy 134.49948 72.18848)
        (xy 134.530383 72.160471)
        (xy 134.563882 72.135626)
        (xy 134.599657 72.114184)
        (xy 134.63736 72.096353)
        (xy 134.67663 72.082301)
        (xy 134.717087 72.072167)
        (xy 134.758343 72.066047)
        (xy 134.8 72.064)
        (xy 134.803999 72.064197)
        (xy 134.804 72.064)
        (xy 135.373447 72.064)
        (xy 135.386641 72.063352)
        (xy 135.428296 72.065399)
        (xy 135.469553 72.071519)
        (xy 135.51001 72.081653)
        (xy 135.54928 72.095704)
        (xy 135.586982 72.113536)
        (xy 135.622757 72.134978)
        (xy 135.656257 72.159823)
        (xy 135.68716 72.187832)
        (xy 135.715169 72.218734)
        (xy 135.740015 72.252235)
        (xy 135.761455 72.288009)
        (xy 135.779288 72.325713)
        (xy 135.793339 72.364982)
        (xy 135.803472 72.405439)
        (xy 135.809592 72.446695)
        (xy 135.81164 72.488351)
        (xy 135.809593 72.530009)
        (xy 135.803473 72.571265)
        (xy 135.793339 72.611722)
        (xy 135.779288 72.650992)
        (xy 135.761456 72.688695)
        (xy 135.740014 72.724469)
        (xy 135.715169 72.757968)
        (xy 135.68716 72.788872)
        (xy 135.656255 72.816881)
        (xy 135.622756 72.841726)
        (xy 135.586983 72.863168)
        (xy 135.54928 72.881)
        (xy 135.51001 72.895051)
        (xy 135.469553 72.905185)
        (xy 135.428297 72.911305)
        (xy 135.38664 72.913352)
        (xy 135.357747 72.911932)
        (xy 134.847587 72.911073)
        (xy 134.841657 72.911953)
        (xy 134.799999 72.914)
        (xy 134.758342 72.911953)
        (xy 134.717087 72.905834)
        (xy 134.67663 72.895699)
        (xy 134.63736 72.881648)
        (xy 134.599657 72.863817)
        (xy 134.563883 72.842374)
        (xy 134.530383 72.817529)
        (xy 134.49948 72.78952)
        (xy 134.471471 72.758617)
        (xy 134.446626 72.725117)
        (xy 134.425183 72.689343)
        (xy 134.407352 72.65164)
        (xy 134.393301 72.61237)
        (xy 134.383166 72.571913)
        (xy 134.377046 72.530657)
        (xy 134.375 72.489001)
      )
    )
  )
  (zone (net 0) (net_name "") (layers "In1.Cu" "In3.Cu" "In5.Cu" "In6.Cu") (hatch edge 0.508)
    (connect_pads yes (clearance 0))
    (min_thickness 0.1) (filled_areas_thickness no)
    (keepout (tracks allowed) (vias allowed) (pads allowed) (copperpour not_allowed) (footprints allowed))
    (fill (thermal_gap 0.254) (thermal_bridge_width 0.254))
    (polygon
      (pts
        (xy 143.617047 140.347343)
        (xy 143.623167 140.306087)
        (xy 143.633301 140.26563)
        (xy 143.647352 140.22636)
        (xy 143.665184 140.188657)
        (xy 143.686626 140.152883)
        (xy 143.711471 140.119383)
        (xy 143.73948 140.08848)
        (xy 143.770383 140.060471)
        (xy 143.803882 140.035626)
        (xy 143.839657 140.014184)
        (xy 143.87736 139.996353)
        (xy 143.91663 139.982301)
        (xy 143.957087 139.972167)
        (xy 143.998343 139.966047)
        (xy 144.04 139.964)
        (xy 144.043999 139.964197)
        (xy 144.044 139.964)
        (xy 144.613447 139.964)
        (xy 144.626641 139.963352)
        (xy 144.668296 139.965399)
        (xy 144.709553 139.971519)
        (xy 144.75001 139.981653)
        (xy 144.78928 139.995704)
        (xy 144.826982 140.013536)
        (xy 144.862757 140.034978)
        (xy 144.896257 140.059823)
        (xy 144.92716 140.087832)
        (xy 144.955169 140.118734)
        (xy 144.980015 140.152235)
        (xy 145.001455 140.188009)
        (xy 145.019288 140.225713)
        (xy 145.033339 140.264982)
        (xy 145.043472 140.305439)
        (xy 145.049592 140.346695)
        (xy 145.05164 140.388351)
        (xy 145.049593 140.430009)
        (xy 145.043473 140.471265)
        (xy 145.033339 140.511722)
        (xy 145.019288 140.550992)
        (xy 145.001456 140.588695)
        (xy 144.980014 140.624469)
        (xy 144.955169 140.657968)
        (xy 144.92716 140.688872)
        (xy 144.896255 140.716881)
        (xy 144.862756 140.741726)
        (xy 144.826983 140.763168)
        (xy 144.78928 140.781)
        (xy 144.75001 140.795051)
        (xy 144.709553 140.805185)
        (xy 144.668297 140.811305)
        (xy 144.62664 140.813352)
        (xy 144.597747 140.811932)
        (xy 144.087587 140.811073)
        (xy 144.081657 140.811953)
        (xy 144.039999 140.814)
        (xy 143.998342 140.811953)
        (xy 143.957087 140.805834)
        (xy 143.91663 140.795699)
        (xy 143.87736 140.781648)
        (xy 143.839657 140.763817)
        (xy 143.803883 140.742374)
        (xy 143.770383 140.717529)
        (xy 143.73948 140.68952)
        (xy 143.711471 140.658617)
        (xy 143.686626 140.625117)
        (xy 143.665183 140.589343)
        (xy 143.647352 140.55164)
        (xy 143.633301 140.51237)
        (xy 143.623166 140.471913)
        (xy 143.617046 140.430657)
        (xy 143.615 140.389001)
      )
    )
  )
  (zone (net 0) (net_name "") (layers "In1.Cu" "In3.Cu" "In5.Cu" "In6.Cu") (hatch edge 0.508)
    (connect_pads yes (clearance 0))
    (min_thickness 0.1) (filled_areas_thickness no)
    (keepout (tracks allowed) (vias allowed) (pads allowed) (copperpour not_allowed) (footprints allowed))
    (fill (thermal_gap 0.254) (thermal_bridge_width 0.254))
    (polygon
      (pts
        (xy 114.503263 123.587)
        (xy 115.269387 123.587)
        (xy 115.270343 123.586953)
        (xy 115.312 123.589)
        (xy 115.353256 123.59512)
        (xy 115.393713 123.605254)
        (xy 115.432983 123.619305)
        (xy 115.470686 123.637137)
        (xy 115.50646 123.658579)
        (xy 115.53996 123.683424)
        (xy 115.570863 123.711433)
        (xy 115.598872 123.742336)
        (xy 115.623717 123.775836)
        (xy 115.645159 123.81161)
        (xy 115.662991 123.849313)
        (xy 115.677042 123.888583)
        (xy 115.687176 123.92904)
        (xy 115.693296 123.970296)
        (xy 115.695343 124.011953)
        (xy 115.693296 124.05361)
        (xy 115.687176 124.094866)
        (xy 115.677042 124.135323)
        (xy 115.662991 124.174593)
        (xy 115.645159 124.212296)
        (xy 115.623717 124.24807)
        (xy 115.598872 124.28157)
        (xy 115.570863 124.312473)
        (xy 115.53996 124.340482)
        (xy 115.50646 124.365327)
        (xy 115.470686 124.386769)
        (xy 115.432983 124.404601)
        (xy 115.393713 124.418652)
        (xy 115.353256 124.428786)
        (xy 115.312 124.434906)
        (xy 115.271 124.436921)
        (xy 115.271 124.437)
        (xy 114.490315 124.436004)
        (xy 114.486657 124.436184)
        (xy 114.445 124.434137)
        (xy 114.403744 124.428017)
        (xy 114.363287 124.417883)
        (xy 114.324017 124.403832)
        (xy 114.286314 124.386)
        (xy 114.25054 124.364558)
        (xy 114.21704 124.339713)
        (xy 114.186137 124.311704)
        (xy 114.158128 124.280801)
        (xy 114.133283 124.247301)
        (xy 114.111841 124.211527)
        (xy 114.094009 124.173824)
        (xy 114.079958 124.134554)
        (xy 114.069824 124.094097)
        (xy 114.063704 124.052841)
        (xy 114.061657 124.011184)
        (xy 114.063704 123.969527)
        (xy 114.069824 123.928271)
        (xy 114.079958 123.887814)
        (xy 114.094009 123.848544)
        (xy 114.111841 123.810841)
        (xy 114.133283 123.775067)
        (xy 114.158128 123.741567)
        (xy 114.186137 123.710664)
        (xy 114.21704 123.682655)
        (xy 114.25054 123.65781)
        (xy 114.286314 123.636368)
        (xy 114.324017 123.618536)
        (xy 114.363287 123.604485)
        (xy 114.403744 123.594351)
        (xy 114.445 123.588231)
        (xy 114.486657 123.586184)
      )
    )
  )
  (zone (net 0) (net_name "") (layers "In1.Cu" "In3.Cu" "In5.Cu" "In6.Cu") (hatch edge 0.508)
    (connect_pads yes (clearance 0))
    (min_thickness 0.1) (filled_areas_thickness no)
    (keepout (tracks allowed) (vias allowed) (pads allowed) (copperpour not_allowed) (footprints allowed))
    (fill (thermal_gap 0.254) (thermal_bridge_width 0.254))
    (polygon
      (pts
        (xy 129.786657 84.6136)
        (xy 129.827913 84.61972)
        (xy 129.86837 84.629854)
        (xy 129.90764 84.643905)
        (xy 129.945343 84.661737)
        (xy 129.981117 84.683179)
        (xy 130.014617 84.708024)
        (xy 130.04552 84.736033)
        (xy 130.073529 84.766936)
        (xy 130.098374 84.800435)
        (xy 130.119816 84.83621)
        (xy 130.137647 84.873913)
        (xy 130.151699 84.913183)
        (xy 130.161833 84.95364)
        (xy 130.167953 84.994896)
        (xy 130.17 85.036553)
        (xy 130.169803 85.040553)
        (xy 130.17 85.040553)
        (xy 130.17 85.61)
        (xy 130.170648 85.623193)
        (xy 130.168601 85.664849)
        (xy 130.162481 85.706106)
        (xy 130.152347 85.746563)
        (xy 130.138296 85.785833)
        (xy 130.120464 85.823535)
        (xy 130.099022 85.85931)
        (xy 130.074177 85.89281)
        (xy 130.046168 85.923713)
        (xy 130.015266 85.951722)
        (xy 129.981765 85.976568)
        (xy 129.945991 85.998008)
        (xy 129.908287 86.015841)
        (xy 129.869018 86.029892)
        (xy 129.828561 86.040025)
        (xy 129.787305 86.046145)
        (xy 129.745648 86.048193)
        (xy 129.703991 86.046146)
        (xy 129.662735 86.040026)
        (xy 129.622278 86.029892)
        (xy 129.583008 86.015841)
        (xy 129.545305 85.998009)
        (xy 129.509531 85.976567)
        (xy 129.476032 85.951722)
        (xy 129.445128 85.923713)
        (xy 129.417119 85.892809)
        (xy 129.392274 85.859309)
        (xy 129.370832 85.823536)
        (xy 129.353 85.785833)
        (xy 129.338949 85.746563)
        (xy 129.328815 85.706106)
        (xy 129.322695 85.66485)
        (xy 129.320648 85.623193)
        (xy 129.322068 85.5943)
        (xy 129.322927 85.08414)
        (xy 129.322047 85.07821)
        (xy 129.32 85.036553)
        (xy 129.322047 84.994895)
        (xy 129.328166 84.95364)
        (xy 129.338301 84.913183)
        (xy 129.352352 84.873913)
        (xy 129.370183 84.83621)
        (xy 129.391626 84.800436)
        (xy 129.416471 84.766936)
        (xy 129.44448 84.736033)
        (xy 129.475383 84.708024)
        (xy 129.508883 84.683179)
        (xy 129.544657 84.661736)
        (xy 129.58236 84.643905)
        (xy 129.62163 84.629854)
        (xy 129.662087 84.619719)
        (xy 129.703343 84.613599)
        (xy 129.745 84.611553)
      )
    )
  )
  (zone (net 0) (net_name "") (layers "In1.Cu" "In3.Cu" "In5.Cu" "In6.Cu") (hatch edge 0.508)
    (connect_pads yes (clearance 0))
    (min_thickness 0.1) (filled_areas_thickness no)
    (keepout (tracks allowed) (vias allowed) (pads allowed) (copperpour not_allowed) (footprints allowed))
    (fill (thermal_gap 0.254) (thermal_bridge_width 0.254))
    (polygon
      (pts
        (xy 120.987047 92.137343)
        (xy 120.993167 92.096087)
        (xy 121.003301 92.05563)
        (xy 121.017352 92.01636)
        (xy 121.035184 91.978657)
        (xy 121.056626 91.942883)
        (xy 121.081471 91.909383)
        (xy 121.10948 91.87848)
        (xy 121.140383 91.850471)
        (xy 121.173882 91.825626)
        (xy 121.209657 91.804184)
        (xy 121.24736 91.786353)
        (xy 121.28663 91.772301)
        (xy 121.327087 91.762167)
        (xy 121.368343 91.756047)
        (xy 121.41 91.754)
        (xy 121.413999 91.754197)
        (xy 121.414 91.754)
        (xy 121.983447 91.754)
        (xy 121.996641 91.753352)
        (xy 122.038296 91.755399)
        (xy 122.079553 91.761519)
        (xy 122.12001 91.771653)
        (xy 122.15928 91.785704)
        (xy 122.196982 91.803536)
        (xy 122.232757 91.824978)
        (xy 122.266257 91.849823)
        (xy 122.29716 91.877832)
        (xy 122.325169 91.908734)
        (xy 122.350015 91.942235)
        (xy 122.371455 91.978009)
        (xy 122.389288 92.015713)
        (xy 122.403339 92.054982)
        (xy 122.413472 92.095439)
        (xy 122.419592 92.136695)
        (xy 122.42164 92.178351)
        (xy 122.419593 92.220009)
        (xy 122.413473 92.261265)
        (xy 122.403339 92.301722)
        (xy 122.389288 92.340992)
        (xy 122.371456 92.378695)
        (xy 122.350014 92.414469)
        (xy 122.325169 92.447968)
        (xy 122.29716 92.478872)
        (xy 122.266255 92.506881)
        (xy 122.232756 92.531726)
        (xy 122.196983 92.553168)
        (xy 122.15928 92.571)
        (xy 122.12001 92.585051)
        (xy 122.079553 92.595185)
        (xy 122.038297 92.601305)
        (xy 121.99664 92.603352)
        (xy 121.967747 92.601932)
        (xy 121.457587 92.601073)
        (xy 121.451657 92.601953)
        (xy 121.409999 92.604)
        (xy 121.368342 92.601953)
        (xy 121.327087 92.595834)
        (xy 121.28663 92.585699)
        (xy 121.24736 92.571648)
        (xy 121.209657 92.553817)
        (xy 121.173883 92.532374)
        (xy 121.140383 92.507529)
        (xy 121.10948 92.47952)
        (xy 121.081471 92.448617)
        (xy 121.056626 92.415117)
        (xy 121.035183 92.379343)
        (xy 121.017352 92.34164)
        (xy 121.003301 92.30237)
        (xy 120.993166 92.261913)
        (xy 120.987046 92.220657)
        (xy 120.985 92.179001)
      )
    )
  )
  (zone (net 0) (net_name "") (layers "In1.Cu" "In3.Cu" "In5.Cu" "In6.Cu") (hatch edge 0.508)
    (connect_pads yes (clearance 0))
    (min_thickness 0.1) (filled_areas_thickness no)
    (keepout (tracks allowed) (vias allowed) (pads allowed) (copperpour not_allowed) (footprints allowed))
    (fill (thermal_gap 0.254) (thermal_bridge_width 0.254))
    (polygon
      (pts
        (xy 129.792657 86.207047)
        (xy 129.833913 86.213167)
        (xy 129.87437 86.223301)
        (xy 129.91364 86.237352)
        (xy 129.951343 86.255184)
        (xy 129.987117 86.276626)
        (xy 130.020617 86.301471)
        (xy 130.05152 86.32948)
        (xy 130.079529 86.360383)
        (xy 130.104374 86.393882)
        (xy 130.125816 86.429657)
        (xy 130.143647 86.46736)
        (xy 130.157699 86.50663)
        (xy 130.167833 86.547087)
        (xy 130.173953 86.588343)
        (xy 130.176 86.63)
        (xy 130.175803 86.634)
        (xy 130.176 86.634)
        (xy 130.176 87.203447)
        (xy 130.176648 87.21664)
        (xy 130.174601 87.258296)
        (xy 130.168481 87.299553)
        (xy 130.158347 87.34001)
        (xy 130.144296 87.37928)
        (xy 130.126464 87.416982)
        (xy 130.105022 87.452757)
        (xy 130.080177 87.486257)
        (xy 130.052168 87.51716)
        (xy 130.021266 87.545169)
        (xy 129.987765 87.570015)
        (xy 129.951991 87.591455)
        (xy 129.914287 87.609288)
        (xy 129.875018 87.623339)
        (xy 129.834561 87.633472)
        (xy 129.793305 87.639592)
        (xy 129.751648 87.64164)
        (xy 129.709991 87.639593)
        (xy 129.668735 87.633473)
        (xy 129.628278 87.623339)
        (xy 129.589008 87.609288)
        (xy 129.551305 87.591456)
        (xy 129.515531 87.570014)
        (xy 129.482032 87.545169)
        (xy 129.451128 87.51716)
        (xy 129.423119 87.486256)
        (xy 129.398274 87.452756)
        (xy 129.376832 87.416983)
        (xy 129.359 87.37928)
        (xy 129.344949 87.34001)
        (xy 129.334815 87.299553)
        (xy 129.328695 87.258297)
        (xy 129.326648 87.21664)
        (xy 129.328068 87.187747)
        (xy 129.328927 86.677587)
        (xy 129.328047 86.671657)
        (xy 129.326 86.63)
        (xy 129.328047 86.588342)
        (xy 129.334166 86.547087)
        (xy 129.344301 86.50663)
        (xy 129.358352 86.46736)
        (xy 129.376183 86.429657)
        (xy 129.397626 86.393883)
        (xy 129.422471 86.360383)
        (xy 129.45048 86.32948)
        (xy 129.481383 86.301471)
        (xy 129.514883 86.276626)
        (xy 129.550657 86.255183)
        (xy 129.58836 86.237352)
        (xy 129.62763 86.223301)
        (xy 129.668087 86.213166)
        (xy 129.709343 86.207046)
        (xy 129.751 86.205)
      )
    )
  )
  (zone (net 0) (net_name "") (layers "In1.Cu" "In3.Cu" "In5.Cu" "In6.Cu") (hatch edge 0.508)
    (connect_pads yes (clearance 0))
    (min_thickness 0.1) (filled_areas_thickness no)
    (keepout (tracks allowed) (vias allowed) (pads allowed) (copperpour not_allowed) (footprints allowed))
    (fill (thermal_gap 0.254) (thermal_bridge_width 0.254))
    (polygon
      (pts
        (xy 108.122657 75.567047)
        (xy 108.163913 75.573167)
        (xy 108.20437 75.583301)
        (xy 108.24364 75.597352)
        (xy 108.281343 75.615184)
        (xy 108.317117 75.636626)
        (xy 108.350617 75.661471)
        (xy 108.38152 75.68948)
        (xy 108.409529 75.720383)
        (xy 108.434374 75.753882)
        (xy 108.455816 75.789657)
        (xy 108.473647 75.82736)
        (xy 108.487699 75.86663)
        (xy 108.497833 75.907087)
        (xy 108.503953 75.948343)
        (xy 108.506 75.99)
        (xy 108.505803 75.994)
        (xy 108.506 75.994)
        (xy 108.506 76.563447)
        (xy 108.506648 76.57664)
        (xy 108.504601 76.618296)
        (xy 108.498481 76.659553)
        (xy 108.488347 76.70001)
        (xy 108.474296 76.73928)
        (xy 108.456464 76.776982)
        (xy 108.435022 76.812757)
        (xy 108.410177 76.846257)
        (xy 108.382168 76.87716)
        (xy 108.351266 76.905169)
        (xy 108.317765 76.930015)
        (xy 108.281991 76.951455)
        (xy 108.244287 76.969288)
        (xy 108.205018 76.983339)
        (xy 108.164561 76.993472)
        (xy 108.123305 76.999592)
        (xy 108.081648 77.00164)
        (xy 108.039991 76.999593)
        (xy 107.998735 76.993473)
        (xy 107.958278 76.983339)
        (xy 107.919008 76.969288)
        (xy 107.881305 76.951456)
        (xy 107.845531 76.930014)
        (xy 107.812032 76.905169)
        (xy 107.781128 76.87716)
        (xy 107.753119 76.846256)
        (xy 107.728274 76.812756)
        (xy 107.706832 76.776983)
        (xy 107.689 76.73928)
        (xy 107.674949 76.70001)
        (xy 107.664815 76.659553)
        (xy 107.658695 76.618297)
        (xy 107.656648 76.57664)
        (xy 107.658068 76.547747)
        (xy 107.658927 76.037587)
        (xy 107.658047 76.031657)
        (xy 107.656 75.99)
        (xy 107.658047 75.948342)
        (xy 107.664166 75.907087)
        (xy 107.674301 75.86663)
        (xy 107.688352 75.82736)
        (xy 107.706183 75.789657)
        (xy 107.727626 75.753883)
        (xy 107.752471 75.720383)
        (xy 107.78048 75.68948)
        (xy 107.811383 75.661471)
        (xy 107.844883 75.636626)
        (xy 107.880657 75.615183)
        (xy 107.91836 75.597352)
        (xy 107.95763 75.583301)
        (xy 107.998087 75.573166)
        (xy 108.039343 75.567046)
        (xy 108.081 75.565)
      )
    )
  )
  (zone (net 0) (net_name "") (layers "In1.Cu" "In3.Cu" "In5.Cu" "In6.Cu") (hatch edge 0.508)
    (connect_pads yes (clearance 0))
    (min_thickness 0.1) (filled_areas_thickness no)
    (keepout (tracks allowed) (vias allowed) (pads allowed) (copperpour not_allowed) (footprints allowed))
    (fill (thermal_gap 0.254) (thermal_bridge_width 0.254))
    (polygon
      (pts
        (xy 112.467047 76.557343)
        (xy 112.473167 76.516087)
        (xy 112.483301 76.47563)
        (xy 112.497352 76.43636)
        (xy 112.515184 76.398657)
        (xy 112.536626 76.362883)
        (xy 112.561471 76.329383)
        (xy 112.58948 76.29848)
        (xy 112.620383 76.270471)
        (xy 112.653882 76.245626)
        (xy 112.689657 76.224184)
        (xy 112.72736 76.206353)
        (xy 112.76663 76.192301)
        (xy 112.807087 76.182167)
        (xy 112.848343 76.176047)
        (xy 112.89 76.174)
        (xy 112.893999 76.174197)
        (xy 112.894 76.174)
        (xy 113.463447 76.174)
        (xy 113.476641 76.173352)
        (xy 113.518296 76.175399)
        (xy 113.559553 76.181519)
        (xy 113.60001 76.191653)
        (xy 113.63928 76.205704)
        (xy 113.676982 76.223536)
        (xy 113.712757 76.244978)
        (xy 113.746257 76.269823)
        (xy 113.77716 76.297832)
        (xy 113.805169 76.328734)
        (xy 113.830015 76.362235)
        (xy 113.851455 76.398009)
        (xy 113.869288 76.435713)
        (xy 113.883339 76.474982)
        (xy 113.893472 76.515439)
        (xy 113.899592 76.556695)
        (xy 113.90164 76.598351)
        (xy 113.899593 76.640009)
        (xy 113.893473 76.681265)
        (xy 113.883339 76.721722)
        (xy 113.869288 76.760992)
        (xy 113.851456 76.798695)
        (xy 113.830014 76.834469)
        (xy 113.805169 76.867968)
        (xy 113.77716 76.898872)
        (xy 113.746255 76.926881)
        (xy 113.712756 76.951726)
        (xy 113.676983 76.973168)
        (xy 113.63928 76.991)
        (xy 113.60001 77.005051)
        (xy 113.559553 77.015185)
        (xy 113.518297 77.021305)
        (xy 113.47664 77.023352)
        (xy 113.447747 77.021932)
        (xy 112.937587 77.021073)
        (xy 112.931657 77.021953)
        (xy 112.889999 77.024)
        (xy 112.848342 77.021953)
        (xy 112.807087 77.015834)
        (xy 112.76663 77.005699)
        (xy 112.72736 76.991648)
        (xy 112.689657 76.973817)
        (xy 112.653883 76.952374)
        (xy 112.620383 76.927529)
        (xy 112.58948 76.89952)
        (xy 112.561471 76.868617)
        (xy 112.536626 76.835117)
        (xy 112.515183 76.799343)
        (xy 112.497352 76.76164)
        (xy 112.483301 76.72237)
        (xy 112.473166 76.681913)
        (xy 112.467046 76.640657)
        (xy 112.465 76.599001)
      )
    )
  )
  (zone (net 0) (net_name "") (layers "In1.Cu" "In3.Cu" "In5.Cu" "In6.Cu") (hatch edge 0.508)
    (connect_pads yes (clearance 0))
    (min_thickness 0.1) (filled_areas_thickness no)
    (keepout (tracks allowed) (vias allowed) (pads allowed) (copperpour not_allowed) (footprints allowed))
    (fill (thermal_gap 0.254) (thermal_bridge_width 0.254))
    (polygon
      (pts
        (xy 143.657047 145.167343)
        (xy 143.663167 145.126087)
        (xy 143.673301 145.08563)
        (xy 143.687352 145.04636)
        (xy 143.705184 145.008657)
        (xy 143.726626 144.972883)
        (xy 143.751471 144.939383)
        (xy 143.77948 144.90848)
        (xy 143.810383 144.880471)
        (xy 143.843882 144.855626)
        (xy 143.879657 144.834184)
        (xy 143.91736 144.816353)
        (xy 143.95663 144.802301)
        (xy 143.997087 144.792167)
        (xy 144.038343 144.786047)
        (xy 144.08 144.784)
        (xy 144.083999 144.784197)
        (xy 144.084 144.784)
        (xy 144.653447 144.784)
        (xy 144.666641 144.783352)
        (xy 144.708296 144.785399)
        (xy 144.749553 144.791519)
        (xy 144.79001 144.801653)
        (xy 144.82928 144.815704)
        (xy 144.866982 144.833536)
        (xy 144.902757 144.854978)
        (xy 144.936257 144.879823)
        (xy 144.96716 144.907832)
        (xy 144.995169 144.938734)
        (xy 145.020015 144.972235)
        (xy 145.041455 145.008009)
        (xy 145.059288 145.045713)
        (xy 145.073339 145.084982)
        (xy 145.083472 145.125439)
        (xy 145.089592 145.166695)
        (xy 145.09164 145.208351)
        (xy 145.089593 145.250009)
        (xy 145.083473 145.291265)
        (xy 145.073339 145.331722)
        (xy 145.059288 145.370992)
        (xy 145.041456 145.408695)
        (xy 145.020014 145.444469)
        (xy 144.995169 145.477968)
        (xy 144.96716 145.508872)
        (xy 144.936255 145.536881)
        (xy 144.902756 145.561726)
        (xy 144.866983 145.583168)
        (xy 144.82928 145.601)
        (xy 144.79001 145.615051)
        (xy 144.749553 145.625185)
        (xy 144.708297 145.631305)
        (xy 144.66664 145.633352)
        (xy 144.637747 145.631932)
        (xy 144.127587 145.631073)
        (xy 144.121657 145.631953)
        (xy 144.079999 145.634)
        (xy 144.038342 145.631953)
        (xy 143.997087 145.625834)
        (xy 143.95663 145.615699)
        (xy 143.91736 145.601648)
        (xy 143.879657 145.583817)
        (xy 143.843883 145.562374)
        (xy 143.810383 145.537529)
        (xy 143.77948 145.50952)
        (xy 143.751471 145.478617)
        (xy 143.726626 145.445117)
        (xy 143.705183 145.409343)
        (xy 143.687352 145.37164)
        (xy 143.673301 145.33237)
        (xy 143.663166 145.291913)
        (xy 143.657046 145.250657)
        (xy 143.655 145.209001)
      )
    )
  )
  (zone (net 0) (net_name "") (layers "In1.Cu" "In3.Cu" "In5.Cu" "In6.Cu") (hatch edge 0.508)
    (connect_pads yes (clearance 0))
    (min_thickness 0.1) (filled_areas_thickness no)
    (keepout (tracks allowed) (vias allowed) (pads allowed) (copperpour not_allowed) (footprints allowed))
    (fill (thermal_gap 0.254) (thermal_bridge_width 0.254))
    (polygon
      (pts
        (xy 147.017047 106.107343)
        (xy 147.023167 106.066087)
        (xy 147.033301 106.02563)
        (xy 147.047352 105.98636)
        (xy 147.065184 105.948657)
        (xy 147.086626 105.912883)
        (xy 147.111471 105.879383)
        (xy 147.13948 105.84848)
        (xy 147.170383 105.820471)
        (xy 147.203882 105.795626)
        (xy 147.239657 105.774184)
        (xy 147.27736 105.756353)
        (xy 147.31663 105.742301)
        (xy 147.357087 105.732167)
        (xy 147.398343 105.726047)
        (xy 147.44 105.724)
        (xy 147.443999 105.724197)
        (xy 147.444 105.724)
        (xy 148.013447 105.724)
        (xy 148.026641 105.723352)
        (xy 148.068296 105.725399)
        (xy 148.109553 105.731519)
        (xy 148.15001 105.741653)
        (xy 148.18928 105.755704)
        (xy 148.226982 105.773536)
        (xy 148.262757 105.794978)
        (xy 148.296257 105.819823)
        (xy 148.32716 105.847832)
        (xy 148.355169 105.878734)
        (xy 148.380015 105.912235)
        (xy 148.401455 105.948009)
        (xy 148.419288 105.985713)
        (xy 148.433339 106.024982)
        (xy 148.443472 106.065439)
        (xy 148.449592 106.106695)
        (xy 148.45164 106.148351)
        (xy 148.449593 106.190009)
        (xy 148.443473 106.231265)
        (xy 148.433339 106.271722)
        (xy 148.419288 106.310992)
        (xy 148.401456 106.348695)
        (xy 148.380014 106.384469)
        (xy 148.355169 106.417968)
        (xy 148.32716 106.448872)
        (xy 148.296255 106.476881)
        (xy 148.262756 106.501726)
        (xy 148.226983 106.523168)
        (xy 148.18928 106.541)
        (xy 148.15001 106.555051)
        (xy 148.109553 106.565185)
        (xy 148.068297 106.571305)
        (xy 148.02664 106.573352)
        (xy 147.997747 106.571932)
        (xy 147.487587 106.571073)
        (xy 147.481657 106.571953)
        (xy 147.439999 106.574)
        (xy 147.398342 106.571953)
        (xy 147.357087 106.565834)
        (xy 147.31663 106.555699)
        (xy 147.27736 106.541648)
        (xy 147.239657 106.523817)
        (xy 147.203883 106.502374)
        (xy 147.170383 106.477529)
        (xy 147.13948 106.44952)
        (xy 147.111471 106.418617)
        (xy 147.086626 106.385117)
        (xy 147.065183 106.349343)
        (xy 147.047352 106.31164)
        (xy 147.033301 106.27237)
        (xy 147.023166 106.231913)
        (xy 147.017046 106.190657)
        (xy 147.015 106.149001)
      )
    )
  )
  (zone (net 0) (net_name "") (layers "In1.Cu" "In3.Cu" "In5.Cu" "In6.Cu") (hatch edge 0.508)
    (connect_pads yes (clearance 0))
    (min_thickness 0.1) (filled_areas_thickness no)
    (keepout (tracks allowed) (vias allowed) (pads allowed) (copperpour not_allowed) (footprints allowed))
    (fill (thermal_gap 0.254) (thermal_bridge_width 0.254))
    (polygon
      (pts
        (xy 127.687047 77.561256)
        (xy 127.693167 77.52)
        (xy 127.703301 77.479543)
        (xy 127.717352 77.440273)
        (xy 127.735184 77.40257)
        (xy 127.756626 77.366796)
        (xy 127.781471 77.333296)
        (xy 127.80948 77.302393)
        (xy 127.840383 77.274384)
        (xy 127.873882 77.249539)
        (xy 127.909657 77.228097)
        (xy 127.94736 77.210266)
        (xy 127.98663 77.196214)
        (xy 128.027087 77.18608)
        (xy 128.068343 77.17996)
        (xy 128.11 77.177913)
        (xy 128.113999 77.17811)
        (xy 128.114 77.177913)
        (xy 128.683447 77.177913)
        (xy 128.696641 77.177265)
        (xy 128.738296 77.179312)
        (xy 128.779553 77.185432)
        (xy 128.82001 77.195566)
        (xy 128.85928 77.209617)
        (xy 128.896982 77.227449)
        (xy 128.932757 77.248891)
        (xy 128.966257 77.273736)
        (xy 128.99716 77.301745)
        (xy 129.025169 77.332647)
        (xy 129.050015 77.366148)
        (xy 129.071455 77.401922)
        (xy 129.089288 77.439626)
        (xy 129.103339 77.478895)
        (xy 129.113472 77.519352)
        (xy 129.119592 77.560608)
        (xy 129.12164 77.602264)
        (xy 129.119593 77.643922)
        (xy 129.113473 77.685178)
        (xy 129.103339 77.725635)
        (xy 129.089288 77.764905)
        (xy 129.071456 77.802608)
        (xy 129.050014 77.838382)
        (xy 129.025169 77.871881)
        (xy 128.99716 77.902785)
        (xy 128.966255 77.930794)
        (xy 128.932756 77.955639)
        (xy 128.896983 77.977081)
        (xy 128.85928 77.994913)
        (xy 128.82001 78.008964)
        (xy 128.779553 78.019098)
        (xy 128.738297 78.025218)
        (xy 128.69664 78.027265)
        (xy 128.667747 78.025845)
        (xy 128.157587 78.024986)
        (xy 128.151657 78.025866)
        (xy 128.109999 78.027913)
        (xy 128.068342 78.025866)
        (xy 128.027087 78.019747)
        (xy 127.98663 78.009612)
        (xy 127.94736 77.995561)
        (xy 127.909657 77.97773)
        (xy 127.873883 77.956287)
        (xy 127.840383 77.931442)
        (xy 127.80948 77.903433)
        (xy 127.781471 77.87253)
        (xy 127.756626 77.83903)
        (xy 127.735183 77.803256)
        (xy 127.717352 77.765553)
        (xy 127.703301 77.726283)
        (xy 127.693166 77.685826)
        (xy 127.687046 77.64457)
        (xy 127.685 77.602914)
      )
    )
  )
  (zone (net 0) (net_name "") (layers "In1.Cu" "In3.Cu" "In5.Cu" "In6.Cu") (hatch edge 0.508)
    (connect_pads yes (clearance 0))
    (min_thickness 0.1) (filled_areas_thickness no)
    (keepout (tracks allowed) (vias allowed) (pads allowed) (copperpour not_allowed) (footprints allowed))
    (fill (thermal_gap 0.254) (thermal_bridge_width 0.254))
    (polygon
      (pts
        (xy 127.486657 75.537047)
        (xy 127.527913 75.543167)
        (xy 127.56837 75.553301)
        (xy 127.60764 75.567352)
        (xy 127.645343 75.585184)
        (xy 127.681117 75.606626)
        (xy 127.714617 75.631471)
        (xy 127.74552 75.65948)
        (xy 127.773529 75.690383)
        (xy 127.798374 75.723882)
        (xy 127.819816 75.759657)
        (xy 127.837647 75.79736)
        (xy 127.851699 75.83663)
        (xy 127.861833 75.877087)
        (xy 127.867953 75.918343)
        (xy 127.87 75.96)
        (xy 127.869803 75.964)
        (xy 127.87 75.964)
        (xy 127.87 76.533447)
        (xy 127.870648 76.54664)
        (xy 127.868601 76.588296)
        (xy 127.862481 76.629553)
        (xy 127.852347 76.67001)
        (xy 127.838296 76.70928)
        (xy 127.820464 76.746982)
        (xy 127.799022 76.782757)
        (xy 127.774177 76.816257)
        (xy 127.746168 76.84716)
        (xy 127.715266 76.875169)
        (xy 127.681765 76.900015)
        (xy 127.645991 76.921455)
        (xy 127.608287 76.939288)
        (xy 127.569018 76.953339)
        (xy 127.528561 76.963472)
        (xy 127.487305 76.969592)
        (xy 127.445648 76.97164)
        (xy 127.403991 76.969593)
        (xy 127.362735 76.963473)
        (xy 127.322278 76.953339)
        (xy 127.283008 76.939288)
        (xy 127.245305 76.921456)
        (xy 127.209531 76.900014)
        (xy 127.176032 76.875169)
        (xy 127.145128 76.84716)
        (xy 127.117119 76.816256)
        (xy 127.092274 76.782756)
        (xy 127.070832 76.746983)
        (xy 127.053 76.70928)
        (xy 127.038949 76.67001)
        (xy 127.028815 76.629553)
        (xy 127.022695 76.588297)
        (xy 127.020648 76.54664)
        (xy 127.022068 76.517747)
        (xy 127.022927 76.007587)
        (xy 127.022047 76.001657)
        (xy 127.02 75.96)
        (xy 127.022047 75.918342)
        (xy 127.028166 75.877087)
        (xy 127.038301 75.83663)
        (xy 127.052352 75.79736)
        (xy 127.070183 75.759657)
        (xy 127.091626 75.723883)
        (xy 127.116471 75.690383)
        (xy 127.14448 75.65948)
        (xy 127.175383 75.631471)
        (xy 127.208883 75.606626)
        (xy 127.244657 75.585183)
        (xy 127.28236 75.567352)
        (xy 127.32163 75.553301)
        (xy 127.362087 75.543166)
        (xy 127.403343 75.537046)
        (xy 127.445 75.535)
      )
    )
  )
  (zone (net 0) (net_name "") (layers "In1.Cu" "In3.Cu" "In5.Cu" "In6.Cu") (hatch edge 0.508)
    (connect_pads yes (clearance 0))
    (min_thickness 0.1) (filled_areas_thickness no)
    (keepout (tracks allowed) (vias allowed) (pads allowed) (copperpour not_allowed) (footprints allowed))
    (fill (thermal_gap 0.254) (thermal_bridge_width 0.254))
    (polygon
      (pts
        (xy 131.847047 72.507343)
        (xy 131.853167 72.466087)
        (xy 131.863301 72.42563)
        (xy 131.877352 72.38636)
        (xy 131.895184 72.348657)
        (xy 131.916626 72.312883)
        (xy 131.941471 72.279383)
        (xy 131.96948 72.24848)
        (xy 132.000383 72.220471)
        (xy 132.033882 72.195626)
        (xy 132.069657 72.174184)
        (xy 132.10736 72.156353)
        (xy 132.14663 72.142301)
        (xy 132.187087 72.132167)
        (xy 132.228343 72.126047)
        (xy 132.27 72.124)
        (xy 132.273999 72.124197)
        (xy 132.274 72.124)
        (xy 132.843447 72.124)
        (xy 132.856641 72.123352)
        (xy 132.898296 72.125399)
        (xy 132.939553 72.131519)
        (xy 132.98001 72.141653)
        (xy 133.01928 72.155704)
        (xy 133.056982 72.173536)
        (xy 133.092757 72.194978)
        (xy 133.126257 72.219823)
        (xy 133.15716 72.247832)
        (xy 133.185169 72.278734)
        (xy 133.210015 72.312235)
        (xy 133.231455 72.348009)
        (xy 133.249288 72.385713)
        (xy 133.263339 72.424982)
        (xy 133.273472 72.465439)
        (xy 133.279592 72.506695)
        (xy 133.28164 72.548351)
        (xy 133.279593 72.590009)
        (xy 133.273473 72.631265)
        (xy 133.263339 72.671722)
        (xy 133.249288 72.710992)
        (xy 133.231456 72.748695)
        (xy 133.210014 72.784469)
        (xy 133.185169 72.817968)
        (xy 133.15716 72.848872)
        (xy 133.126255 72.876881)
        (xy 133.092756 72.901726)
        (xy 133.056983 72.923168)
        (xy 133.01928 72.941)
        (xy 132.98001 72.955051)
        (xy 132.939553 72.965185)
        (xy 132.898297 72.971305)
        (xy 132.85664 72.973352)
        (xy 132.827747 72.971932)
        (xy 132.317587 72.971073)
        (xy 132.311657 72.971953)
        (xy 132.269999 72.974)
        (xy 132.228342 72.971953)
        (xy 132.187087 72.965834)
        (xy 132.14663 72.955699)
        (xy 132.10736 72.941648)
        (xy 132.069657 72.923817)
        (xy 132.033883 72.902374)
        (xy 132.000383 72.877529)
        (xy 131.96948 72.84952)
        (xy 131.941471 72.818617)
        (xy 131.916626 72.785117)
        (xy 131.895183 72.749343)
        (xy 131.877352 72.71164)
        (xy 131.863301 72.67237)
        (xy 131.853166 72.631913)
        (xy 131.847046 72.590657)
        (xy 131.845 72.549001)
      )
    )
  )
  (zone (net 0) (net_name "") (layers "In1.Cu" "In3.Cu" "In5.Cu" "In6.Cu") (hatch edge 0.508)
    (connect_pads yes (clearance 0))
    (min_thickness 0.1) (filled_areas_thickness no)
    (keepout (tracks allowed) (vias allowed) (pads allowed) (copperpour not_allowed) (footprints allowed))
    (fill (thermal_gap 0.254) (thermal_bridge_width 0.254))
    (polygon
      (pts
        (xy 134.470666 119.815592)
        (xy 134.511922 119.821712)
        (xy 134.552379 119.831846)
        (xy 134.591649 119.845897)
        (xy 134.629352 119.863729)
        (xy 134.665126 119.885171)
        (xy 134.698626 119.910016)
        (xy 134.729529 119.938025)
        (xy 134.757538 119.968928)
        (xy 134.782383 120.002427)
        (xy 134.803825 120.038202)
        (xy 134.821656 120.075905)
        (xy 134.835708 120.115175)
        (xy 134.845842 120.155632)
        (xy 134.851962 120.196888)
        (xy 134.854009 120.238545)
        (xy 134.853812 120.242545)
        (xy 134.854009 120.242545)
        (xy 134.854009 120.811992)
        (xy 134.854657 120.825185)
        (xy 134.85261 120.866841)
        (xy 134.84649 120.908098)
        (xy 134.836356 120.948555)
        (xy 134.822305 120.987825)
        (xy 134.804473 121.025527)
        (xy 134.783031 121.061302)
        (xy 134.758186 121.094802)
        (xy 134.730177 121.125705)
        (xy 134.699275 121.153714)
        (xy 134.665774 121.17856)
        (xy 134.63 121.2)
        (xy 134.592296 121.217833)
        (xy 134.553027 121.231884)
        (xy 134.51257 121.242017)
        (xy 134.471314 121.248137)
        (xy 134.429657 121.250185)
        (xy 134.388 121.248138)
        (xy 134.346744 121.242018)
        (xy 134.306287 121.231884)
        (xy 134.267017 121.217833)
        (xy 134.229314 121.200001)
        (xy 134.19354 121.178559)
        (xy 134.160041 121.153714)
        (xy 134.129137 121.125705)
        (xy 134.101128 121.094801)
        (xy 134.076283 121.061301)
        (xy 134.054841 121.025528)
        (xy 134.037009 120.987825)
        (xy 134.022958 120.948555)
        (xy 134.012824 120.908098)
        (xy 134.006704 120.866842)
        (xy 134.004657 120.825185)
        (xy 134.006077 120.796292)
        (xy 134.006936 120.286132)
        (xy 134.006056 120.280202)
        (xy 134.004009 120.238545)
        (xy 134.006056 120.196887)
        (xy 134.012175 120.155632)
        (xy 134.02231 120.115175)
        (xy 134.036361 120.075905)
        (xy 134.054192 120.038202)
        (xy 134.075635 120.002428)
        (xy 134.10048 119.968928)
        (xy 134.128489 119.938025)
        (xy 134.159392 119.910016)
        (xy 134.192892 119.885171)
        (xy 134.228666 119.863728)
        (xy 134.266369 119.845897)
        (xy 134.305639 119.831846)
        (xy 134.346096 119.821711)
        (xy 134.387352 119.815591)
        (xy 134.429009 119.813545)
      )
    )
  )
  (zone (net 0) (net_name "") (layers "In1.Cu" "In3.Cu" "In5.Cu" "In6.Cu") (hatch edge 0.508)
    (connect_pads yes (clearance 0))
    (min_thickness 0.1) (filled_areas_thickness no)
    (keepout (tracks allowed) (vias allowed) (pads allowed) (copperpour not_allowed) (footprints allowed))
    (fill (thermal_gap 0.254) (thermal_bridge_width 0.254))
    (polygon
      (pts
        (xy 114.521269 117.927)
        (xy 115.287393 117.927)
        (xy 115.288349 117.926953)
        (xy 115.330006 117.929)
        (xy 115.371262 117.93512)
        (xy 115.411719 117.945254)
        (xy 115.450989 117.959305)
        (xy 115.488692 117.977137)
        (xy 115.524466 117.998579)
        (xy 115.557966 118.023424)
        (xy 115.588869 118.051433)
        (xy 115.616878 118.082336)
        (xy 115.641723 118.115836)
        (xy 115.663165 118.15161)
        (xy 115.680997 118.189313)
        (xy 115.695048 118.228583)
        (xy 115.705182 118.26904)
        (xy 115.711302 118.310296)
        (xy 115.713349 118.351953)
        (xy 115.711302 118.39361)
        (xy 115.705182 118.434866)
        (xy 115.695048 118.475323)
        (xy 115.680997 118.514593)
        (xy 115.663165 118.552296)
        (xy 115.641723 118.58807)
        (xy 115.616878 118.62157)
        (xy 115.588869 118.652473)
        (xy 115.557966 118.680482)
        (xy 115.524466 118.705327)
        (xy 115.488692 118.726769)
        (xy 115.450989 118.744601)
        (xy 115.411719 118.758652)
        (xy 115.371262 118.768786)
        (xy 115.330006 118.774906)
        (xy 115.289006 118.776921)
        (xy 115.289006 118.777)
        (xy 114.508321 118.776004)
        (xy 114.504663 118.776184)
        (xy 114.463006 118.774137)
        (xy 114.42175 118.768017)
        (xy 114.381293 118.757883)
        (xy 114.342023 118.743832)
        (xy 114.30432 118.726)
        (xy 114.268546 118.704558)
        (xy 114.235046 118.679713)
        (xy 114.204143 118.651704)
        (xy 114.176134 118.620801)
        (xy 114.151289 118.587301)
        (xy 114.129847 118.551527)
        (xy 114.112015 118.513824)
        (xy 114.097964 118.474554)
        (xy 114.08783 118.434097)
        (xy 114.08171 118.392841)
        (xy 114.079663 118.351184)
        (xy 114.08171 118.309527)
        (xy 114.08783 118.268271)
        (xy 114.097964 118.227814)
        (xy 114.112015 118.188544)
        (xy 114.129847 118.150841)
        (xy 114.151289 118.115067)
        (xy 114.176134 118.081567)
        (xy 114.204143 118.050664)
        (xy 114.235046 118.022655)
        (xy 114.268546 117.99781)
        (xy 114.30432 117.976368)
        (xy 114.342023 117.958536)
        (xy 114.381293 117.944485)
        (xy 114.42175 117.934351)
        (xy 114.463006 117.928231)
        (xy 114.504663 117.926184)
      )
    )
  )
  (zone (net 0) (net_name "") (layers "In1.Cu" "In3.Cu" "In5.Cu" "In6.Cu") (hatch edge 0.508)
    (connect_pads yes (clearance 0))
    (min_thickness 0.1) (filled_areas_thickness no)
    (keepout (tracks allowed) (vias allowed) (pads allowed) (copperpour not_allowed) (footprints allowed))
    (fill (thermal_gap 0.254) (thermal_bridge_width 0.254))
    (polygon
      (pts
        (xy 146.967047 108.767343)
        (xy 146.973167 108.726087)
        (xy 146.983301 108.68563)
        (xy 146.997352 108.64636)
        (xy 147.015184 108.608657)
        (xy 147.036626 108.572883)
        (xy 147.061471 108.539383)
        (xy 147.08948 108.50848)
        (xy 147.120383 108.480471)
        (xy 147.153882 108.455626)
        (xy 147.189657 108.434184)
        (xy 147.22736 108.416353)
        (xy 147.26663 108.402301)
        (xy 147.307087 108.392167)
        (xy 147.348343 108.386047)
        (xy 147.39 108.384)
        (xy 147.393999 108.384197)
        (xy 147.394 108.384)
        (xy 147.963447 108.384)
        (xy 147.976641 108.383352)
        (xy 148.018296 108.385399)
        (xy 148.059553 108.391519)
        (xy 148.10001 108.401653)
        (xy 148.13928 108.415704)
        (xy 148.176982 108.433536)
        (xy 148.212757 108.454978)
        (xy 148.246257 108.479823)
        (xy 148.27716 108.507832)
        (xy 148.305169 108.538734)
        (xy 148.330015 108.572235)
        (xy 148.351455 108.608009)
        (xy 148.369288 108.645713)
        (xy 148.383339 108.684982)
        (xy 148.393472 108.725439)
        (xy 148.399592 108.766695)
        (xy 148.40164 108.808351)
        (xy 148.399593 108.850009)
        (xy 148.393473 108.891265)
        (xy 148.383339 108.931722)
        (xy 148.369288 108.970992)
        (xy 148.351456 109.008695)
        (xy 148.330014 109.044469)
        (xy 148.305169 109.077968)
        (xy 148.27716 109.108872)
        (xy 148.246255 109.136881)
        (xy 148.212756 109.161726)
        (xy 148.176983 109.183168)
        (xy 148.13928 109.201)
        (xy 148.10001 109.215051)
        (xy 148.059553 109.225185)
        (xy 148.018297 109.231305)
        (xy 147.97664 109.233352)
        (xy 147.947747 109.231932)
        (xy 147.437587 109.231073)
        (xy 147.431657 109.231953)
        (xy 147.389999 109.234)
        (xy 147.348342 109.231953)
        (xy 147.307087 109.225834)
        (xy 147.26663 109.215699)
        (xy 147.22736 109.201648)
        (xy 147.189657 109.183817)
        (xy 147.153883 109.162374)
        (xy 147.120383 109.137529)
        (xy 147.08948 109.10952)
        (xy 147.061471 109.078617)
        (xy 147.036626 109.045117)
        (xy 147.015183 109.009343)
        (xy 146.997352 108.97164)
        (xy 146.983301 108.93237)
        (xy 146.973166 108.891913)
        (xy 146.967046 108.850657)
        (xy 146.965 108.809001)
      )
    )
  )
  (zone (net 0) (net_name "") (layers "In1.Cu" "In3.Cu" "In5.Cu" "In6.Cu") (hatch edge 0.508)
    (connect_pads yes (clearance 0))
    (min_thickness 0.1) (filled_areas_thickness no)
    (keepout (tracks allowed) (vias allowed) (pads allowed) (copperpour not_allowed) (footprints allowed))
    (fill (thermal_gap 0.254) (thermal_bridge_width 0.254))
    (polygon
      (pts
        (xy 147.637047 84.067343)
        (xy 147.643167 84.026087)
        (xy 147.653301 83.98563)
        (xy 147.667352 83.94636)
        (xy 147.685184 83.908657)
        (xy 147.706626 83.872883)
        (xy 147.731471 83.839383)
        (xy 147.75948 83.80848)
        (xy 147.790383 83.780471)
        (xy 147.823882 83.755626)
        (xy 147.859657 83.734184)
        (xy 147.89736 83.716353)
        (xy 147.93663 83.702301)
        (xy 147.977087 83.692167)
        (xy 148.018343 83.686047)
        (xy 148.06 83.684)
        (xy 148.063999 83.684197)
        (xy 148.064 83.684)
        (xy 148.633447 83.684)
        (xy 148.646641 83.683352)
        (xy 148.688296 83.685399)
        (xy 148.729553 83.691519)
        (xy 148.77001 83.701653)
        (xy 148.80928 83.715704)
        (xy 148.846982 83.733536)
        (xy 148.882757 83.754978)
        (xy 148.916257 83.779823)
        (xy 148.94716 83.807832)
        (xy 148.975169 83.838734)
        (xy 149.000015 83.872235)
        (xy 149.021455 83.908009)
        (xy 149.039288 83.945713)
        (xy 149.053339 83.984982)
        (xy 149.063472 84.025439)
        (xy 149.069592 84.066695)
        (xy 149.07164 84.108351)
        (xy 149.069593 84.150009)
        (xy 149.063473 84.191265)
        (xy 149.053339 84.231722)
        (xy 149.039288 84.270992)
        (xy 149.021456 84.308695)
        (xy 149.000014 84.344469)
        (xy 148.975169 84.377968)
        (xy 148.94716 84.408872)
        (xy 148.916255 84.436881)
        (xy 148.882756 84.461726)
        (xy 148.846983 84.483168)
        (xy 148.80928 84.501)
        (xy 148.77001 84.515051)
        (xy 148.729553 84.525185)
        (xy 148.688297 84.531305)
        (xy 148.64664 84.533352)
        (xy 148.617747 84.531932)
        (xy 148.107587 84.531073)
        (xy 148.101657 84.531953)
        (xy 148.059999 84.534)
        (xy 148.018342 84.531953)
        (xy 147.977087 84.525834)
        (xy 147.93663 84.515699)
        (xy 147.89736 84.501648)
        (xy 147.859657 84.483817)
        (xy 147.823883 84.462374)
        (xy 147.790383 84.437529)
        (xy 147.75948 84.40952)
        (xy 147.731471 84.378617)
        (xy 147.706626 84.345117)
        (xy 147.685183 84.309343)
        (xy 147.667352 84.27164)
        (xy 147.653301 84.23237)
        (xy 147.643166 84.191913)
        (xy 147.637046 84.150657)
        (xy 147.635 84.109001)
      )
    )
  )
  (zone (net 0) (net_name "") (layers "In1.Cu" "In3.Cu" "In5.Cu" "In6.Cu") (hatch edge 0.508)
    (connect_pads yes (clearance 0))
    (min_thickness 0.1) (filled_areas_thickness no)
    (keepout (tracks allowed) (vias allowed) (pads allowed) (copperpour not_allowed) (footprints allowed))
    (fill (thermal_gap 0.254) (thermal_bridge_width 0.254))
    (polygon
      (pts
        (xy 145.957047 58.447343)
        (xy 145.963167 58.406087)
        (xy 145.973301 58.36563)
        (xy 145.987352 58.32636)
        (xy 146.005184 58.288657)
        (xy 146.026626 58.252883)
        (xy 146.051471 58.219383)
        (xy 146.07948 58.18848)
        (xy 146.110383 58.160471)
        (xy 146.143882 58.135626)
        (xy 146.179657 58.114184)
        (xy 146.21736 58.096353)
        (xy 146.25663 58.082301)
        (xy 146.297087 58.072167)
        (xy 146.338343 58.066047)
        (xy 146.38 58.064)
        (xy 146.383999 58.064197)
        (xy 146.384 58.064)
        (xy 146.953447 58.064)
        (xy 146.966641 58.063352)
        (xy 147.008296 58.065399)
        (xy 147.049553 58.071519)
        (xy 147.09001 58.081653)
        (xy 147.12928 58.095704)
        (xy 147.166982 58.113536)
        (xy 147.202757 58.134978)
        (xy 147.236257 58.159823)
        (xy 147.26716 58.187832)
        (xy 147.295169 58.218734)
        (xy 147.320015 58.252235)
        (xy 147.341455 58.288009)
        (xy 147.359288 58.325713)
        (xy 147.373339 58.364982)
        (xy 147.383472 58.405439)
        (xy 147.389592 58.446695)
        (xy 147.39164 58.488351)
        (xy 147.389593 58.530009)
        (xy 147.383473 58.571265)
        (xy 147.373339 58.611722)
        (xy 147.359288 58.650992)
        (xy 147.341456 58.688695)
        (xy 147.320014 58.724469)
        (xy 147.295169 58.757968)
        (xy 147.26716 58.788872)
        (xy 147.236255 58.816881)
        (xy 147.202756 58.841726)
        (xy 147.166983 58.863168)
        (xy 147.12928 58.881)
        (xy 147.09001 58.895051)
        (xy 147.049553 58.905185)
        (xy 147.008297 58.911305)
        (xy 146.96664 58.913352)
        (xy 146.937747 58.911932)
        (xy 146.427587 58.911073)
        (xy 146.421657 58.911953)
        (xy 146.379999 58.914)
        (xy 146.338342 58.911953)
        (xy 146.297087 58.905834)
        (xy 146.25663 58.895699)
        (xy 146.21736 58.881648)
        (xy 146.179657 58.863817)
        (xy 146.143883 58.842374)
        (xy 146.110383 58.817529)
        (xy 146.07948 58.78952)
        (xy 146.051471 58.758617)
        (xy 146.026626 58.725117)
        (xy 146.005183 58.689343)
        (xy 145.987352 58.65164)
        (xy 145.973301 58.61237)
        (xy 145.963166 58.571913)
        (xy 145.957046 58.530657)
        (xy 145.955 58.489001)
      )
    )
  )
  (zone (net 0) (net_name "") (layers "In1.Cu" "In3.Cu" "In5.Cu" "In6.Cu") (hatch edge 0.508)
    (connect_pads yes (clearance 0))
    (min_thickness 0.1) (filled_areas_thickness no)
    (keepout (tracks allowed) (vias allowed) (pads allowed) (copperpour not_allowed) (footprints allowed))
    (fill (thermal_gap 0.254) (thermal_bridge_width 0.254))
    (polygon
      (pts
        (xy 126.773161 88.251816)
        (xy 126.731905 88.245696)
        (xy 126.691448 88.235562)
        (xy 126.652178 88.221511)
        (xy 126.614475 88.203679)
        (xy 126.578701 88.182237)
        (xy 126.545201 88.157392)
        (xy 126.514298 88.129383)
        (xy 126.486289 88.09848)
        (xy 126.461444 88.064981)
        (xy 126.440002 88.029206)
        (xy 126.422171 87.991503)
        (xy 126.408119 87.952233)
        (xy 126.397985 87.911776)
        (xy 126.391865 87.87052)
        (xy 126.389818 87.828863)
        (xy 126.390015 87.824864)
        (xy 126.389818 87.824863)
        (xy 126.389818 87.255416)
        (xy 126.38917 87.242222)
        (xy 126.391217 87.200567)
        (xy 126.397337 87.15931)
        (xy 126.407471 87.118853)
        (xy 126.421522 87.079583)
        (xy 126.439354 87.041881)
        (xy 126.460796 87.006106)
        (xy 126.485641 86.972606)
        (xy 126.51365 86.941703)
        (xy 126.544552 86.913694)
        (xy 126.578053 86.888848)
        (xy 126.613827 86.867408)
        (xy 126.651531 86.849575)
        (xy 126.6908 86.835524)
        (xy 126.731257 86.825391)
        (xy 126.772513 86.819271)
        (xy 126.814169 86.817223)
        (xy 126.855827 86.81927)
        (xy 126.897083 86.82539)
        (xy 126.93754 86.835524)
        (xy 126.97681 86.849575)
        (xy 127.014513 86.867407)
        (xy 127.050287 86.888849)
        (xy 127.083786 86.913694)
        (xy 127.11469 86.941703)
        (xy 127.142699 86.972608)
        (xy 127.167544 87.006107)
        (xy 127.188986 87.04188)
        (xy 127.206818 87.079583)
        (xy 127.220869 87.118853)
        (xy 127.231003 87.15931)
        (xy 127.237123 87.200566)
        (xy 127.23917 87.242223)
        (xy 127.23775 87.271116)
        (xy 127.236891 87.781276)
        (xy 127.237771 87.787206)
        (xy 127.239818 87.828864)
        (xy 127.237771 87.870521)
        (xy 127.231652 87.911776)
        (xy 127.221517 87.952233)
        (xy 127.207466 87.991503)
        (xy 127.189635 88.029206)
        (xy 127.168192 88.06498)
        (xy 127.143347 88.09848)
        (xy 127.115338 88.129383)
        (xy 127.084435 88.157392)
        (xy 127.050935 88.182237)
        (xy 127.015161 88.20368)
        (xy 126.977458 88.221511)
        (xy 126.938188 88.235562)
        (xy 126.897731 88.245697)
        (xy 126.856475 88.251817)
        (xy 126.814819 88.253863)
      )
    )
  )
  (zone (net 0) (net_name "") (layers "In1.Cu" "In3.Cu" "In5.Cu" "In6.Cu") (hatch edge 0.508)
    (connect_pads yes (clearance 0))
    (min_thickness 0.1) (filled_areas_thickness no)
    (keepout (tracks allowed) (vias allowed) (pads allowed) (copperpour not_allowed) (footprints allowed))
    (fill (thermal_gap 0.254) (thermal_bridge_width 0.254))
    (polygon
      (pts
        (xy 109.767047 77.377343)
        (xy 109.773167 77.336087)
        (xy 109.783301 77.29563)
        (xy 109.797352 77.25636)
        (xy 109.815184 77.218657)
        (xy 109.836626 77.182883)
        (xy 109.861471 77.149383)
        (xy 109.88948 77.11848)
        (xy 109.920383 77.090471)
        (xy 109.953882 77.065626)
        (xy 109.989657 77.044184)
        (xy 110.02736 77.026353)
        (xy 110.06663 77.012301)
        (xy 110.107087 77.002167)
        (xy 110.148343 76.996047)
        (xy 110.19 76.994)
        (xy 110.193999 76.994197)
        (xy 110.194 76.994)
        (xy 110.763447 76.994)
        (xy 110.776641 76.993352)
        (xy 110.818296 76.995399)
        (xy 110.859553 77.001519)
        (xy 110.90001 77.011653)
        (xy 110.93928 77.025704)
        (xy 110.976982 77.043536)
        (xy 111.012757 77.064978)
        (xy 111.046257 77.089823)
        (xy 111.07716 77.117832)
        (xy 111.105169 77.148734)
        (xy 111.130015 77.182235)
        (xy 111.151455 77.218009)
        (xy 111.169288 77.255713)
        (xy 111.183339 77.294982)
        (xy 111.193472 77.335439)
        (xy 111.199592 77.376695)
        (xy 111.20164 77.418351)
        (xy 111.199593 77.460009)
        (xy 111.193473 77.501265)
        (xy 111.183339 77.541722)
        (xy 111.169288 77.580992)
        (xy 111.151456 77.618695)
        (xy 111.130014 77.654469)
        (xy 111.105169 77.687968)
        (xy 111.07716 77.718872)
        (xy 111.046255 77.746881)
        (xy 111.012756 77.771726)
        (xy 110.976983 77.793168)
        (xy 110.93928 77.811)
        (xy 110.90001 77.825051)
        (xy 110.859553 77.835185)
        (xy 110.818297 77.841305)
        (xy 110.77664 77.843352)
        (xy 110.747747 77.841932)
        (xy 110.237587 77.841073)
        (xy 110.231657 77.841953)
        (xy 110.189999 77.844)
        (xy 110.148342 77.841953)
        (xy 110.107087 77.835834)
        (xy 110.06663 77.825699)
        (xy 110.02736 77.811648)
        (xy 109.989657 77.793817)
        (xy 109.953883 77.772374)
        (xy 109.920383 77.747529)
        (xy 109.88948 77.71952)
        (xy 109.861471 77.688617)
        (xy 109.836626 77.655117)
        (xy 109.815183 77.619343)
        (xy 109.797352 77.58164)
        (xy 109.783301 77.54237)
        (xy 109.773166 77.501913)
        (xy 109.767046 77.460657)
        (xy 109.765 77.419001)
      )
    )
  )
  (zone (net 0) (net_name "") (layers "In1.Cu" "In3.Cu" "In5.Cu" "In6.Cu") (hatch edge 0.508)
    (connect_pads yes (clearance 0))
    (min_thickness 0.1) (filled_areas_thickness no)
    (keepout (tracks allowed) (vias allowed) (pads allowed) (copperpour not_allowed) (footprints allowed))
    (fill (thermal_gap 0.254) (thermal_bridge_width 0.254))
    (polygon
      (pts
        (xy 124.987047 76.857343)
        (xy 124.993167 76.816087)
        (xy 125.003301 76.77563)
        (xy 125.017352 76.73636)
        (xy 125.035184 76.698657)
        (xy 125.056626 76.662883)
        (xy 125.081471 76.629383)
        (xy 125.10948 76.59848)
        (xy 125.140383 76.570471)
        (xy 125.173882 76.545626)
        (xy 125.209657 76.524184)
        (xy 125.24736 76.506353)
        (xy 125.28663 76.492301)
        (xy 125.327087 76.482167)
        (xy 125.368343 76.476047)
        (xy 125.41 76.474)
        (xy 125.413999 76.474197)
        (xy 125.414 76.474)
        (xy 125.983447 76.474)
        (xy 125.996641 76.473352)
        (xy 126.038296 76.475399)
        (xy 126.079553 76.481519)
        (xy 126.12001 76.491653)
        (xy 126.15928 76.505704)
        (xy 126.196982 76.523536)
        (xy 126.232757 76.544978)
        (xy 126.266257 76.569823)
        (xy 126.29716 76.597832)
        (xy 126.325169 76.628734)
        (xy 126.350015 76.662235)
        (xy 126.371455 76.698009)
        (xy 126.389288 76.735713)
        (xy 126.403339 76.774982)
        (xy 126.413472 76.815439)
        (xy 126.419592 76.856695)
        (xy 126.42164 76.898351)
        (xy 126.419593 76.940009)
        (xy 126.413473 76.981265)
        (xy 126.403339 77.021722)
        (xy 126.389288 77.060992)
        (xy 126.371456 77.098695)
        (xy 126.350014 77.134469)
        (xy 126.325169 77.167968)
        (xy 126.29716 77.198872)
        (xy 126.266255 77.226881)
        (xy 126.232756 77.251726)
        (xy 126.196983 77.273168)
        (xy 126.15928 77.291)
        (xy 126.12001 77.305051)
        (xy 126.079553 77.315185)
        (xy 126.038297 77.321305)
        (xy 125.99664 77.323352)
        (xy 125.967747 77.321932)
        (xy 125.457587 77.321073)
        (xy 125.451657 77.321953)
        (xy 125.409999 77.324)
        (xy 125.368342 77.321953)
        (xy 125.327087 77.315834)
        (xy 125.28663 77.305699)
        (xy 125.24736 77.291648)
        (xy 125.209657 77.273817)
        (xy 125.173883 77.252374)
        (xy 125.140383 77.227529)
        (xy 125.10948 77.19952)
        (xy 125.081471 77.168617)
        (xy 125.056626 77.135117)
        (xy 125.035183 77.099343)
        (xy 125.017352 77.06164)
        (xy 125.003301 77.02237)
        (xy 124.993166 76.981913)
        (xy 124.987046 76.940657)
        (xy 124.985 76.899001)
      )
    )
  )
  (zone (net 0) (net_name "") (layers "In1.Cu" "In3.Cu" "In5.Cu" "In6.Cu") (hatch edge 0.508)
    (connect_pads yes (clearance 0))
    (min_thickness 0.1) (filled_areas_thickness no)
    (keepout (tracks allowed) (vias allowed) (pads allowed) (copperpour not_allowed) (footprints allowed))
    (fill (thermal_gap 0.254) (thermal_bridge_width 0.254))
    (polygon
      (pts
        (xy 130.457047 77.337343)
        (xy 130.463167 77.296087)
        (xy 130.473301 77.25563)
        (xy 130.487352 77.21636)
        (xy 130.505184 77.178657)
        (xy 130.526626 77.142883)
        (xy 130.551471 77.109383)
        (xy 130.57948 77.07848)
        (xy 130.610383 77.050471)
        (xy 130.643882 77.025626)
        (xy 130.679657 77.004184)
        (xy 130.71736 76.986353)
        (xy 130.75663 76.972301)
        (xy 130.797087 76.962167)
        (xy 130.838343 76.956047)
        (xy 130.88 76.954)
        (xy 130.883999 76.954197)
        (xy 130.884 76.954)
        (xy 131.453447 76.954)
        (xy 131.466641 76.953352)
        (xy 131.508296 76.955399)
        (xy 131.549553 76.961519)
        (xy 131.59001 76.971653)
        (xy 131.62928 76.985704)
        (xy 131.666982 77.003536)
        (xy 131.702757 77.024978)
        (xy 131.736257 77.049823)
        (xy 131.76716 77.077832)
        (xy 131.795169 77.108734)
        (xy 131.820015 77.142235)
        (xy 131.841455 77.178009)
        (xy 131.859288 77.215713)
        (xy 131.873339 77.254982)
        (xy 131.883472 77.295439)
        (xy 131.889592 77.336695)
        (xy 131.89164 77.378351)
        (xy 131.889593 77.420009)
        (xy 131.883473 77.461265)
        (xy 131.873339 77.501722)
        (xy 131.859288 77.540992)
        (xy 131.841456 77.578695)
        (xy 131.820014 77.614469)
        (xy 131.795169 77.647968)
        (xy 131.76716 77.678872)
        (xy 131.736255 77.706881)
        (xy 131.702756 77.731726)
        (xy 131.666983 77.753168)
        (xy 131.62928 77.771)
        (xy 131.59001 77.785051)
        (xy 131.549553 77.795185)
        (xy 131.508297 77.801305)
        (xy 131.46664 77.803352)
        (xy 131.437747 77.801932)
        (xy 130.927587 77.801073)
        (xy 130.921657 77.801953)
        (xy 130.879999 77.804)
        (xy 130.838342 77.801953)
        (xy 130.797087 77.795834)
        (xy 130.75663 77.785699)
        (xy 130.71736 77.771648)
        (xy 130.679657 77.753817)
        (xy 130.643883 77.732374)
        (xy 130.610383 77.707529)
        (xy 130.57948 77.67952)
        (xy 130.551471 77.648617)
        (xy 130.526626 77.615117)
        (xy 130.505183 77.579343)
        (xy 130.487352 77.54164)
        (xy 130.473301 77.50237)
        (xy 130.463166 77.461913)
        (xy 130.457046 77.420657)
        (xy 130.455 77.379001)
      )
    )
  )
  (zone (net 0) (net_name "") (layers "In1.Cu" "In3.Cu" "In5.Cu" "In6.Cu") (hatch edge 0.508)
    (connect_pads yes (clearance 0))
    (min_thickness 0.1) (filled_areas_thickness no)
    (keepout (tracks allowed) (vias allowed) (pads allowed) (copperpour not_allowed) (footprints allowed))
    (fill (thermal_gap 0.254) (thermal_bridge_width 0.254))
    (polygon
      (pts
        (xy 146.137047 84.067343)
        (xy 146.143167 84.026087)
        (xy 146.153301 83.98563)
        (xy 146.167352 83.94636)
        (xy 146.185184 83.908657)
        (xy 146.206626 83.872883)
        (xy 146.231471 83.839383)
        (xy 146.25948 83.80848)
        (xy 146.290383 83.780471)
        (xy 146.323882 83.755626)
        (xy 146.359657 83.734184)
        (xy 146.39736 83.716353)
        (xy 146.43663 83.702301)
        (xy 146.477087 83.692167)
        (xy 146.518343 83.686047)
        (xy 146.56 83.684)
        (xy 146.563999 83.684197)
        (xy 146.564 83.684)
        (xy 147.133447 83.684)
        (xy 147.146641 83.683352)
        (xy 147.188296 83.685399)
        (xy 147.229553 83.691519)
        (xy 147.27001 83.701653)
        (xy 147.30928 83.715704)
        (xy 147.346982 83.733536)
        (xy 147.382757 83.754978)
        (xy 147.416257 83.779823)
        (xy 147.44716 83.807832)
        (xy 147.475169 83.838734)
        (xy 147.500015 83.872235)
        (xy 147.521455 83.908009)
        (xy 147.539288 83.945713)
        (xy 147.553339 83.984982)
        (xy 147.563472 84.025439)
        (xy 147.569592 84.066695)
        (xy 147.57164 84.108351)
        (xy 147.569593 84.150009)
        (xy 147.563473 84.191265)
        (xy 147.553339 84.231722)
        (xy 147.539288 84.270992)
        (xy 147.521456 84.308695)
        (xy 147.500014 84.344469)
        (xy 147.475169 84.377968)
        (xy 147.44716 84.408872)
        (xy 147.416255 84.436881)
        (xy 147.382756 84.461726)
        (xy 147.346983 84.483168)
        (xy 147.30928 84.501)
        (xy 147.27001 84.515051)
        (xy 147.229553 84.525185)
        (xy 147.188297 84.531305)
        (xy 147.14664 84.533352)
        (xy 147.117747 84.531932)
        (xy 146.607587 84.531073)
        (xy 146.601657 84.531953)
        (xy 146.559999 84.534)
        (xy 146.518342 84.531953)
        (xy 146.477087 84.525834)
        (xy 146.43663 84.515699)
        (xy 146.39736 84.501648)
        (xy 146.359657 84.483817)
        (xy 146.323883 84.462374)
        (xy 146.290383 84.437529)
        (xy 146.25948 84.40952)
        (xy 146.231471 84.378617)
        (xy 146.206626 84.345117)
        (xy 146.185183 84.309343)
        (xy 146.167352 84.27164)
        (xy 146.153301 84.23237)
        (xy 146.143166 84.191913)
        (xy 146.137046 84.150657)
        (xy 146.135 84.109001)
      )
    )
  )
  (zone (net 0) (net_name "") (layers "In1.Cu" "In3.Cu" "In5.Cu" "In6.Cu") (hatch edge 0.508)
    (connect_pads yes (clearance 0))
    (min_thickness 0.1) (filled_areas_thickness no)
    (keepout (tracks allowed) (vias allowed) (pads allowed) (copperpour not_allowed) (footprints allowed))
    (fill (thermal_gap 0.254) (thermal_bridge_width 0.254))
    (polygon
      (pts
        (xy 91.527047 75.296167)
        (xy 91.533167 75.254911)
        (xy 91.543301 75.214454)
        (xy 91.557352 75.175184)
        (xy 91.575184 75.137481)
        (xy 91.596626 75.101707)
        (xy 91.621471 75.068207)
        (xy 91.64948 75.037304)
        (xy 91.680383 75.009295)
        (xy 91.713882 74.98445)
        (xy 91.749657 74.963008)
        (xy 91.78736 74.945177)
        (xy 91.82663 74.931125)
        (xy 91.867087 74.920991)
        (xy 91.908343 74.914871)
        (xy 91.95 74.912824)
        (xy 91.953999 74.913021)
        (xy 91.954 74.912824)
        (xy 92.523447 74.912824)
        (xy 92.536641 74.912176)
        (xy 92.578296 74.914223)
        (xy 92.619553 74.920343)
        (xy 92.66001 74.930477)
        (xy 92.69928 74.944528)
        (xy 92.736982 74.96236)
        (xy 92.772757 74.983802)
        (xy 92.806257 75.008647)
        (xy 92.83716 75.036656)
        (xy 92.865169 75.067558)
        (xy 92.890015 75.101059)
        (xy 92.911455 75.136833)
        (xy 92.929288 75.174537)
        (xy 92.943339 75.213806)
        (xy 92.953472 75.254263)
        (xy 92.959592 75.295519)
        (xy 92.96164 75.337175)
        (xy 92.959593 75.378833)
        (xy 92.953473 75.420089)
        (xy 92.943339 75.460546)
        (xy 92.929288 75.499816)
        (xy 92.911456 75.537519)
        (xy 92.890014 75.573293)
        (xy 92.865169 75.606792)
        (xy 92.83716 75.637696)
        (xy 92.806255 75.665705)
        (xy 92.772756 75.69055)
        (xy 92.736983 75.711992)
        (xy 92.69928 75.729824)
        (xy 92.66001 75.743875)
        (xy 92.619553 75.754009)
        (xy 92.578297 75.760129)
        (xy 92.53664 75.762176)
        (xy 92.507747 75.760756)
        (xy 91.997587 75.759897)
        (xy 91.991657 75.760777)
        (xy 91.949999 75.762824)
        (xy 91.908342 75.760777)
        (xy 91.867087 75.754658)
        (xy 91.82663 75.744523)
        (xy 91.78736 75.730472)
        (xy 91.749657 75.712641)
        (xy 91.713883 75.691198)
        (xy 91.680383 75.666353)
        (xy 91.64948 75.638344)
        (xy 91.621471 75.607441)
        (xy 91.596626 75.573941)
        (xy 91.575183 75.538167)
        (xy 91.557352 75.500464)
        (xy 91.543301 75.461194)
        (xy 91.533166 75.420737)
        (xy 91.527046 75.379481)
        (xy 91.525 75.337825)
      )
    )
  )
  (zone (net 0) (net_name "") (layers "In1.Cu" "In3.Cu" "In5.Cu" "In6.Cu") (hatch edge 0.508)
    (connect_pads yes (clearance 0))
    (min_thickness 0.1) (filled_areas_thickness no)
    (keepout (tracks allowed) (vias allowed) (pads allowed) (copperpour not_allowed) (footprints allowed))
    (fill (thermal_gap 0.254) (thermal_bridge_width 0.254))
    (polygon
      (pts
        (xy 115.017047 76.517343)
        (xy 115.023167 76.476087)
        (xy 115.033301 76.43563)
        (xy 115.047352 76.39636)
        (xy 115.065184 76.358657)
        (xy 115.086626 76.322883)
        (xy 115.111471 76.289383)
        (xy 115.13948 76.25848)
        (xy 115.170383 76.230471)
        (xy 115.203882 76.205626)
        (xy 115.239657 76.184184)
        (xy 115.27736 76.166353)
        (xy 115.31663 76.152301)
        (xy 115.357087 76.142167)
        (xy 115.398343 76.136047)
        (xy 115.44 76.134)
        (xy 115.443999 76.134197)
        (xy 115.444 76.134)
        (xy 116.013447 76.134)
        (xy 116.026641 76.133352)
        (xy 116.068296 76.135399)
        (xy 116.109553 76.141519)
        (xy 116.15001 76.151653)
        (xy 116.18928 76.165704)
        (xy 116.226982 76.183536)
        (xy 116.262757 76.204978)
        (xy 116.296257 76.229823)
        (xy 116.32716 76.257832)
        (xy 116.355169 76.288734)
        (xy 116.380015 76.322235)
        (xy 116.401455 76.358009)
        (xy 116.419288 76.395713)
        (xy 116.433339 76.434982)
        (xy 116.443472 76.475439)
        (xy 116.449592 76.516695)
        (xy 116.45164 76.558351)
        (xy 116.449593 76.600009)
        (xy 116.443473 76.641265)
        (xy 116.433339 76.681722)
        (xy 116.419288 76.720992)
        (xy 116.401456 76.758695)
        (xy 116.380014 76.794469)
        (xy 116.355169 76.827968)
        (xy 116.32716 76.858872)
        (xy 116.296255 76.886881)
        (xy 116.262756 76.911726)
        (xy 116.226983 76.933168)
        (xy 116.18928 76.951)
        (xy 116.15001 76.965051)
        (xy 116.109553 76.975185)
        (xy 116.068297 76.981305)
        (xy 116.02664 76.983352)
        (xy 115.997747 76.981932)
        (xy 115.487587 76.981073)
        (xy 115.481657 76.981953)
        (xy 115.439999 76.984)
        (xy 115.398342 76.981953)
        (xy 115.357087 76.975834)
        (xy 115.31663 76.965699)
        (xy 115.27736 76.951648)
        (xy 115.239657 76.933817)
        (xy 115.203883 76.912374)
        (xy 115.170383 76.887529)
        (xy 115.13948 76.85952)
        (xy 115.111471 76.828617)
        (xy 115.086626 76.795117)
        (xy 115.065183 76.759343)
        (xy 115.047352 76.72164)
        (xy 115.033301 76.68237)
        (xy 115.023166 76.641913)
        (xy 115.017046 76.600657)
        (xy 115.015 76.559001)
      )
    )
  )
  (zone (net 0) (net_name "") (layers "In1.Cu" "In3.Cu" "In5.Cu" "In6.Cu") (hatch edge 0.508)
    (connect_pads yes (clearance 0))
    (min_thickness 0.1) (filled_areas_thickness no)
    (keepout (tracks allowed) (vias allowed) (pads allowed) (copperpour not_allowed) (footprints allowed))
    (fill (thermal_gap 0.254) (thermal_bridge_width 0.254))
    (polygon
      (pts
        (xy 132.818361 124.027767)
        (xy 132.859617 124.033887)
        (xy 132.900074 124.044021)
        (xy 132.939344 124.058072)
        (xy 132.977047 124.075904)
        (xy 133.012821 124.097346)
        (xy 133.046321 124.122191)
        (xy 133.077224 124.1502)
        (xy 133.105233 124.181103)
        (xy 133.130078 124.214602)
        (xy 133.15152 124.250377)
        (xy 133.169351 124.28808)
        (xy 133.183403 124.32735)
        (xy 133.193537 124.367807)
        (xy 133.199657 124.409063)
        (xy 133.201704 124.45072)
        (xy 133.201507 124.45472)
        (xy 133.201704 124.45472)
        (xy 133.201704 125.024167)
        (xy 133.202352 125.03736)
        (xy 133.200305 125.079016)
        (xy 133.194185 125.120273)
        (xy 133.184051 125.16073)
        (xy 133.17 125.2)
        (xy 133.152168 125.237702)
        (xy 133.130726 125.273477)
        (xy 133.105881 125.306977)
        (xy 133.077872 125.33788)
        (xy 133.04697 125.365889)
        (xy 133.013469 125.390735)
        (xy 132.977695 125.412175)
        (xy 132.939991 125.430008)
        (xy 132.900722 125.444059)
        (xy 132.860265 125.454192)
        (xy 132.819009 125.460312)
        (xy 132.777352 125.46236)
        (xy 132.735695 125.460313)
        (xy 132.694439 125.454193)
        (xy 132.653982 125.444059)
        (xy 132.614712 125.430008)
        (xy 132.577009 125.412176)
        (xy 132.541235 125.390734)
        (xy 132.507736 125.365889)
        (xy 132.476832 125.33788)
        (xy 132.448823 125.306976)
        (xy 132.423978 125.273476)
        (xy 132.402536 125.237703)
        (xy 132.384704 125.2)
        (xy 132.370653 125.16073)
        (xy 132.360519 125.120273)
        (xy 132.354399 125.079017)
        (xy 132.352352 125.03736)
        (xy 132.353772 125.008467)
        (xy 132.354631 124.498307)
        (xy 132.353751 124.492377)
        (xy 132.351704 124.45072)
        (xy 132.353751 124.409062)
        (xy 132.35987 124.367807)
        (xy 132.370005 124.32735)
        (xy 132.384056 124.28808)
        (xy 132.401887 124.250377)
        (xy 132.42333 124.214603)
        (xy 132.448175 124.181103)
        (xy 132.476184 124.1502)
        (xy 132.507087 124.122191)
        (xy 132.540587 124.097346)
        (xy 132.576361 124.075903)
        (xy 132.614064 124.058072)
        (xy 132.653334 124.044021)
        (xy 132.693791 124.033886)
        (xy 132.735047 124.027766)
        (xy 132.776704 124.02572)
      )
    )
  )
  (zone (net 0) (net_name "") (layers "In1.Cu" "In3.Cu" "In5.Cu" "In6.Cu") (hatch edge 0.508)
    (connect_pads yes (clearance 0))
    (min_thickness 0.1) (filled_areas_thickness no)
    (keepout (tracks allowed) (vias allowed) (pads allowed) (copperpour not_allowed) (footprints allowed))
    (fill (thermal_gap 0.254) (thermal_bridge_width 0.254))
    (polygon
      (pts
        (xy 115.035406 72.488991)
        (xy 115.041526 72.447735)
        (xy 115.05166 72.407278)
        (xy 115.065711 72.368008)
        (xy 115.083543 72.330305)
        (xy 115.104985 72.294531)
        (xy 115.12983 72.261031)
        (xy 115.157839 72.230128)
        (xy 115.188742 72.202119)
        (xy 115.222241 72.177274)
        (xy 115.258016 72.155832)
        (xy 115.295719 72.138001)
        (xy 115.334989 72.123949)
        (xy 115.375446 72.113815)
        (xy 115.416702 72.107695)
        (xy 115.458359 72.105648)
        (xy 115.462358 72.105845)
        (xy 115.462359 72.105648)
        (xy 116.031806 72.105648)
        (xy 116.045 72.105)
        (xy 116.086655 72.107047)
        (xy 116.127912 72.113167)
        (xy 116.168369 72.123301)
        (xy 116.207639 72.137352)
        (xy 116.245341 72.155184)
        (xy 116.281116 72.176626)
        (xy 116.314616 72.201471)
        (xy 116.345519 72.22948)
        (xy 116.373528 72.260382)
        (xy 116.398374 72.293883)
        (xy 116.419814 72.329657)
        (xy 116.437647 72.367361)
        (xy 116.451698 72.40663)
        (xy 116.461831 72.447087)
        (xy 116.467951 72.488343)
        (xy 116.469999 72.529999)
        (xy 116.467952 72.571657)
        (xy 116.461832 72.612913)
        (xy 116.451698 72.65337)
        (xy 116.437647 72.69264)
        (xy 116.419815 72.730343)
        (xy 116.398373 72.766117)
        (xy 116.373528 72.799616)
        (xy 116.345519 72.83052)
        (xy 116.314614 72.858529)
        (xy 116.281115 72.883374)
        (xy 116.245342 72.904816)
        (xy 116.207639 72.922648)
        (xy 116.168369 72.936699)
        (xy 116.127912 72.946833)
        (xy 116.086656 72.952953)
        (xy 116.044999 72.955)
        (xy 116.016106 72.95358)
        (xy 115.505946 72.952721)
        (xy 115.500016 72.953601)
        (xy 115.458358 72.955648)
        (xy 115.416701 72.953601)
        (xy 115.375446 72.947482)
        (xy 115.334989 72.937347)
        (xy 115.295719 72.923296)
        (xy 115.258016 72.905465)
        (xy 115.222242 72.884022)
        (xy 115.188742 72.859177)
        (xy 115.157839 72.831168)
        (xy 115.12983 72.800265)
        (xy 115.104985 72.766765)
        (xy 115.083542 72.730991)
        (xy 115.065711 72.693288)
        (xy 115.05166 72.654018)
        (xy 115.041525 72.613561)
        (xy 115.035405 72.572305)
        (xy 115.033359 72.530649)
      )
    )
  )
  (zone (net 0) (net_name "") (layers "In1.Cu" "In3.Cu" "In5.Cu" "In6.Cu") (hatch edge 0.508)
    (connect_pads yes (clearance 0))
    (min_thickness 0.1) (filled_areas_thickness no)
    (keepout (tracks allowed) (vias allowed) (pads allowed) (copperpour not_allowed) (footprints allowed))
    (fill (thermal_gap 0.254) (thermal_bridge_width 0.254))
    (polygon
      (pts
        (xy 131.833708 76.515621)
        (xy 131.839828 76.474365)
        (xy 131.849962 76.433908)
        (xy 131.864013 76.394638)
        (xy 131.881845 76.356935)
        (xy 131.903287 76.321161)
        (xy 131.928132 76.287661)
        (xy 131.956141 76.256758)
        (xy 131.987044 76.228749)
        (xy 132.020543 76.203904)
        (xy 132.056318 76.182462)
        (xy 132.094021 76.164631)
        (xy 132.133291 76.150579)
        (xy 132.173748 76.140445)
        (xy 132.215004 76.134325)
        (xy 132.256661 76.132278)
        (xy 132.26066 76.132475)
        (xy 132.260661 76.132278)
        (xy 132.830108 76.132278)
        (xy 132.843302 76.13163)
        (xy 132.884957 76.133677)
        (xy 132.926214 76.139797)
        (xy 132.966671 76.149931)
        (xy 133.005941 76.163982)
        (xy 133.043643 76.181814)
        (xy 133.079418 76.203256)
        (xy 133.112918 76.228101)
        (xy 133.143821 76.25611)
        (xy 133.17183 76.287012)
        (xy 133.196676 76.320513)
        (xy 133.218116 76.356287)
        (xy 133.235949 76.393991)
        (xy 133.25 76.43326)
        (xy 133.260133 76.473717)
        (xy 133.266253 76.514973)
        (xy 133.268301 76.556629)
        (xy 133.266254 76.598287)
        (xy 133.260134 76.639543)
        (xy 133.25 76.68)
        (xy 133.235949 76.71927)
        (xy 133.218117 76.756973)
        (xy 133.196675 76.792747)
        (xy 133.17183 76.826246)
        (xy 133.143821 76.85715)
        (xy 133.112916 76.885159)
        (xy 133.079417 76.910004)
        (xy 133.043644 76.931446)
        (xy 133.005941 76.949278)
        (xy 132.966671 76.963329)
        (xy 132.926214 76.973463)
        (xy 132.884958 76.979583)
        (xy 132.843301 76.98163)
        (xy 132.814408 76.98021)
        (xy 132.304248 76.979351)
        (xy 132.298318 76.980231)
        (xy 132.25666 76.982278)
        (xy 132.215003 76.980231)
        (xy 132.173748 76.974112)
        (xy 132.133291 76.963977)
        (xy 132.094021 76.949926)
        (xy 132.056318 76.932095)
        (xy 132.020544 76.910652)
        (xy 131.987044 76.885807)
        (xy 131.956141 76.857798)
        (xy 131.928132 76.826895)
        (xy 131.903287 76.793395)
        (xy 131.881844 76.757621)
        (xy 131.864013 76.719918)
        (xy 131.849962 76.680648)
        (xy 131.839827 76.640191)
        (xy 131.833707 76.598935)
        (xy 131.831661 76.557279)
      )
    )
  )
  (zone (net 0) (net_name "") (layers "In1.Cu" "In3.Cu" "In5.Cu" "In6.Cu") (hatch edge 0.508)
    (connect_pads yes (clearance 0))
    (min_thickness 0.1) (filled_areas_thickness no)
    (keepout (tracks allowed) (vias allowed) (pads allowed) (copperpour not_allowed) (footprints allowed))
    (fill (thermal_gap 0.254) (thermal_bridge_width 0.254))
    (polygon
      (pts
        (xy 123.597047 76.783343)
        (xy 123.603167 76.742087)
        (xy 123.613301 76.70163)
        (xy 123.627352 76.66236)
        (xy 123.645184 76.624657)
        (xy 123.666626 76.588883)
        (xy 123.691471 76.555383)
        (xy 123.71948 76.52448)
        (xy 123.750383 76.496471)
        (xy 123.783882 76.471626)
        (xy 123.819657 76.450184)
        (xy 123.85736 76.432353)
        (xy 123.89663 76.418301)
        (xy 123.937087 76.408167)
        (xy 123.978343 76.402047)
        (xy 124.02 76.4)
        (xy 124.023999 76.400197)
        (xy 124.024 76.4)
        (xy 124.593447 76.4)
        (xy 124.606641 76.399352)
        (xy 124.648296 76.401399)
        (xy 124.689553 76.407519)
        (xy 124.73001 76.417653)
        (xy 124.76928 76.431704)
        (xy 124.806982 76.449536)
        (xy 124.842757 76.470978)
        (xy 124.876257 76.495823)
        (xy 124.90716 76.523832)
        (xy 124.935169 76.554734)
        (xy 124.960015 76.588235)
        (xy 124.981455 76.624009)
        (xy 124.999288 76.661713)
        (xy 125.013339 76.700982)
        (xy 125.023472 76.741439)
        (xy 125.029592 76.782695)
        (xy 125.03164 76.824351)
        (xy 125.029593 76.866009)
        (xy 125.023473 76.907265)
        (xy 125.013339 76.947722)
        (xy 124.999288 76.986992)
        (xy 124.981456 77.024695)
        (xy 124.960014 77.060469)
        (xy 124.935169 77.093968)
        (xy 124.90716 77.124872)
        (xy 124.876255 77.152881)
        (xy 124.842756 77.177726)
        (xy 124.806983 77.199168)
        (xy 124.76928 77.217)
        (xy 124.73001 77.231051)
        (xy 124.689553 77.241185)
        (xy 124.648297 77.247305)
        (xy 124.60664 77.249352)
        (xy 124.577747 77.247932)
        (xy 124.067587 77.247073)
        (xy 124.061657 77.247953)
        (xy 124.019999 77.25)
        (xy 123.978342 77.247953)
        (xy 123.937087 77.241834)
        (xy 123.89663 77.231699)
        (xy 123.85736 77.217648)
        (xy 123.819657 77.199817)
        (xy 123.783883 77.178374)
        (xy 123.750383 77.153529)
        (xy 123.71948 77.12552)
        (xy 123.691471 77.094617)
        (xy 123.666626 77.061117)
        (xy 123.645183 77.025343)
        (xy 123.627352 76.98764)
        (xy 123.613301 76.94837)
        (xy 123.603166 76.907913)
        (xy 123.597046 76.866657)
        (xy 123.595 76.825001)
      )
    )
  )
  (zone (net 0) (net_name "") (layers "In1.Cu" "In3.Cu" "In5.Cu" "In6.Cu") (hatch edge 0.508)
    (connect_pads yes (clearance 0))
    (min_thickness 0.1) (filled_areas_thickness no)
    (keepout (tracks allowed) (vias allowed) (pads allowed) (copperpour not_allowed) (footprints allowed))
    (fill (thermal_gap 0.254) (thermal_bridge_width 0.254))
    (polygon
      (pts
        (xy 134.387047 76.467343)
        (xy 134.393167 76.426087)
        (xy 134.403301 76.38563)
        (xy 134.417352 76.34636)
        (xy 134.435184 76.308657)
        (xy 134.456626 76.272883)
        (xy 134.481471 76.239383)
        (xy 134.50948 76.20848)
        (xy 134.540383 76.180471)
        (xy 134.573882 76.155626)
        (xy 134.609657 76.134184)
        (xy 134.64736 76.116353)
        (xy 134.68663 76.102301)
        (xy 134.727087 76.092167)
        (xy 134.768343 76.086047)
        (xy 134.81 76.084)
        (xy 134.813999 76.084197)
        (xy 134.814 76.084)
        (xy 135.383447 76.084)
        (xy 135.396641 76.083352)
        (xy 135.438296 76.085399)
        (xy 135.479553 76.091519)
        (xy 135.52001 76.101653)
        (xy 135.55928 76.115704)
        (xy 135.596982 76.133536)
        (xy 135.632757 76.154978)
        (xy 135.666257 76.179823)
        (xy 135.69716 76.207832)
        (xy 135.725169 76.238734)
        (xy 135.750015 76.272235)
        (xy 135.771455 76.308009)
        (xy 135.789288 76.345713)
        (xy 135.803339 76.384982)
        (xy 135.813472 76.425439)
        (xy 135.819592 76.466695)
        (xy 135.82164 76.508351)
        (xy 135.819593 76.550009)
        (xy 135.813473 76.591265)
        (xy 135.803339 76.631722)
        (xy 135.789288 76.670992)
        (xy 135.771456 76.708695)
        (xy 135.750014 76.744469)
        (xy 135.725169 76.777968)
        (xy 135.69716 76.808872)
        (xy 135.666255 76.836881)
        (xy 135.632756 76.861726)
        (xy 135.596983 76.883168)
        (xy 135.55928 76.901)
        (xy 135.52001 76.915051)
        (xy 135.479553 76.925185)
        (xy 135.438297 76.931305)
        (xy 135.39664 76.933352)
        (xy 135.367747 76.931932)
        (xy 134.857587 76.931073)
        (xy 134.851657 76.931953)
        (xy 134.809999 76.934)
        (xy 134.768342 76.931953)
        (xy 134.727087 76.925834)
        (xy 134.68663 76.915699)
        (xy 134.64736 76.901648)
        (xy 134.609657 76.883817)
        (xy 134.573883 76.862374)
        (xy 134.540383 76.837529)
        (xy 134.50948 76.80952)
        (xy 134.481471 76.778617)
        (xy 134.456626 76.745117)
        (xy 134.435183 76.709343)
        (xy 134.417352 76.67164)
        (xy 134.403301 76.63237)
        (xy 134.393166 76.591913)
        (xy 134.387046 76.550657)
        (xy 134.385 76.509001)
      )
    )
  )
  (zone (net 0) (net_name "") (layers "In1.Cu" "In3.Cu" "In5.Cu" "In6.Cu") (hatch edge 0.508)
    (connect_pads yes (clearance 0))
    (min_thickness 0.1) (filled_areas_thickness no)
    (keepout (tracks allowed) (vias allowed) (pads allowed) (copperpour not_allowed) (footprints allowed))
    (fill (thermal_gap 0.254) (thermal_bridge_width 0.254))
    (polygon
      (pts
        (xy 147.497047 112.313343)
        (xy 147.503167 112.272087)
        (xy 147.513301 112.23163)
        (xy 147.527352 112.19236)
        (xy 147.545184 112.154657)
        (xy 147.566626 112.118883)
        (xy 147.591471 112.085383)
        (xy 147.61948 112.05448)
        (xy 147.650383 112.026471)
        (xy 147.683882 112.001626)
        (xy 147.719657 111.980184)
        (xy 147.75736 111.962353)
        (xy 147.79663 111.948301)
        (xy 147.837087 111.938167)
        (xy 147.878343 111.932047)
        (xy 147.92 111.93)
        (xy 147.923999 111.930197)
        (xy 147.924 111.93)
        (xy 148.493447 111.93)
        (xy 148.506641 111.929352)
        (xy 148.548296 111.931399)
        (xy 148.589553 111.937519)
        (xy 148.63001 111.947653)
        (xy 148.66928 111.961704)
        (xy 148.706982 111.979536)
        (xy 148.742757 112.000978)
        (xy 148.776257 112.025823)
        (xy 148.80716 112.053832)
        (xy 148.835169 112.084734)
        (xy 148.860015 112.118235)
        (xy 148.881455 112.154009)
        (xy 148.899288 112.191713)
        (xy 148.913339 112.230982)
        (xy 148.923472 112.271439)
        (xy 148.929592 112.312695)
        (xy 148.93164 112.354351)
        (xy 148.929593 112.396009)
        (xy 148.923473 112.437265)
        (xy 148.913339 112.477722)
        (xy 148.899288 112.516992)
        (xy 148.881456 112.554695)
        (xy 148.860014 112.590469)
        (xy 148.835169 112.623968)
        (xy 148.80716 112.654872)
        (xy 148.776255 112.682881)
        (xy 148.742756 112.707726)
        (xy 148.706983 112.729168)
        (xy 148.66928 112.747)
        (xy 148.63001 112.761051)
        (xy 148.589553 112.771185)
        (xy 148.548297 112.777305)
        (xy 148.50664 112.779352)
        (xy 148.477747 112.777932)
        (xy 147.967587 112.777073)
        (xy 147.961657 112.777953)
        (xy 147.919999 112.78)
        (xy 147.878342 112.777953)
        (xy 147.837087 112.771834)
        (xy 147.79663 112.761699)
        (xy 147.75736 112.747648)
        (xy 147.719657 112.729817)
        (xy 147.683883 112.708374)
        (xy 147.650383 112.683529)
        (xy 147.61948 112.65552)
        (xy 147.591471 112.624617)
        (xy 147.566626 112.591117)
        (xy 147.545183 112.555343)
        (xy 147.527352 112.51764)
        (xy 147.513301 112.47837)
        (xy 147.503166 112.437913)
        (xy 147.497046 112.396657)
        (xy 147.495 112.355001)
      )
    )
  )
  (zone (net 0) (net_name "") (layers "In1.Cu" "In3.Cu" "In5.Cu" "In6.Cu") (hatch edge 0.508)
    (connect_pads yes (clearance 0))
    (min_thickness 0.1) (filled_areas_thickness no)
    (keepout (tracks allowed) (vias allowed) (pads allowed) (copperpour not_allowed) (footprints allowed))
    (fill (thermal_gap 0.254) (thermal_bridge_width 0.254))
    (polygon
      (pts
        (xy 84.167047 72.697343)
        (xy 84.173167 72.656087)
        (xy 84.183301 72.61563)
        (xy 84.197352 72.57636)
        (xy 84.215184 72.538657)
        (xy 84.236626 72.502883)
        (xy 84.261471 72.469383)
        (xy 84.28948 72.43848)
        (xy 84.320383 72.410471)
        (xy 84.353882 72.385626)
        (xy 84.389657 72.364184)
        (xy 84.42736 72.346353)
        (xy 84.46663 72.332301)
        (xy 84.507087 72.322167)
        (xy 84.548343 72.316047)
        (xy 84.59 72.314)
        (xy 84.593999 72.314197)
        (xy 84.594 72.314)
        (xy 85.163447 72.314)
        (xy 85.176641 72.313352)
        (xy 85.218296 72.315399)
        (xy 85.259553 72.321519)
        (xy 85.30001 72.331653)
        (xy 85.33928 72.345704)
        (xy 85.376982 72.363536)
        (xy 85.412757 72.384978)
        (xy 85.446257 72.409823)
        (xy 85.47716 72.437832)
        (xy 85.505169 72.468734)
        (xy 85.530015 72.502235)
        (xy 85.551455 72.538009)
        (xy 85.569288 72.575713)
        (xy 85.583339 72.614982)
        (xy 85.593472 72.655439)
        (xy 85.599592 72.696695)
        (xy 85.60164 72.738351)
        (xy 85.599593 72.780009)
        (xy 85.593473 72.821265)
        (xy 85.583339 72.861722)
        (xy 85.569288 72.900992)
        (xy 85.551456 72.938695)
        (xy 85.530014 72.974469)
        (xy 85.505169 73.007968)
        (xy 85.47716 73.038872)
        (xy 85.446255 73.066881)
        (xy 85.412756 73.091726)
        (xy 85.376983 73.113168)
        (xy 85.33928 73.131)
        (xy 85.30001 73.145051)
        (xy 85.259553 73.155185)
        (xy 85.218297 73.161305)
        (xy 85.17664 73.163352)
        (xy 85.147747 73.161932)
        (xy 84.637587 73.161073)
        (xy 84.631657 73.161953)
        (xy 84.589999 73.164)
        (xy 84.548342 73.161953)
        (xy 84.507087 73.155834)
        (xy 84.46663 73.145699)
        (xy 84.42736 73.131648)
        (xy 84.389657 73.113817)
        (xy 84.353883 73.092374)
        (xy 84.320383 73.067529)
        (xy 84.28948 73.03952)
        (xy 84.261471 73.008617)
        (xy 84.236626 72.975117)
        (xy 84.215183 72.939343)
        (xy 84.197352 72.90164)
        (xy 84.183301 72.86237)
        (xy 84.173166 72.821913)
        (xy 84.167046 72.780657)
        (xy 84.165 72.739001)
      )
    )
  )
  (zone (net 0) (net_name "") (layers "In1.Cu" "In3.Cu" "In5.Cu" "In6.Cu") (hatch edge 0.508)
    (connect_pads yes (clearance 0))
    (min_thickness 0.1) (filled_areas_thickness no)
    (keepout (tracks allowed) (vias allowed) (pads allowed) (copperpour not_allowed) (footprints allowed))
    (fill (thermal_gap 0.254) (thermal_bridge_width 0.254))
    (polygon
      (pts
        (xy 118.797047 89.187343)
        (xy 118.803167 89.146087)
        (xy 118.813301 89.10563)
        (xy 118.827352 89.06636)
        (xy 118.845184 89.028657)
        (xy 118.866626 88.992883)
        (xy 118.891471 88.959383)
        (xy 118.91948 88.92848)
        (xy 118.950383 88.900471)
        (xy 118.983882 88.875626)
        (xy 119.019657 88.854184)
        (xy 119.05736 88.836353)
        (xy 119.09663 88.822301)
        (xy 119.137087 88.812167)
        (xy 119.178343 88.806047)
        (xy 119.22 88.804)
        (xy 119.223999 88.804197)
        (xy 119.224 88.804)
        (xy 119.793447 88.804)
        (xy 119.806641 88.803352)
        (xy 119.848296 88.805399)
        (xy 119.889553 88.811519)
        (xy 119.93001 88.821653)
        (xy 119.96928 88.835704)
        (xy 120.006982 88.853536)
        (xy 120.042757 88.874978)
        (xy 120.076257 88.899823)
        (xy 120.10716 88.927832)
        (xy 120.135169 88.958734)
        (xy 120.160015 88.992235)
        (xy 120.181455 89.028009)
        (xy 120.199288 89.065713)
        (xy 120.213339 89.104982)
        (xy 120.223472 89.145439)
        (xy 120.229592 89.186695)
        (xy 120.23164 89.228351)
        (xy 120.229593 89.270009)
        (xy 120.223473 89.311265)
        (xy 120.213339 89.351722)
        (xy 120.199288 89.390992)
        (xy 120.181456 89.428695)
        (xy 120.160014 89.464469)
        (xy 120.135169 89.497968)
        (xy 120.10716 89.528872)
        (xy 120.076255 89.556881)
        (xy 120.042756 89.581726)
        (xy 120.006983 89.603168)
        (xy 119.96928 89.621)
        (xy 119.93001 89.635051)
        (xy 119.889553 89.645185)
        (xy 119.848297 89.651305)
        (xy 119.80664 89.653352)
        (xy 119.777747 89.651932)
        (xy 119.267587 89.651073)
        (xy 119.261657 89.651953)
        (xy 119.219999 89.654)
        (xy 119.178342 89.651953)
        (xy 119.137087 89.645834)
        (xy 119.09663 89.635699)
        (xy 119.05736 89.621648)
        (xy 119.019657 89.603817)
        (xy 118.983883 89.582374)
        (xy 118.950383 89.557529)
        (xy 118.91948 89.52952)
        (xy 118.891471 89.498617)
        (xy 118.866626 89.465117)
        (xy 118.845183 89.429343)
        (xy 118.827352 89.39164)
        (xy 118.813301 89.35237)
        (xy 118.803166 89.311913)
        (xy 118.797046 89.270657)
        (xy 118.795 89.229001)
      )
    )
  )
  (zone (net 0) (net_name "") (layers "In1.Cu" "In3.Cu" "In5.Cu" "In6.Cu") (hatch edge 0.508)
    (connect_pads yes (clearance 0))
    (min_thickness 0.1) (filled_areas_thickness no)
    (keepout (tracks allowed) (vias allowed) (pads allowed) (copperpour not_allowed) (footprints allowed))
    (fill (thermal_gap 0.254) (thermal_bridge_width 0.254))
    (polygon
      (pts
        (xy 86.387047 72.665951)
        (xy 86.393167 72.624695)
        (xy 86.403301 72.584238)
        (xy 86.417352 72.544968)
        (xy 86.435184 72.507265)
        (xy 86.456626 72.471491)
        (xy 86.481471 72.437991)
        (xy 86.50948 72.407088)
        (xy 86.540383 72.379079)
        (xy 86.573882 72.354234)
        (xy 86.609657 72.332792)
        (xy 86.64736 72.314961)
        (xy 86.68663 72.300909)
        (xy 86.727087 72.290775)
        (xy 86.768343 72.284655)
        (xy 86.81 72.282608)
        (xy 86.813999 72.282805)
        (xy 86.814 72.282608)
        (xy 87.383447 72.282608)
        (xy 87.396641 72.28196)
        (xy 87.438296 72.284007)
        (xy 87.479553 72.290127)
        (xy 87.52001 72.300261)
        (xy 87.55928 72.314312)
        (xy 87.596982 72.332144)
        (xy 87.632757 72.353586)
        (xy 87.666257 72.378431)
        (xy 87.69716 72.40644)
        (xy 87.725169 72.437342)
        (xy 87.750015 72.470843)
        (xy 87.771455 72.506617)
        (xy 87.789288 72.544321)
        (xy 87.803339 72.58359)
        (xy 87.813472 72.624047)
        (xy 87.819592 72.665303)
        (xy 87.82164 72.706959)
        (xy 87.819593 72.748617)
        (xy 87.813473 72.789873)
        (xy 87.803339 72.83033)
        (xy 87.789288 72.8696)
        (xy 87.771456 72.907303)
        (xy 87.750014 72.943077)
        (xy 87.725169 72.976576)
        (xy 87.69716 73.00748)
        (xy 87.666255 73.035489)
        (xy 87.632756 73.060334)
        (xy 87.596983 73.081776)
        (xy 87.55928 73.099608)
        (xy 87.52001 73.113659)
        (xy 87.479553 73.123793)
        (xy 87.438297 73.129913)
        (xy 87.39664 73.13196)
        (xy 87.367747 73.13054)
        (xy 86.857587 73.129681)
        (xy 86.851657 73.130561)
        (xy 86.809999 73.132608)
        (xy 86.768342 73.130561)
        (xy 86.727087 73.124442)
        (xy 86.68663 73.114307)
        (xy 86.64736 73.100256)
        (xy 86.609657 73.082425)
        (xy 86.573883 73.060982)
        (xy 86.540383 73.036137)
        (xy 86.50948 73.008128)
        (xy 86.481471 72.977225)
        (xy 86.456626 72.943725)
        (xy 86.435183 72.907951)
        (xy 86.417352 72.870248)
        (xy 86.403301 72.830978)
        (xy 86.393166 72.790521)
        (xy 86.387046 72.749265)
        (xy 86.385 72.707609)
      )
    )
  )
  (zone (net 0) (net_name "") (layers "In1.Cu" "In3.Cu" "In5.Cu" "In6.Cu") (hatch edge 0.508)
    (connect_pads yes (clearance 0))
    (min_thickness 0.1) (filled_areas_thickness no)
    (keepout (tracks allowed) (vias allowed) (pads allowed) (copperpour not_allowed) (footprints allowed))
    (fill (thermal_gap 0.254) (thermal_bridge_width 0.254))
    (polygon
      (pts
        (xy 119.407047 95.527343)
        (xy 119.413167 95.486087)
        (xy 119.423301 95.44563)
        (xy 119.437352 95.40636)
        (xy 119.455184 95.368657)
        (xy 119.476626 95.332883)
        (xy 119.501471 95.299383)
        (xy 119.52948 95.26848)
        (xy 119.560383 95.240471)
        (xy 119.593882 95.215626)
        (xy 119.629657 95.194184)
        (xy 119.66736 95.176353)
        (xy 119.70663 95.162301)
        (xy 119.747087 95.152167)
        (xy 119.788343 95.146047)
        (xy 119.83 95.144)
        (xy 119.833999 95.144197)
        (xy 119.834 95.144)
        (xy 120.403447 95.144)
        (xy 120.416641 95.143352)
        (xy 120.458296 95.145399)
        (xy 120.499553 95.151519)
        (xy 120.54001 95.161653)
        (xy 120.57928 95.175704)
        (xy 120.616982 95.193536)
        (xy 120.652757 95.214978)
        (xy 120.686257 95.239823)
        (xy 120.71716 95.267832)
        (xy 120.745169 95.298734)
        (xy 120.770015 95.332235)
        (xy 120.791455 95.368009)
        (xy 120.809288 95.405713)
        (xy 120.823339 95.444982)
        (xy 120.833472 95.485439)
        (xy 120.839592 95.526695)
        (xy 120.84164 95.568351)
        (xy 120.839593 95.610009)
        (xy 120.833473 95.651265)
        (xy 120.823339 95.691722)
        (xy 120.809288 95.730992)
        (xy 120.791456 95.768695)
        (xy 120.770014 95.804469)
        (xy 120.745169 95.837968)
        (xy 120.71716 95.868872)
        (xy 120.686255 95.896881)
        (xy 120.652756 95.921726)
        (xy 120.616983 95.943168)
        (xy 120.57928 95.961)
        (xy 120.54001 95.975051)
        (xy 120.499553 95.985185)
        (xy 120.458297 95.991305)
        (xy 120.41664 95.993352)
        (xy 120.387747 95.991932)
        (xy 119.877587 95.991073)
        (xy 119.871657 95.991953)
        (xy 119.829999 95.994)
        (xy 119.788342 95.991953)
        (xy 119.747087 95.985834)
        (xy 119.70663 95.975699)
        (xy 119.66736 95.961648)
        (xy 119.629657 95.943817)
        (xy 119.593883 95.922374)
        (xy 119.560383 95.897529)
        (xy 119.52948 95.86952)
        (xy 119.501471 95.838617)
        (xy 119.476626 95.805117)
        (xy 119.455183 95.769343)
        (xy 119.437352 95.73164)
        (xy 119.423301 95.69237)
        (xy 119.413166 95.651913)
        (xy 119.407046 95.610657)
        (xy 119.405 95.569001)
      )
    )
  )
  (zone (net 0) (net_name "") (layers "In1.Cu" "In3.Cu" "In5.Cu" "In6.Cu") (hatch edge 0.508)
    (connect_pads yes (clearance 0))
    (min_thickness 0.1) (filled_areas_thickness no)
    (keepout (tracks allowed) (vias allowed) (pads allowed) (copperpour not_allowed) (footprints allowed))
    (fill (thermal_gap 0.254) (thermal_bridge_width 0.254))
    (polygon
      (pts
        (xy 111.117047 77.377343)
        (xy 111.123167 77.336087)
        (xy 111.133301 77.29563)
        (xy 111.147352 77.25636)
        (xy 111.165184 77.218657)
        (xy 111.186626 77.182883)
        (xy 111.211471 77.149383)
        (xy 111.23948 77.11848)
        (xy 111.270383 77.090471)
        (xy 111.303882 77.065626)
        (xy 111.339657 77.044184)
        (xy 111.37736 77.026353)
        (xy 111.41663 77.012301)
        (xy 111.457087 77.002167)
        (xy 111.498343 76.996047)
        (xy 111.54 76.994)
        (xy 111.543999 76.994197)
        (xy 111.544 76.994)
        (xy 112.113447 76.994)
        (xy 112.126641 76.993352)
        (xy 112.168296 76.995399)
        (xy 112.209553 77.001519)
        (xy 112.25001 77.011653)
        (xy 112.28928 77.025704)
        (xy 112.326982 77.043536)
        (xy 112.362757 77.064978)
        (xy 112.396257 77.089823)
        (xy 112.42716 77.117832)
        (xy 112.455169 77.148734)
        (xy 112.480015 77.182235)
        (xy 112.501455 77.218009)
        (xy 112.519288 77.255713)
        (xy 112.533339 77.294982)
        (xy 112.543472 77.335439)
        (xy 112.549592 77.376695)
        (xy 112.55164 77.418351)
        (xy 112.549593 77.460009)
        (xy 112.543473 77.501265)
        (xy 112.533339 77.541722)
        (xy 112.519288 77.580992)
        (xy 112.501456 77.618695)
        (xy 112.480014 77.654469)
        (xy 112.455169 77.687968)
        (xy 112.42716 77.718872)
        (xy 112.396255 77.746881)
        (xy 112.362756 77.771726)
        (xy 112.326983 77.793168)
        (xy 112.28928 77.811)
        (xy 112.25001 77.825051)
        (xy 112.209553 77.835185)
        (xy 112.168297 77.841305)
        (xy 112.12664 77.843352)
        (xy 112.097747 77.841932)
        (xy 111.587587 77.841073)
        (xy 111.581657 77.841953)
        (xy 111.539999 77.844)
        (xy 111.498342 77.841953)
        (xy 111.457087 77.835834)
        (xy 111.41663 77.825699)
        (xy 111.37736 77.811648)
        (xy 111.339657 77.793817)
        (xy 111.303883 77.772374)
        (xy 111.270383 77.747529)
        (xy 111.23948 77.71952)
        (xy 111.211471 77.688617)
        (xy 111.186626 77.655117)
        (xy 111.165183 77.619343)
        (xy 111.147352 77.58164)
        (xy 111.133301 77.54237)
        (xy 111.123166 77.501913)
        (xy 111.117046 77.460657)
        (xy 111.115 77.419001)
      )
    )
  )
  (zone (net 0) (net_name "") (layers "In1.Cu" "In3.Cu" "In5.Cu" "In6.Cu") (hatch edge 0.508)
    (connect_pads yes (clearance 0))
    (min_thickness 0.1) (filled_areas_thickness no)
    (keepout (tracks allowed) (vias allowed) (pads allowed) (copperpour not_allowed) (footprints allowed))
    (fill (thermal_gap 0.254) (thermal_bridge_width 0.254))
    (polygon
      (pts
        (xy 122.006485 76.787343)
        (xy 122.012605 76.746087)
        (xy 122.022739 76.70563)
        (xy 122.03679 76.66636)
        (xy 122.054622 76.628657)
        (xy 122.076064 76.592883)
        (xy 122.100909 76.559383)
        (xy 122.128918 76.52848)
        (xy 122.159821 76.500471)
        (xy 122.19332 76.475626)
        (xy 122.229095 76.454184)
        (xy 122.266798 76.436353)
        (xy 122.306068 76.422301)
        (xy 122.346525 76.412167)
        (xy 122.387781 76.406047)
        (xy 122.429438 76.404)
        (xy 122.433437 76.404197)
        (xy 122.433438 76.404)
        (xy 123.002885 76.404)
        (xy 123.016079 76.403352)
        (xy 123.057734 76.405399)
        (xy 123.098991 76.411519)
        (xy 123.139448 76.421653)
        (xy 123.178718 76.435704)
        (xy 123.21642 76.453536)
        (xy 123.252195 76.474978)
        (xy 123.285695 76.499823)
        (xy 123.316598 76.527832)
        (xy 123.344607 76.558734)
        (xy 123.369453 76.592235)
        (xy 123.390893 76.628009)
        (xy 123.408726 76.665713)
        (xy 123.422777 76.704982)
        (xy 123.43291 76.745439)
        (xy 123.43903 76.786695)
        (xy 123.441078 76.828351)
        (xy 123.439031 76.870009)
        (xy 123.432911 76.911265)
        (xy 123.422777 76.951722)
        (xy 123.408726 76.990992)
        (xy 123.390894 77.028695)
        (xy 123.369452 77.064469)
        (xy 123.344607 77.097968)
        (xy 123.316598 77.128872)
        (xy 123.285693 77.156881)
        (xy 123.252194 77.181726)
        (xy 123.216421 77.203168)
        (xy 123.178718 77.221)
        (xy 123.139448 77.235051)
        (xy 123.098991 77.245185)
        (xy 123.057735 77.251305)
        (xy 123.016078 77.253352)
        (xy 122.987185 77.251932)
        (xy 122.477025 77.251073)
        (xy 122.471095 77.251953)
        (xy 122.429437 77.254)
        (xy 122.38778 77.251953)
        (xy 122.346525 77.245834)
        (xy 122.306068 77.235699)
        (xy 122.266798 77.221648)
        (xy 122.229095 77.203817)
        (xy 122.193321 77.182374)
        (xy 122.159821 77.157529)
        (xy 122.128918 77.12952)
        (xy 122.100909 77.098617)
        (xy 122.076064 77.065117)
        (xy 122.054621 77.029343)
        (xy 122.03679 76.99164)
        (xy 122.022739 76.95237)
        (xy 122.012604 76.911913)
        (xy 122.006484 76.870657)
        (xy 122.004438 76.829001)
      )
    )
  )
  (zone (net 0) (net_name "") (layers "In1.Cu" "In3.Cu" "In5.Cu" "In6.Cu") (hatch edge 0.508)
    (connect_pads yes (clearance 0))
    (min_thickness 0.1) (filled_areas_thickness no)
    (keepout (tracks allowed) (vias allowed) (pads allowed) (copperpour not_allowed) (footprints allowed))
    (fill (thermal_gap 0.254) (thermal_bridge_width 0.254))
    (polygon
      (pts
        (xy 121.997047 89.187343)
        (xy 122.003167 89.146087)
        (xy 122.013301 89.10563)
        (xy 122.027352 89.06636)
        (xy 122.045184 89.028657)
        (xy 122.066626 88.992883)
        (xy 122.091471 88.959383)
        (xy 122.11948 88.92848)
        (xy 122.150383 88.900471)
        (xy 122.183882 88.875626)
        (xy 122.219657 88.854184)
        (xy 122.25736 88.836353)
        (xy 122.29663 88.822301)
        (xy 122.337087 88.812167)
        (xy 122.378343 88.806047)
        (xy 122.42 88.804)
        (xy 122.423999 88.804197)
        (xy 122.424 88.804)
        (xy 122.993447 88.804)
        (xy 123.006641 88.803352)
        (xy 123.048296 88.805399)
        (xy 123.089553 88.811519)
        (xy 123.13001 88.821653)
        (xy 123.16928 88.835704)
        (xy 123.206982 88.853536)
        (xy 123.242757 88.874978)
        (xy 123.276257 88.899823)
        (xy 123.30716 88.927832)
        (xy 123.335169 88.958734)
        (xy 123.360015 88.992235)
        (xy 123.381455 89.028009)
        (xy 123.399288 89.065713)
        (xy 123.413339 89.104982)
        (xy 123.423472 89.145439)
        (xy 123.429592 89.186695)
        (xy 123.43164 89.228351)
        (xy 123.429593 89.270009)
        (xy 123.423473 89.311265)
        (xy 123.413339 89.351722)
        (xy 123.399288 89.390992)
        (xy 123.381456 89.428695)
        (xy 123.360014 89.464469)
        (xy 123.335169 89.497968)
        (xy 123.30716 89.528872)
        (xy 123.276255 89.556881)
        (xy 123.242756 89.581726)
        (xy 123.206983 89.603168)
        (xy 123.16928 89.621)
        (xy 123.13001 89.635051)
        (xy 123.089553 89.645185)
        (xy 123.048297 89.651305)
        (xy 123.00664 89.653352)
        (xy 122.977747 89.651932)
        (xy 122.467587 89.651073)
        (xy 122.461657 89.651953)
        (xy 122.419999 89.654)
        (xy 122.378342 89.651953)
        (xy 122.337087 89.645834)
        (xy 122.29663 89.635699)
        (xy 122.25736 89.621648)
        (xy 122.219657 89.603817)
        (xy 122.183883 89.582374)
        (xy 122.150383 89.557529)
        (xy 122.11948 89.52952)
        (xy 122.091471 89.498617)
        (xy 122.066626 89.465117)
        (xy 122.045183 89.429343)
        (xy 122.027352 89.39164)
        (xy 122.013301 89.35237)
        (xy 122.003166 89.311913)
        (xy 121.997046 89.270657)
        (xy 121.995 89.229001)
      )
    )
  )
  (zone (net 0) (net_name "") (layers "In1.Cu" "In3.Cu" "In5.Cu" "In6.Cu") (hatch edge 0.508)
    (connect_pads yes (clearance 0))
    (min_thickness 0.1) (filled_areas_thickness no)
    (keepout (tracks allowed) (vias allowed) (pads allowed) (copperpour not_allowed) (footprints allowed))
    (fill (thermal_gap 0.254) (thermal_bridge_width 0.254))
    (polygon
      (pts
        (xy 120.617047 76.867343)
        (xy 120.623167 76.826087)
        (xy 120.633301 76.78563)
        (xy 120.647352 76.74636)
        (xy 120.665184 76.708657)
        (xy 120.686626 76.672883)
        (xy 120.711471 76.639383)
        (xy 120.73948 76.60848)
        (xy 120.770383 76.580471)
        (xy 120.803882 76.555626)
        (xy 120.839657 76.534184)
        (xy 120.87736 76.516353)
        (xy 120.91663 76.502301)
        (xy 120.957087 76.492167)
        (xy 120.998343 76.486047)
        (xy 121.04 76.484)
        (xy 121.043999 76.484197)
        (xy 121.044 76.484)
        (xy 121.613447 76.484)
        (xy 121.626641 76.483352)
        (xy 121.668296 76.485399)
        (xy 121.709553 76.491519)
        (xy 121.75001 76.501653)
        (xy 121.78928 76.515704)
        (xy 121.826982 76.533536)
        (xy 121.862757 76.554978)
        (xy 121.896257 76.579823)
        (xy 121.92716 76.607832)
        (xy 121.955169 76.638734)
        (xy 121.980015 76.672235)
        (xy 122.001455 76.708009)
        (xy 122.019288 76.745713)
        (xy 122.033339 76.784982)
        (xy 122.043472 76.825439)
        (xy 122.049592 76.866695)
        (xy 122.05164 76.908351)
        (xy 122.049593 76.950009)
        (xy 122.043473 76.991265)
        (xy 122.033339 77.031722)
        (xy 122.019288 77.070992)
        (xy 122.001456 77.108695)
        (xy 121.980014 77.144469)
        (xy 121.955169 77.177968)
        (xy 121.92716 77.208872)
        (xy 121.896255 77.236881)
        (xy 121.862756 77.261726)
        (xy 121.826983 77.283168)
        (xy 121.78928 77.301)
        (xy 121.75001 77.315051)
        (xy 121.709553 77.325185)
        (xy 121.668297 77.331305)
        (xy 121.62664 77.333352)
        (xy 121.597747 77.331932)
        (xy 121.087587 77.331073)
        (xy 121.081657 77.331953)
        (xy 121.039999 77.334)
        (xy 120.998342 77.331953)
        (xy 120.957087 77.325834)
        (xy 120.91663 77.315699)
        (xy 120.87736 77.301648)
        (xy 120.839657 77.283817)
        (xy 120.803883 77.262374)
        (xy 120.770383 77.237529)
        (xy 120.73948 77.20952)
        (xy 120.711471 77.178617)
        (xy 120.686626 77.145117)
        (xy 120.665183 77.109343)
        (xy 120.647352 77.07164)
        (xy 120.633301 77.03237)
        (xy 120.623166 76.991913)
        (xy 120.617046 76.950657)
        (xy 120.615 76.909001)
      )
    )
  )
  (zone (net 0) (net_name "") (layers "In1.Cu" "In3.Cu" "In5.Cu" "In6.Cu") (hatch edge 0.508)
    (connect_pads yes (clearance 0))
    (min_thickness 0.1) (filled_areas_thickness no)
    (keepout (tracks allowed) (vias allowed) (pads allowed) (copperpour not_allowed) (footprints allowed))
    (fill (thermal_gap 0.254) (thermal_bridge_width 0.254))
    (polygon
      (pts
        (xy 129.107047 77.347343)
        (xy 129.113167 77.306087)
        (xy 129.123301 77.26563)
        (xy 129.137352 77.22636)
        (xy 129.155184 77.188657)
        (xy 129.176626 77.152883)
        (xy 129.201471 77.119383)
        (xy 129.22948 77.08848)
        (xy 129.260383 77.060471)
        (xy 129.293882 77.035626)
        (xy 129.329657 77.014184)
        (xy 129.36736 76.996353)
        (xy 129.40663 76.982301)
        (xy 129.447087 76.972167)
        (xy 129.488343 76.966047)
        (xy 129.53 76.964)
        (xy 129.533999 76.964197)
        (xy 129.534 76.964)
        (xy 130.103447 76.964)
        (xy 130.116641 76.963352)
        (xy 130.158296 76.965399)
        (xy 130.199553 76.971519)
        (xy 130.24001 76.981653)
        (xy 130.27928 76.995704)
        (xy 130.316982 77.013536)
        (xy 130.352757 77.034978)
        (xy 130.386257 77.059823)
        (xy 130.41716 77.087832)
        (xy 130.445169 77.118734)
        (xy 130.470015 77.152235)
        (xy 130.491455 77.188009)
        (xy 130.509288 77.225713)
        (xy 130.523339 77.264982)
        (xy 130.533472 77.305439)
        (xy 130.539592 77.346695)
        (xy 130.54164 77.388351)
        (xy 130.539593 77.430009)
        (xy 130.533473 77.471265)
        (xy 130.523339 77.511722)
        (xy 130.509288 77.550992)
        (xy 130.491456 77.588695)
        (xy 130.470014 77.624469)
        (xy 130.445169 77.657968)
        (xy 130.41716 77.688872)
        (xy 130.386255 77.716881)
        (xy 130.352756 77.741726)
        (xy 130.316983 77.763168)
        (xy 130.27928 77.781)
        (xy 130.24001 77.795051)
        (xy 130.199553 77.805185)
        (xy 130.158297 77.811305)
        (xy 130.11664 77.813352)
        (xy 130.087747 77.811932)
        (xy 129.577587 77.811073)
        (xy 129.571657 77.811953)
        (xy 129.529999 77.814)
        (xy 129.488342 77.811953)
        (xy 129.447087 77.805834)
        (xy 129.40663 77.795699)
        (xy 129.36736 77.781648)
        (xy 129.329657 77.763817)
        (xy 129.293883 77.742374)
        (xy 129.260383 77.717529)
        (xy 129.22948 77.68952)
        (xy 129.201471 77.658617)
        (xy 129.176626 77.625117)
        (xy 129.155183 77.589343)
        (xy 129.137352 77.55164)
        (xy 129.123301 77.51237)
        (xy 129.113166 77.471913)
        (xy 129.107046 77.430657)
        (xy 129.105 77.389001)
      )
    )
  )
  (zone (net 0) (net_name "") (layers "In1.Cu" "In3.Cu" "In5.Cu" "In6.Cu") (hatch edge 0.508)
    (connect_pads yes (clearance 0))
    (min_thickness 0.1) (filled_areas_thickness no)
    (keepout (tracks allowed) (vias allowed) (pads allowed) (copperpour not_allowed) (footprints allowed))
    (fill (thermal_gap 0.254) (thermal_bridge_width 0.254))
    (polygon
      (pts
        (xy 133.752657 129.807047)
        (xy 133.793913 129.813167)
        (xy 133.83437 129.823301)
        (xy 133.87364 129.837352)
        (xy 133.911343 129.855184)
        (xy 133.947117 129.876626)
        (xy 133.980617 129.901471)
        (xy 134.01152 129.92948)
        (xy 134.039529 129.960383)
        (xy 134.064374 129.993882)
        (xy 134.085816 130.029657)
        (xy 134.103647 130.06736)
        (xy 134.117699 130.10663)
        (xy 134.127833 130.147087)
        (xy 134.133953 130.188343)
        (xy 134.136 130.23)
        (xy 134.135803 130.234)
        (xy 134.136 130.234)
        (xy 134.136 130.803447)
        (xy 134.136648 130.81664)
        (xy 134.134601 130.858296)
        (xy 134.128481 130.899553)
        (xy 134.118347 130.94001)
        (xy 134.104296 130.97928)
        (xy 134.086464 131.016982)
        (xy 134.065022 131.052757)
        (xy 134.040177 131.086257)
        (xy 134.012168 131.11716)
        (xy 133.981266 131.145169)
        (xy 133.947765 131.170015)
        (xy 133.911991 131.191455)
        (xy 133.874287 131.209288)
        (xy 133.835018 131.223339)
        (xy 133.794561 131.233472)
        (xy 133.753305 131.239592)
        (xy 133.711648 131.24164)
        (xy 133.669991 131.239593)
        (xy 133.628735 131.233473)
        (xy 133.588278 131.223339)
        (xy 133.549008 131.209288)
        (xy 133.511305 131.191456)
        (xy 133.475531 131.170014)
        (xy 133.442032 131.145169)
        (xy 133.411128 131.11716)
        (xy 133.383119 131.086256)
        (xy 133.358274 131.052756)
        (xy 133.336832 131.016983)
        (xy 133.319 130.97928)
        (xy 133.304949 130.94001)
        (xy 133.294815 130.899553)
        (xy 133.288695 130.858297)
        (xy 133.286648 130.81664)
        (xy 133.288068 130.787747)
        (xy 133.288927 130.277587)
        (xy 133.288047 130.271657)
        (xy 133.286 130.23)
        (xy 133.288047 130.188342)
        (xy 133.294166 130.147087)
        (xy 133.304301 130.10663)
        (xy 133.318352 130.06736)
        (xy 133.336183 130.029657)
        (xy 133.357626 129.993883)
        (xy 133.382471 129.960383)
        (xy 133.41048 129.92948)
        (xy 133.441383 129.901471)
        (xy 133.474883 129.876626)
        (xy 133.510657 129.855183)
        (xy 133.54836 129.837352)
        (xy 133.58763 129.823301)
        (xy 133.628087 129.813166)
        (xy 133.669343 129.807046)
        (xy 133.711 129.805)
      )
    )
  )
  (zone (net 0) (net_name "") (layers "In1.Cu" "In3.Cu" "In5.Cu" "In6.Cu") (hatch edge 0.508)
    (connect_pads yes (clearance 0))
    (min_thickness 0.1) (filled_areas_thickness no)
    (keepout (tracks allowed) (vias allowed) (pads allowed) (copperpour not_allowed) (footprints allowed))
    (fill (thermal_gap 0.254) (thermal_bridge_width 0.254))
    (polygon
      (pts
        (xy 108.317047 77.607343)
        (xy 108.323167 77.566087)
        (xy 108.333301 77.52563)
        (xy 108.347352 77.48636)
        (xy 108.365184 77.448657)
        (xy 108.386626 77.412883)
        (xy 108.411471 77.379383)
        (xy 108.43948 77.34848)
        (xy 108.470383 77.320471)
        (xy 108.503882 77.295626)
        (xy 108.539657 77.274184)
        (xy 108.57736 77.256353)
        (xy 108.61663 77.242301)
        (xy 108.657087 77.232167)
        (xy 108.698343 77.226047)
        (xy 108.74 77.224)
        (xy 108.743999 77.224197)
        (xy 108.744 77.224)
        (xy 109.313447 77.224)
        (xy 109.326641 77.223352)
        (xy 109.368296 77.225399)
        (xy 109.409553 77.231519)
        (xy 109.45001 77.241653)
        (xy 109.48928 77.255704)
        (xy 109.526982 77.273536)
        (xy 109.562757 77.294978)
        (xy 109.596257 77.319823)
        (xy 109.62716 77.347832)
        (xy 109.655169 77.378734)
        (xy 109.680015 77.412235)
        (xy 109.701455 77.448009)
        (xy 109.719288 77.485713)
        (xy 109.733339 77.524982)
        (xy 109.743472 77.565439)
        (xy 109.749592 77.606695)
        (xy 109.75164 77.648351)
        (xy 109.749593 77.690009)
        (xy 109.743473 77.731265)
        (xy 109.733339 77.771722)
        (xy 109.719288 77.810992)
        (xy 109.701456 77.848695)
        (xy 109.680014 77.884469)
        (xy 109.655169 77.917968)
        (xy 109.62716 77.948872)
        (xy 109.596255 77.976881)
        (xy 109.562756 78.001726)
        (xy 109.526983 78.023168)
        (xy 109.48928 78.041)
        (xy 109.45001 78.055051)
        (xy 109.409553 78.065185)
        (xy 109.368297 78.071305)
        (xy 109.32664 78.073352)
        (xy 109.297747 78.071932)
        (xy 108.787587 78.071073)
        (xy 108.781657 78.071953)
        (xy 108.739999 78.074)
        (xy 108.698342 78.071953)
        (xy 108.657087 78.065834)
        (xy 108.61663 78.055699)
        (xy 108.57736 78.041648)
        (xy 108.539657 78.023817)
        (xy 108.503883 78.002374)
        (xy 108.470383 77.977529)
        (xy 108.43948 77.94952)
        (xy 108.411471 77.918617)
        (xy 108.386626 77.885117)
        (xy 108.365183 77.849343)
        (xy 108.347352 77.81164)
        (xy 108.333301 77.77237)
        (xy 108.323166 77.731913)
        (xy 108.317046 77.690657)
        (xy 108.315 77.649001)
      )
    )
  )
  (zone (net 0) (net_name "") (layers "In1.Cu" "In3.Cu" "In5.Cu" "In6.Cu") (hatch edge 0.508)
    (connect_pads yes (clearance 0))
    (min_thickness 0.1) (filled_areas_thickness no)
    (keepout (tracks allowed) (vias allowed) (pads allowed) (copperpour not_allowed) (footprints allowed))
    (fill (thermal_gap 0.254) (thermal_bridge_width 0.254))
    (polygon
      (pts
        (xy 147.007047 111.087343)
        (xy 147.013167 111.046087)
        (xy 147.023301 111.00563)
        (xy 147.037352 110.96636)
        (xy 147.055184 110.928657)
        (xy 147.076626 110.892883)
        (xy 147.101471 110.859383)
        (xy 147.12948 110.82848)
        (xy 147.160383 110.800471)
        (xy 147.193882 110.775626)
        (xy 147.229657 110.754184)
        (xy 147.26736 110.736353)
        (xy 147.30663 110.722301)
        (xy 147.347087 110.712167)
        (xy 147.388343 110.706047)
        (xy 147.43 110.704)
        (xy 147.433999 110.704197)
        (xy 147.434 110.704)
        (xy 148.003447 110.704)
        (xy 148.016641 110.703352)
        (xy 148.058296 110.705399)
        (xy 148.099553 110.711519)
        (xy 148.14001 110.721653)
        (xy 148.17928 110.735704)
        (xy 148.216982 110.753536)
        (xy 148.252757 110.774978)
        (xy 148.286257 110.799823)
        (xy 148.31716 110.827832)
        (xy 148.345169 110.858734)
        (xy 148.370015 110.892235)
        (xy 148.391455 110.928009)
        (xy 148.409288 110.965713)
        (xy 148.423339 111.004982)
        (xy 148.433472 111.045439)
        (xy 148.439592 111.086695)
        (xy 148.44164 111.128351)
        (xy 148.439593 111.170009)
        (xy 148.433473 111.211265)
        (xy 148.423339 111.251722)
        (xy 148.409288 111.290992)
        (xy 148.391456 111.328695)
        (xy 148.370014 111.364469)
        (xy 148.345169 111.397968)
        (xy 148.31716 111.428872)
        (xy 148.286255 111.456881)
        (xy 148.252756 111.481726)
        (xy 148.216983 111.503168)
        (xy 148.17928 111.521)
        (xy 148.14001 111.535051)
        (xy 148.099553 111.545185)
        (xy 148.058297 111.551305)
        (xy 148.01664 111.553352)
        (xy 147.987747 111.551932)
        (xy 147.477587 111.551073)
        (xy 147.471657 111.551953)
        (xy 147.429999 111.554)
        (xy 147.388342 111.551953)
        (xy 147.347087 111.545834)
        (xy 147.30663 111.535699)
        (xy 147.26736 111.521648)
        (xy 147.229657 111.503817)
        (xy 147.193883 111.482374)
        (xy 147.160383 111.457529)
        (xy 147.12948 111.42952)
        (xy 147.101471 111.398617)
        (xy 147.076626 111.365117)
        (xy 147.055183 111.329343)
        (xy 147.037352 111.29164)
        (xy 147.023301 111.25237)
        (xy 147.013166 111.211913)
        (xy 147.007046 111.170657)
        (xy 147.005 111.129001)
      )
    )
  )
  (zone (net 0) (net_name "") (layers "In1.Cu" "In5.Cu" "In6.Cu") (hatch edge 0.508)
    (connect_pads yes (clearance 0))
    (min_thickness 0.1) (filled_areas_thickness no)
    (keepout (tracks allowed) (vias allowed) (pads allowed) (copperpour not_allowed) (footprints allowed))
    (fill (thermal_gap 0.254) (thermal_bridge_width 0.254))
    (polygon
      (pts
        (xy 77.922648 101.88064)
        (xy 77.924695 101.838983)
        (xy 77.930815 101.797727)
        (xy 77.940949 101.75727)
        (xy 77.955 101.718001)
        (xy 77.972832 101.680297)
        (xy 77.994273 101.644523)
        (xy 78.019119 101.611022)
        (xy 78.047128 101.58012)
        (xy 78.078031 101.55211)
        (xy 78.111531 101.527266)
        (xy 78.147305 101.505824)
        (xy 78.185008 101.487992)
        (xy 78.224278 101.473941)
        (xy 78.264735 101.463807)
        (xy 78.305991 101.457687)
        (xy 78.347648 101.45564)
        (xy 78.389306 101.457687)
        (xy 78.43056 101.463807)
        (xy 78.471018 101.473941)
        (xy 78.510288 101.487991)
        (xy 78.547991 101.505825)
        (xy 78.583765 101.527266)
        (xy 78.617265 101.55211)
        (xy 78.648168 101.58012)
        (xy 78.676177 101.611023)
        (xy 78.701022 101.644523)
        (xy 78.722464 101.680298)
        (xy 78.740296 101.718)
        (xy 78.754347 101.75727)
        (xy 78.764481 101.797728)
        (xy 78.770602 101.838983)
        (xy 78.772648 101.88064)
        (xy 78.770601 101.922296)
        (xy 78.764481 101.963553)
        (xy 78.754347 102.00401)
        (xy 78.740296 102.04328)
        (xy 78.722464 102.080982)
        (xy 78.701022 102.116757)
        (xy 78.676177 102.150257)
        (xy 78.648168 102.18116)
        (xy 78.617266 102.209169)
        (xy 78.583765 102.234015)
        (xy 78.547991 102.255455)
        (xy 78.510287 102.273288)
        (xy 78.471018 102.287339)
        (xy 78.430561 102.297472)
        (xy 78.389305 102.303592)
        (xy 78.347648 102.30564)
        (xy 78.305991 102.303593)
        (xy 78.264735 102.297473)
        (xy 78.224278 102.287339)
        (xy 78.185008 102.273288)
        (xy 78.147305 102.255456)
        (xy 78.111531 102.234014)
        (xy 78.078032 102.209169)
        (xy 78.047128 102.18116)
        (xy 78.019119 102.150256)
        (xy 77.994274 102.116756)
        (xy 77.972832 102.080983)
        (xy 77.955 102.04328)
        (xy 77.940949 102.00401)
        (xy 77.930815 101.963553)
        (xy 77.924695 101.922297)
      )
    )
  )
  (zone (net 0) (net_name "") (layers "In1.Cu" "In5.Cu" "In6.Cu") (hatch edge 0.508)
    (connect_pads yes (clearance 0))
    (min_thickness 0.1) (filled_areas_thickness no)
    (keepout (tracks allowed) (vias allowed) (pads allowed) (copperpour not_allowed) (footprints allowed))
    (fill (thermal_gap 0.254) (thermal_bridge_width 0.254))
    (polygon
      (pts
        (xy 77.924 101.892)
        (xy 77.925 101.298)
        (xy 78.772 101.298)
        (xy 78.772 101.893)
      )
    )
  )
  (zone (net 0) (net_name "") (layers "In1.Cu" "In5.Cu" "In6.Cu") (hatch edge 0.508)
    (connect_pads yes (clearance 0))
    (min_thickness 0.1) (filled_areas_thickness no)
    (keepout (tracks allowed) (vias allowed) (pads allowed) (copperpour not_allowed) (footprints allowed))
    (fill (thermal_gap 0.254) (thermal_bridge_width 0.254))
    (polygon
      (pts
        (xy 77.922 101.294)
        (xy 77.924047 101.252342)
        (xy 77.930166 101.211087)
        (xy 77.940301 101.17063)
        (xy 77.954352 101.13136)
        (xy 77.972183 101.093657)
        (xy 77.993626 101.057883)
        (xy 78.018471 101.024383)
        (xy 78.04648 100.99348)
        (xy 78.077383 100.965471)
        (xy 78.110883 100.940626)
        (xy 78.146657 100.919183)
        (xy 78.18436 100.901352)
        (xy 78.22363 100.887301)
        (xy 78.264087 100.877166)
        (xy 78.305343 100.871046)
        (xy 78.347 100.869)
        (xy 78.388657 100.871047)
        (xy 78.429913 100.877167)
        (xy 78.47037 100.887301)
        (xy 78.50964 100.901352)
        (xy 78.547343 100.919184)
        (xy 78.583117 100.940626)
        (xy 78.616617 100.965471)
        (xy 78.64752 100.99348)
        (xy 78.675529 101.024383)
        (xy 78.700374 101.057882)
        (xy 78.721816 101.093657)
        (xy 78.739647 101.13136)
        (xy 78.753699 101.17063)
        (xy 78.763833 101.211087)
        (xy 78.769953 101.252343)
        (xy 78.772 101.294)
        (xy 78.769953 101.335657)
        (xy 78.763833 101.376913)
        (xy 78.753699 101.417371)
        (xy 78.739648 101.45664)
        (xy 78.721816 101.494343)
        (xy 78.700374 101.530117)
        (xy 78.675529 101.563616)
        (xy 78.647521 101.59452)
        (xy 78.616616 101.622529)
        (xy 78.583117 101.647374)
        (xy 78.547343 101.668816)
        (xy 78.50964 101.686648)
        (xy 78.47037 101.700699)
        (xy 78.429913 101.710833)
        (xy 78.388657 101.716953)
        (xy 78.347 101.719)
        (xy 78.305343 101.716953)
        (xy 78.264087 101.710833)
        (xy 78.22363 101.700699)
        (xy 78.18436 101.686647)
        (xy 78.146657 101.668816)
        (xy 78.110882 101.647374)
        (xy 78.077382 101.622529)
        (xy 78.04648 101.59452)
        (xy 78.018471 101.563617)
        (xy 77.993626 101.530117)
        (xy 77.972184 101.494343)
        (xy 77.954352 101.45664)
        (xy 77.940301 101.41737)
        (xy 77.930167 101.376913)
        (xy 77.924047 101.335657)
      )
    )
  )
  (zone (net 0) (net_name "") (layers "In1.Cu" "In5.Cu" "In6.Cu") (hatch edge 0.508)
    (connect_pads yes (clearance 0))
    (min_thickness 0.1) (filled_areas_thickness no)
    (keepout (tracks allowed) (vias allowed) (pads allowed) (copperpour not_allowed) (footprints allowed))
    (fill (thermal_gap 0.254) (thermal_bridge_width 0.254))
    (polygon
      (pts
        (xy 77.778 102.702)
        (xy 77.780047 102.660342)
        (xy 77.786166 102.619087)
        (xy 77.796301 102.57863)
        (xy 77.810352 102.53936)
        (xy 77.828183 102.501657)
        (xy 77.849626 102.465883)
        (xy 77.874471 102.432383)
        (xy 77.90248 102.40148)
        (xy 77.933383 102.373471)
        (xy 77.966883 102.348626)
        (xy 78.002657 102.327183)
        (xy 78.04036 102.309352)
        (xy 78.07963 102.295301)
        (xy 78.120087 102.285166)
        (xy 78.161343 102.279046)
        (xy 78.203 102.277)
        (xy 78.244657 102.279047)
        (xy 78.285913 102.285167)
        (xy 78.32637 102.295301)
        (xy 78.36564 102.309352)
        (xy 78.403343 102.327184)
        (xy 78.439117 102.348626)
        (xy 78.472617 102.373471)
        (xy 78.50352 102.40148)
        (xy 78.531529 102.432383)
        (xy 78.556374 102.465882)
        (xy 78.577816 102.501657)
        (xy 78.595647 102.53936)
        (xy 78.609699 102.57863)
        (xy 78.619833 102.619087)
        (xy 78.625953 102.660343)
        (xy 78.628 102.702)
        (xy 78.625953 102.743657)
        (xy 78.619833 102.784913)
        (xy 78.609699 102.825371)
        (xy 78.595648 102.86464)
        (xy 78.577816 102.902343)
        (xy 78.556374 102.938117)
        (xy 78.531529 102.971616)
        (xy 78.503521 103.00252)
        (xy 78.472616 103.030529)
        (xy 78.439117 103.055374)
        (xy 78.403343 103.076816)
        (xy 78.36564 103.094648)
        (xy 78.32637 103.108699)
        (xy 78.285913 103.118833)
        (xy 78.244657 103.124953)
        (xy 78.203 103.127)
        (xy 78.161343 103.124953)
        (xy 78.120087 103.118833)
        (xy 78.07963 103.108699)
        (xy 78.04036 103.094647)
        (xy 78.002657 103.076816)
        (xy 77.966882 103.055374)
        (xy 77.933382 103.030529)
        (xy 77.90248 103.00252)
        (xy 77.874471 102.971617)
        (xy 77.849626 102.938117)
        (xy 77.828184 102.902343)
        (xy 77.810352 102.86464)
        (xy 77.796301 102.82537)
        (xy 77.786167 102.784913)
        (xy 77.780047 102.743657)
      )
    )
  )
  (zone (net 0) (net_name "") (layers "In1.Cu" "In5.Cu" "In6.Cu") (hatch edge 0.508)
    (connect_pads yes (clearance 0))
    (min_thickness 0.1) (filled_areas_thickness no)
    (keepout (tracks allowed) (vias allowed) (pads allowed) (copperpour not_allowed) (footprints allowed))
    (fill (thermal_gap 0.254) (thermal_bridge_width 0.254))
    (polygon
      (pts
        (xy 77.78 103.3)
        (xy 77.781 102.706)
        (xy 78.628 102.706)
        (xy 78.628 103.301)
      )
    )
  )
  (zone (net 0) (net_name "") (layers "In1.Cu" "In5.Cu" "In6.Cu") (hatch edge 0.508)
    (connect_pads yes (clearance 0))
    (min_thickness 0.1) (filled_areas_thickness no)
    (keepout (tracks allowed) (vias allowed) (pads allowed) (copperpour not_allowed) (footprints allowed))
    (fill (thermal_gap 0.254) (thermal_bridge_width 0.254))
    (polygon
      (pts
        (xy 77.778648 103.28864)
        (xy 77.780695 103.246983)
        (xy 77.786815 103.205727)
        (xy 77.796949 103.16527)
        (xy 77.811 103.126001)
        (xy 77.828832 103.088297)
        (xy 77.850273 103.052523)
        (xy 77.875119 103.019022)
        (xy 77.903128 102.98812)
        (xy 77.934031 102.96011)
        (xy 77.967531 102.935266)
        (xy 78.003305 102.913824)
        (xy 78.041008 102.895992)
        (xy 78.080278 102.881941)
        (xy 78.120735 102.871807)
        (xy 78.161991 102.865687)
        (xy 78.203648 102.86364)
        (xy 78.245306 102.865687)
        (xy 78.28656 102.871807)
        (xy 78.327018 102.881941)
        (xy 78.366288 102.895991)
        (xy 78.403991 102.913825)
        (xy 78.439765 102.935266)
        (xy 78.473265 102.96011)
        (xy 78.504168 102.98812)
        (xy 78.532177 103.019023)
        (xy 78.557022 103.052523)
        (xy 78.578464 103.088298)
        (xy 78.596296 103.126)
        (xy 78.610347 103.16527)
        (xy 78.620481 103.205728)
        (xy 78.626602 103.246983)
        (xy 78.628648 103.28864)
        (xy 78.626601 103.330296)
        (xy 78.620481 103.371553)
        (xy 78.610347 103.41201)
        (xy 78.596296 103.45128)
        (xy 78.578464 103.488982)
        (xy 78.557022 103.524757)
        (xy 78.532177 103.558257)
        (xy 78.504168 103.58916)
        (xy 78.473266 103.617169)
        (xy 78.439765 103.642015)
        (xy 78.403991 103.663455)
        (xy 78.366287 103.681288)
        (xy 78.327018 103.695339)
        (xy 78.286561 103.705472)
        (xy 78.245305 103.711592)
        (xy 78.203648 103.71364)
        (xy 78.161991 103.711593)
        (xy 78.120735 103.705473)
        (xy 78.080278 103.695339)
        (xy 78.041008 103.681288)
        (xy 78.003305 103.663456)
        (xy 77.967531 103.642014)
        (xy 77.934032 103.617169)
        (xy 77.903128 103.58916)
        (xy 77.875119 103.558256)
        (xy 77.850274 103.524756)
        (xy 77.828832 103.488983)
        (xy 77.811 103.45128)
        (xy 77.796949 103.41201)
        (xy 77.786815 103.371553)
        (xy 77.780695 103.330297)
      )
    )
  )
  (zone (net 0) (net_name "") (layers "In1.Cu" "In5.Cu" "In6.Cu") (hatch edge 0.508)
    (connect_pads yes (clearance 0))
    (min_thickness 0.1) (filled_areas_thickness no)
    (keepout (tracks allowed) (vias allowed) (pads allowed) (copperpour not_allowed) (footprints allowed))
    (fill (thermal_gap 0.254) (thermal_bridge_width 0.254))
    (polygon
      (pts
        (xy 77.92 99.876)
        (xy 77.922047 99.834342)
        (xy 77.928166 99.793087)
        (xy 77.938301 99.75263)
        (xy 77.952352 99.71336)
        (xy 77.970183 99.675657)
        (xy 77.991626 99.639883)
        (xy 78.016471 99.606383)
        (xy 78.04448 99.57548)
        (xy 78.075383 99.547471)
        (xy 78.108883 99.522626)
        (xy 78.144657 99.501183)
        (xy 78.18236 99.483352)
        (xy 78.22163 99.469301)
        (xy 78.262087 99.459166)
        (xy 78.303343 99.453046)
        (xy 78.345 99.451)
        (xy 78.386657 99.453047)
        (xy 78.427913 99.459167)
        (xy 78.46837 99.469301)
        (xy 78.50764 99.483352)
        (xy 78.545343 99.501184)
        (xy 78.581117 99.522626)
        (xy 78.614617 99.547471)
        (xy 78.64552 99.57548)
        (xy 78.673529 99.606383)
        (xy 78.698374 99.639882)
        (xy 78.719816 99.675657)
        (xy 78.737647 99.71336)
        (xy 78.751699 99.75263)
        (xy 78.761833 99.793087)
        (xy 78.767953 99.834343)
        (xy 78.77 99.876)
        (xy 78.767953 99.917657)
        (xy 78.761833 99.958913)
        (xy 78.751699 99.999371)
        (xy 78.737648 100.03864)
        (xy 78.719816 100.076343)
        (xy 78.698374 100.112117)
        (xy 78.673529 100.145616)
        (xy 78.645521 100.17652)
        (xy 78.614616 100.204529)
        (xy 78.581117 100.229374)
        (xy 78.545343 100.250816)
        (xy 78.50764 100.268648)
        (xy 78.46837 100.282699)
        (xy 78.427913 100.292833)
        (xy 78.386657 100.298953)
        (xy 78.345 100.301)
        (xy 78.303343 100.298953)
        (xy 78.262087 100.292833)
        (xy 78.22163 100.282699)
        (xy 78.18236 100.268647)
        (xy 78.144657 100.250816)
        (xy 78.108882 100.229374)
        (xy 78.075382 100.204529)
        (xy 78.04448 100.17652)
        (xy 78.016471 100.145617)
        (xy 77.991626 100.112117)
        (xy 77.970184 100.076343)
        (xy 77.952352 100.03864)
        (xy 77.938301 99.99937)
        (xy 77.928167 99.958913)
        (xy 77.922047 99.917657)
      )
    )
  )
  (zone (net 0) (net_name "") (layers "In1.Cu" "In5.Cu" "In6.Cu") (hatch edge 0.508)
    (connect_pads yes (clearance 0))
    (min_thickness 0.1) (filled_areas_thickness no)
    (keepout (tracks allowed) (vias allowed) (pads allowed) (copperpour not_allowed) (footprints allowed))
    (fill (thermal_gap 0.254) (thermal_bridge_width 0.254))
    (polygon
      (pts
        (xy 77.922 100.474)
        (xy 77.923 99.88)
        (xy 78.77 99.88)
        (xy 78.77 100.475)
      )
    )
  )
  (zone (net 0) (net_name "") (layers "In1.Cu" "In5.Cu" "In6.Cu") (hatch edge 0.508)
    (connect_pads yes (clearance 0))
    (min_thickness 0.1) (filled_areas_thickness no)
    (keepout (tracks allowed) (vias allowed) (pads allowed) (copperpour not_allowed) (footprints allowed))
    (fill (thermal_gap 0.254) (thermal_bridge_width 0.254))
    (polygon
      (pts
        (xy 77.920648 100.46264)
        (xy 77.922695 100.420983)
        (xy 77.928815 100.379727)
        (xy 77.938949 100.33927)
        (xy 77.953 100.300001)
        (xy 77.970832 100.262297)
        (xy 77.992273 100.226523)
        (xy 78.017119 100.193022)
        (xy 78.045128 100.16212)
        (xy 78.076031 100.13411)
        (xy 78.109531 100.109266)
        (xy 78.145305 100.087824)
        (xy 78.183008 100.069992)
        (xy 78.222278 100.055941)
        (xy 78.262735 100.045807)
        (xy 78.303991 100.039687)
        (xy 78.345648 100.03764)
        (xy 78.387306 100.039687)
        (xy 78.42856 100.045807)
        (xy 78.469018 100.055941)
        (xy 78.508288 100.069991)
        (xy 78.545991 100.087825)
        (xy 78.581765 100.109266)
        (xy 78.615265 100.13411)
        (xy 78.646168 100.16212)
        (xy 78.674177 100.193023)
        (xy 78.699022 100.226523)
        (xy 78.720464 100.262298)
        (xy 78.738296 100.3)
        (xy 78.752347 100.33927)
        (xy 78.762481 100.379728)
        (xy 78.768602 100.420983)
        (xy 78.770648 100.46264)
        (xy 78.768601 100.504296)
        (xy 78.762481 100.545553)
        (xy 78.752347 100.58601)
        (xy 78.738296 100.62528)
        (xy 78.720464 100.662982)
        (xy 78.699022 100.698757)
        (xy 78.674177 100.732257)
        (xy 78.646168 100.76316)
        (xy 78.615266 100.791169)
        (xy 78.581765 100.816015)
        (xy 78.545991 100.837455)
        (xy 78.508287 100.855288)
        (xy 78.469018 100.869339)
        (xy 78.428561 100.879472)
        (xy 78.387305 100.885592)
        (xy 78.345648 100.88764)
        (xy 78.303991 100.885593)
        (xy 78.262735 100.879473)
        (xy 78.222278 100.869339)
        (xy 78.183008 100.855288)
        (xy 78.145305 100.837456)
        (xy 78.109531 100.816014)
        (xy 78.076032 100.791169)
        (xy 78.045128 100.76316)
        (xy 78.017119 100.732256)
        (xy 77.992274 100.698756)
        (xy 77.970832 100.662983)
        (xy 77.953 100.62528)
        (xy 77.938949 100.58601)
        (xy 77.928815 100.545553)
        (xy 77.922695 100.504297)
      )
    )
  )
  (zone (net 0) (net_name "") (layers "In1.Cu" "In5.Cu" "In6.Cu") (hatch edge 0.508)
    (connect_pads yes (clearance 0))
    (min_thickness 0.1) (filled_areas_thickness no)
    (keepout (tracks allowed) (vias allowed) (pads allowed) (copperpour not_allowed) (footprints allowed))
    (fill (thermal_gap 0.254) (thermal_bridge_width 0.254))
    (polygon
      (pts
        (xy 78.558 111.018)
        (xy 78.559 110.424)
        (xy 79.406 110.424)
        (xy 79.406 111.019)
      )
    )
  )
  (zone (net 0) (net_name "") (layers "In1.Cu" "In5.Cu" "In6.Cu") (hatch edge 0.508)
    (connect_pads yes (clearance 0))
    (min_thickness 0.1) (filled_areas_thickness no)
    (keepout (tracks allowed) (vias allowed) (pads allowed) (copperpour not_allowed) (footprints allowed))
    (fill (thermal_gap 0.254) (thermal_bridge_width 0.254))
    (polygon
      (pts
        (xy 78.696 109.01)
        (xy 78.698047 108.968342)
        (xy 78.704166 108.927087)
        (xy 78.714301 108.88663)
        (xy 78.728352 108.84736)
        (xy 78.746183 108.809657)
        (xy 78.767626 108.773883)
        (xy 78.792471 108.740383)
        (xy 78.82048 108.70948)
        (xy 78.851383 108.681471)
        (xy 78.884883 108.656626)
        (xy 78.920657 108.635183)
        (xy 78.95836 108.617352)
        (xy 78.99763 108.603301)
        (xy 79.038087 108.593166)
        (xy 79.079343 108.587046)
        (xy 79.121 108.585)
        (xy 79.162657 108.587047)
        (xy 79.203913 108.593167)
        (xy 79.24437 108.603301)
        (xy 79.28364 108.617352)
        (xy 79.321343 108.635184)
        (xy 79.357117 108.656626)
        (xy 79.390617 108.681471)
        (xy 79.42152 108.70948)
        (xy 79.449529 108.740383)
        (xy 79.474374 108.773882)
        (xy 79.495816 108.809657)
        (xy 79.513647 108.84736)
        (xy 79.527699 108.88663)
        (xy 79.537833 108.927087)
        (xy 79.543953 108.968343)
        (xy 79.546 109.01)
        (xy 79.543953 109.051657)
        (xy 79.537833 109.092913)
        (xy 79.527699 109.133371)
        (xy 79.513648 109.17264)
        (xy 79.495816 109.210343)
        (xy 79.474374 109.246117)
        (xy 79.449529 109.279616)
        (xy 79.421521 109.31052)
        (xy 79.390616 109.338529)
        (xy 79.357117 109.363374)
        (xy 79.321343 109.384816)
        (xy 79.28364 109.402648)
        (xy 79.24437 109.416699)
        (xy 79.203913 109.426833)
        (xy 79.162657 109.432953)
        (xy 79.121 109.435)
        (xy 79.079343 109.432953)
        (xy 79.038087 109.426833)
        (xy 78.99763 109.416699)
        (xy 78.95836 109.402647)
        (xy 78.920657 109.384816)
        (xy 78.884882 109.363374)
        (xy 78.851382 109.338529)
        (xy 78.82048 109.31052)
        (xy 78.792471 109.279617)
        (xy 78.767626 109.246117)
        (xy 78.746184 109.210343)
        (xy 78.728352 109.17264)
        (xy 78.714301 109.13337)
        (xy 78.704167 109.092913)
        (xy 78.698047 109.051657)
      )
    )
  )
  (zone (net 0) (net_name "") (layers "In1.Cu" "In5.Cu" "In6.Cu") (hatch edge 0.508)
    (connect_pads yes (clearance 0))
    (min_thickness 0.1) (filled_areas_thickness no)
    (keepout (tracks allowed) (vias allowed) (pads allowed) (copperpour not_allowed) (footprints allowed))
    (fill (thermal_gap 0.254) (thermal_bridge_width 0.254))
    (polygon
      (pts
        (xy 78.556 110.42)
        (xy 78.558047 110.378342)
        (xy 78.564166 110.337087)
        (xy 78.574301 110.29663)
        (xy 78.588352 110.25736)
        (xy 78.606183 110.219657)
        (xy 78.627626 110.183883)
        (xy 78.652471 110.150383)
        (xy 78.68048 110.11948)
        (xy 78.711383 110.091471)
        (xy 78.744883 110.066626)
        (xy 78.780657 110.045183)
        (xy 78.81836 110.027352)
        (xy 78.85763 110.013301)
        (xy 78.898087 110.003166)
        (xy 78.939343 109.997046)
        (xy 78.981 109.995)
        (xy 79.022657 109.997047)
        (xy 79.063913 110.003167)
        (xy 79.10437 110.013301)
        (xy 79.14364 110.027352)
        (xy 79.181343 110.045184)
        (xy 79.217117 110.066626)
        (xy 79.250617 110.091471)
        (xy 79.28152 110.11948)
        (xy 79.309529 110.150383)
        (xy 79.334374 110.183882)
        (xy 79.355816 110.219657)
        (xy 79.373647 110.25736)
        (xy 79.387699 110.29663)
        (xy 79.397833 110.337087)
        (xy 79.403953 110.378343)
        (xy 79.406 110.42)
        (xy 79.403953 110.461657)
        (xy 79.397833 110.502913)
        (xy 79.387699 110.543371)
        (xy 79.373648 110.58264)
        (xy 79.355816 110.620343)
        (xy 79.334374 110.656117)
        (xy 79.309529 110.689616)
        (xy 79.281521 110.72052)
        (xy 79.250616 110.748529)
        (xy 79.217117 110.773374)
        (xy 79.181343 110.794816)
        (xy 79.14364 110.812648)
        (xy 79.10437 110.826699)
        (xy 79.063913 110.836833)
        (xy 79.022657 110.842953)
        (xy 78.981 110.845)
        (xy 78.939343 110.842953)
        (xy 78.898087 110.836833)
        (xy 78.85763 110.826699)
        (xy 78.81836 110.812647)
        (xy 78.780657 110.794816)
        (xy 78.744882 110.773374)
        (xy 78.711382 110.748529)
        (xy 78.68048 110.72052)
        (xy 78.652471 110.689617)
        (xy 78.627626 110.656117)
        (xy 78.606184 110.620343)
        (xy 78.588352 110.58264)
        (xy 78.574301 110.54337)
        (xy 78.564167 110.502913)
        (xy 78.558047 110.461657)
      )
    )
  )
  (zone (net 0) (net_name "") (layers "In1.Cu" "In5.Cu" "In6.Cu") (hatch edge 0.508)
    (connect_pads yes (clearance 0))
    (min_thickness 0.1) (filled_areas_thickness no)
    (keepout (tracks allowed) (vias allowed) (pads allowed) (copperpour not_allowed) (footprints allowed))
    (fill (thermal_gap 0.254) (thermal_bridge_width 0.254))
    (polygon
      (pts
        (xy 78.846 107.58)
        (xy 78.848047 107.538342)
        (xy 78.854166 107.497087)
        (xy 78.864301 107.45663)
        (xy 78.878352 107.41736)
        (xy 78.896183 107.379657)
        (xy 78.917626 107.343883)
        (xy 78.942471 107.310383)
        (xy 78.97048 107.27948)
        (xy 79.001383 107.251471)
        (xy 79.034883 107.226626)
        (xy 79.070657 107.205183)
        (xy 79.10836 107.187352)
        (xy 79.14763 107.173301)
        (xy 79.188087 107.163166)
        (xy 79.229343 107.157046)
        (xy 79.271 107.155)
        (xy 79.312657 107.157047)
        (xy 79.353913 107.163167)
        (xy 79.39437 107.173301)
        (xy 79.43364 107.187352)
        (xy 79.471343 107.205184)
        (xy 79.507117 107.226626)
        (xy 79.540617 107.251471)
        (xy 79.57152 107.27948)
        (xy 79.599529 107.310383)
        (xy 79.624374 107.343882)
        (xy 79.645816 107.379657)
        (xy 79.663647 107.41736)
        (xy 79.677699 107.45663)
        (xy 79.687833 107.497087)
        (xy 79.693953 107.538343)
        (xy 79.696 107.58)
        (xy 79.693953 107.621657)
        (xy 79.687833 107.662913)
        (xy 79.677699 107.703371)
        (xy 79.663648 107.74264)
        (xy 79.645816 107.780343)
        (xy 79.624374 107.816117)
        (xy 79.599529 107.849616)
        (xy 79.571521 107.88052)
        (xy 79.540616 107.908529)
        (xy 79.507117 107.933374)
        (xy 79.471343 107.954816)
        (xy 79.43364 107.972648)
        (xy 79.39437 107.986699)
        (xy 79.353913 107.996833)
        (xy 79.312657 108.002953)
        (xy 79.271 108.005)
        (xy 79.229343 108.002953)
        (xy 79.188087 107.996833)
        (xy 79.14763 107.986699)
        (xy 79.10836 107.972647)
        (xy 79.070657 107.954816)
        (xy 79.034882 107.933374)
        (xy 79.001382 107.908529)
        (xy 78.97048 107.88052)
        (xy 78.942471 107.849617)
        (xy 78.917626 107.816117)
        (xy 78.896184 107.780343)
        (xy 78.878352 107.74264)
        (xy 78.864301 107.70337)
        (xy 78.854167 107.662913)
        (xy 78.848047 107.621657)
      )
    )
  )
  (zone (net 0) (net_name "") (layers "In1.Cu" "In5.Cu" "In6.Cu") (hatch edge 0.508)
    (connect_pads yes (clearance 0))
    (min_thickness 0.1) (filled_areas_thickness no)
    (keepout (tracks allowed) (vias allowed) (pads allowed) (copperpour not_allowed) (footprints allowed))
    (fill (thermal_gap 0.254) (thermal_bridge_width 0.254))
    (polygon
      (pts
        (xy 78.116 105.5)
        (xy 78.118047 105.458342)
        (xy 78.124166 105.417087)
        (xy 78.134301 105.37663)
        (xy 78.148352 105.33736)
        (xy 78.166183 105.299657)
        (xy 78.187626 105.263883)
        (xy 78.212471 105.230383)
        (xy 78.24048 105.19948)
        (xy 78.271383 105.171471)
        (xy 78.304883 105.146626)
        (xy 78.340657 105.125183)
        (xy 78.37836 105.107352)
        (xy 78.41763 105.093301)
        (xy 78.458087 105.083166)
        (xy 78.499343 105.077046)
        (xy 78.541 105.075)
        (xy 78.582657 105.077047)
        (xy 78.623913 105.083167)
        (xy 78.66437 105.093301)
        (xy 78.70364 105.107352)
        (xy 78.741343 105.125184)
        (xy 78.777117 105.146626)
        (xy 78.810617 105.171471)
        (xy 78.84152 105.19948)
        (xy 78.869529 105.230383)
        (xy 78.894374 105.263882)
        (xy 78.915816 105.299657)
        (xy 78.933647 105.33736)
        (xy 78.947699 105.37663)
        (xy 78.957833 105.417087)
        (xy 78.963953 105.458343)
        (xy 78.966 105.5)
        (xy 78.963953 105.541657)
        (xy 78.957833 105.582913)
        (xy 78.947699 105.623371)
        (xy 78.933648 105.66264)
        (xy 78.915816 105.700343)
        (xy 78.894374 105.736117)
        (xy 78.869529 105.769616)
        (xy 78.841521 105.80052)
        (xy 78.810616 105.828529)
        (xy 78.777117 105.853374)
        (xy 78.741343 105.874816)
        (xy 78.70364 105.892648)
        (xy 78.66437 105.906699)
        (xy 78.623913 105.916833)
        (xy 78.582657 105.922953)
        (xy 78.541 105.925)
        (xy 78.499343 105.922953)
        (xy 78.458087 105.916833)
        (xy 78.41763 105.906699)
        (xy 78.37836 105.892647)
        (xy 78.340657 105.874816)
        (xy 78.304882 105.853374)
        (xy 78.271382 105.828529)
        (xy 78.24048 105.80052)
        (xy 78.212471 105.769617)
        (xy 78.187626 105.736117)
        (xy 78.166184 105.700343)
        (xy 78.148352 105.66264)
        (xy 78.134301 105.62337)
        (xy 78.124167 105.582913)
        (xy 78.118047 105.541657)
      )
    )
  )
  (zone (net 0) (net_name "") (layers "In1.Cu" "In5.Cu" "In6.Cu") (hatch edge 0.508)
    (connect_pads yes (clearance 0))
    (min_thickness 0.1) (filled_areas_thickness no)
    (keepout (tracks allowed) (vias allowed) (pads allowed) (copperpour not_allowed) (footprints allowed))
    (fill (thermal_gap 0.254) (thermal_bridge_width 0.254))
    (polygon
      (pts
        (xy 78.556648 111.00664)
        (xy 78.558695 110.964983)
        (xy 78.564815 110.923727)
        (xy 78.574949 110.88327)
        (xy 78.589 110.844001)
        (xy 78.606832 110.806297)
        (xy 78.628273 110.770523)
        (xy 78.653119 110.737022)
        (xy 78.681128 110.70612)
        (xy 78.712031 110.67811)
        (xy 78.745531 110.653266)
        (xy 78.781305 110.631824)
        (xy 78.819008 110.613992)
        (xy 78.858278 110.599941)
        (xy 78.898735 110.589807)
        (xy 78.939991 110.583687)
        (xy 78.981648 110.58164)
        (xy 79.023306 110.583687)
        (xy 79.06456 110.589807)
        (xy 79.105018 110.599941)
        (xy 79.144288 110.613991)
        (xy 79.181991 110.631825)
        (xy 79.217765 110.653266)
        (xy 79.251265 110.67811)
        (xy 79.282168 110.70612)
        (xy 79.310177 110.737023)
        (xy 79.335022 110.770523)
        (xy 79.356464 110.806298)
        (xy 79.374296 110.844)
        (xy 79.388347 110.88327)
        (xy 79.398481 110.923728)
        (xy 79.404602 110.964983)
        (xy 79.406648 111.00664)
        (xy 79.404601 111.048296)
        (xy 79.398481 111.089553)
        (xy 79.388347 111.13001)
        (xy 79.374296 111.16928)
        (xy 79.356464 111.206982)
        (xy 79.335022 111.242757)
        (xy 79.310177 111.276257)
        (xy 79.282168 111.30716)
        (xy 79.251266 111.335169)
        (xy 79.217765 111.360015)
        (xy 79.181991 111.381455)
        (xy 79.144287 111.399288)
        (xy 79.105018 111.413339)
        (xy 79.064561 111.423472)
        (xy 79.023305 111.429592)
        (xy 78.981648 111.43164)
        (xy 78.939991 111.429593)
        (xy 78.898735 111.423473)
        (xy 78.858278 111.413339)
        (xy 78.819008 111.399288)
        (xy 78.781305 111.381456)
        (xy 78.745531 111.360014)
        (xy 78.712032 111.335169)
        (xy 78.681128 111.30716)
        (xy 78.653119 111.276256)
        (xy 78.628274 111.242756)
        (xy 78.606832 111.206983)
        (xy 78.589 111.16928)
        (xy 78.574949 111.13001)
        (xy 78.564815 111.089553)
        (xy 78.558695 111.048297)
      )
    )
  )
  (zone (net 0) (net_name "") (layers "In1.Cu" "In5.Cu" "In6.Cu") (hatch edge 0.508)
    (connect_pads yes (clearance 0))
    (min_thickness 0.1) (filled_areas_thickness no)
    (keepout (tracks allowed) (vias allowed) (pads allowed) (copperpour not_allowed) (footprints allowed))
    (fill (thermal_gap 0.254) (thermal_bridge_width 0.254))
    (polygon
      (pts
        (xy 78.008 113.808)
        (xy 78.009 113.214)
        (xy 78.856 113.214)
        (xy 78.856 113.809)
      )
    )
  )
  (zone (net 0) (net_name "") (layers "In1.Cu" "In5.Cu" "In6.Cu") (hatch edge 0.508)
    (connect_pads yes (clearance 0))
    (min_thickness 0.1) (filled_areas_thickness no)
    (keepout (tracks allowed) (vias allowed) (pads allowed) (copperpour not_allowed) (footprints allowed))
    (fill (thermal_gap 0.254) (thermal_bridge_width 0.254))
    (polygon
      (pts
        (xy 77.926648 104.68664)
        (xy 77.928695 104.644983)
        (xy 77.934815 104.603727)
        (xy 77.944949 104.56327)
        (xy 77.959 104.524001)
        (xy 77.976832 104.486297)
        (xy 77.998273 104.450523)
        (xy 78.023119 104.417022)
        (xy 78.051128 104.38612)
        (xy 78.082031 104.35811)
        (xy 78.115531 104.333266)
        (xy 78.151305 104.311824)
        (xy 78.189008 104.293992)
        (xy 78.228278 104.279941)
        (xy 78.268735 104.269807)
        (xy 78.309991 104.263687)
        (xy 78.351648 104.26164)
        (xy 78.393306 104.263687)
        (xy 78.43456 104.269807)
        (xy 78.475018 104.279941)
        (xy 78.514288 104.293991)
        (xy 78.551991 104.311825)
        (xy 78.587765 104.333266)
        (xy 78.621265 104.35811)
        (xy 78.652168 104.38612)
        (xy 78.680177 104.417023)
        (xy 78.705022 104.450523)
        (xy 78.726464 104.486298)
        (xy 78.744296 104.524)
        (xy 78.758347 104.56327)
        (xy 78.768481 104.603728)
        (xy 78.774602 104.644983)
        (xy 78.776648 104.68664)
        (xy 78.774601 104.728296)
        (xy 78.768481 104.769553)
        (xy 78.758347 104.81001)
        (xy 78.744296 104.84928)
        (xy 78.726464 104.886982)
        (xy 78.705022 104.922757)
        (xy 78.680177 104.956257)
        (xy 78.652168 104.98716)
        (xy 78.621266 105.015169)
        (xy 78.587765 105.040015)
        (xy 78.551991 105.061455)
        (xy 78.514287 105.079288)
        (xy 78.475018 105.093339)
        (xy 78.434561 105.103472)
        (xy 78.393305 105.109592)
        (xy 78.351648 105.11164)
        (xy 78.309991 105.109593)
        (xy 78.268735 105.103473)
        (xy 78.228278 105.093339)
        (xy 78.189008 105.079288)
        (xy 78.151305 105.061456)
        (xy 78.115531 105.040014)
        (xy 78.082032 105.015169)
        (xy 78.051128 104.98716)
        (xy 78.023119 104.956256)
        (xy 77.998274 104.922756)
        (xy 77.976832 104.886983)
        (xy 77.959 104.84928)
        (xy 77.944949 104.81001)
        (xy 77.934815 104.769553)
        (xy 77.928695 104.728297)
      )
    )
  )
  (zone (net 0) (net_name "") (layers "In1.Cu" "In5.Cu" "In6.Cu") (hatch edge 0.508)
    (connect_pads yes (clearance 0))
    (min_thickness 0.1) (filled_areas_thickness no)
    (keepout (tracks allowed) (vias allowed) (pads allowed) (copperpour not_allowed) (footprints allowed))
    (fill (thermal_gap 0.254) (thermal_bridge_width 0.254))
    (polygon
      (pts
        (xy 78.848 108.178)
        (xy 78.849 107.584)
        (xy 79.696 107.584)
        (xy 79.696 108.179)
      )
    )
  )
  (zone (net 0) (net_name "") (layers "In1.Cu" "In5.Cu" "In6.Cu") (hatch edge 0.508)
    (connect_pads yes (clearance 0))
    (min_thickness 0.1) (filled_areas_thickness no)
    (keepout (tracks allowed) (vias allowed) (pads allowed) (copperpour not_allowed) (footprints allowed))
    (fill (thermal_gap 0.254) (thermal_bridge_width 0.254))
    (polygon
      (pts
        (xy 78.166 111.81)
        (xy 78.168047 111.768342)
        (xy 78.174166 111.727087)
        (xy 78.184301 111.68663)
        (xy 78.198352 111.64736)
        (xy 78.216183 111.609657)
        (xy 78.237626 111.573883)
        (xy 78.262471 111.540383)
        (xy 78.29048 111.50948)
        (xy 78.321383 111.481471)
        (xy 78.354883 111.456626)
        (xy 78.390657 111.435183)
        (xy 78.42836 111.417352)
        (xy 78.46763 111.403301)
        (xy 78.508087 111.393166)
        (xy 78.549343 111.387046)
        (xy 78.591 111.385)
        (xy 78.632657 111.387047)
        (xy 78.673913 111.393167)
        (xy 78.71437 111.403301)
        (xy 78.75364 111.417352)
        (xy 78.791343 111.435184)
        (xy 78.827117 111.456626)
        (xy 78.860617 111.481471)
        (xy 78.89152 111.50948)
        (xy 78.919529 111.540383)
        (xy 78.944374 111.573882)
        (xy 78.965816 111.609657)
        (xy 78.983647 111.64736)
        (xy 78.997699 111.68663)
        (xy 79.007833 111.727087)
        (xy 79.013953 111.768343)
        (xy 79.016 111.81)
        (xy 79.013953 111.851657)
        (xy 79.007833 111.892913)
        (xy 78.997699 111.933371)
        (xy 78.983648 111.97264)
        (xy 78.965816 112.010343)
        (xy 78.944374 112.046117)
        (xy 78.919529 112.079616)
        (xy 78.891521 112.11052)
        (xy 78.860616 112.138529)
        (xy 78.827117 112.163374)
        (xy 78.791343 112.184816)
        (xy 78.75364 112.202648)
        (xy 78.71437 112.216699)
        (xy 78.673913 112.226833)
        (xy 78.632657 112.232953)
        (xy 78.591 112.235)
        (xy 78.549343 112.232953)
        (xy 78.508087 112.226833)
        (xy 78.46763 112.216699)
        (xy 78.42836 112.202647)
        (xy 78.390657 112.184816)
        (xy 78.354882 112.163374)
        (xy 78.321382 112.138529)
        (xy 78.29048 112.11052)
        (xy 78.262471 112.079617)
        (xy 78.237626 112.046117)
        (xy 78.216184 112.010343)
        (xy 78.198352 111.97264)
        (xy 78.184301 111.93337)
        (xy 78.174167 111.892913)
        (xy 78.168047 111.851657)
      )
    )
  )
  (zone (net 0) (net_name "") (layers "In1.Cu" "In5.Cu" "In6.Cu") (hatch edge 0.508)
    (connect_pads yes (clearance 0))
    (min_thickness 0.1) (filled_areas_thickness no)
    (keepout (tracks allowed) (vias allowed) (pads allowed) (copperpour not_allowed) (footprints allowed))
    (fill (thermal_gap 0.254) (thermal_bridge_width 0.254))
    (polygon
      (pts
        (xy 78.006 113.21)
        (xy 78.008047 113.168342)
        (xy 78.014166 113.127087)
        (xy 78.024301 113.08663)
        (xy 78.038352 113.04736)
        (xy 78.056183 113.009657)
        (xy 78.077626 112.973883)
        (xy 78.102471 112.940383)
        (xy 78.13048 112.90948)
        (xy 78.161383 112.881471)
        (xy 78.194883 112.856626)
        (xy 78.230657 112.835183)
        (xy 78.26836 112.817352)
        (xy 78.30763 112.803301)
        (xy 78.348087 112.793166)
        (xy 78.389343 112.787046)
        (xy 78.431 112.785)
        (xy 78.472657 112.787047)
        (xy 78.513913 112.793167)
        (xy 78.55437 112.803301)
        (xy 78.59364 112.817352)
        (xy 78.631343 112.835184)
        (xy 78.667117 112.856626)
        (xy 78.700617 112.881471)
        (xy 78.73152 112.90948)
        (xy 78.759529 112.940383)
        (xy 78.784374 112.973882)
        (xy 78.805816 113.009657)
        (xy 78.823647 113.04736)
        (xy 78.837699 113.08663)
        (xy 78.847833 113.127087)
        (xy 78.853953 113.168343)
        (xy 78.856 113.21)
        (xy 78.853953 113.251657)
        (xy 78.847833 113.292913)
        (xy 78.837699 113.333371)
        (xy 78.823648 113.37264)
        (xy 78.805816 113.410343)
        (xy 78.784374 113.446117)
        (xy 78.759529 113.479616)
        (xy 78.731521 113.51052)
        (xy 78.700616 113.538529)
        (xy 78.667117 113.563374)
        (xy 78.631343 113.584816)
        (xy 78.59364 113.602648)
        (xy 78.55437 113.616699)
        (xy 78.513913 113.626833)
        (xy 78.472657 113.632953)
        (xy 78.431 113.635)
        (xy 78.389343 113.632953)
        (xy 78.348087 113.626833)
        (xy 78.30763 113.616699)
        (xy 78.26836 113.602647)
        (xy 78.230657 113.584816)
        (xy 78.194882 113.563374)
        (xy 78.161382 113.538529)
        (xy 78.13048 113.51052)
        (xy 78.102471 113.479617)
        (xy 78.077626 113.446117)
        (xy 78.056184 113.410343)
        (xy 78.038352 113.37264)
        (xy 78.024301 113.33337)
        (xy 78.014167 113.292913)
        (xy 78.008047 113.251657)
      )
    )
  )
  (zone (net 0) (net_name "") (layers "In1.Cu" "In5.Cu" "In6.Cu") (hatch edge 0.508)
    (connect_pads yes (clearance 0))
    (min_thickness 0.1) (filled_areas_thickness no)
    (keepout (tracks allowed) (vias allowed) (pads allowed) (copperpour not_allowed) (footprints allowed))
    (fill (thermal_gap 0.254) (thermal_bridge_width 0.254))
    (polygon
      (pts
        (xy 77.926 104.1)
        (xy 77.928047 104.058342)
        (xy 77.934166 104.017087)
        (xy 77.944301 103.97663)
        (xy 77.958352 103.93736)
        (xy 77.976183 103.899657)
        (xy 77.997626 103.863883)
        (xy 78.022471 103.830383)
        (xy 78.05048 103.79948)
        (xy 78.081383 103.771471)
        (xy 78.114883 103.746626)
        (xy 78.150657 103.725183)
        (xy 78.18836 103.707352)
        (xy 78.22763 103.693301)
        (xy 78.268087 103.683166)
        (xy 78.309343 103.677046)
        (xy 78.351 103.675)
        (xy 78.392657 103.677047)
        (xy 78.433913 103.683167)
        (xy 78.47437 103.693301)
        (xy 78.51364 103.707352)
        (xy 78.551343 103.725184)
        (xy 78.587117 103.746626)
        (xy 78.620617 103.771471)
        (xy 78.65152 103.79948)
        (xy 78.679529 103.830383)
        (xy 78.704374 103.863882)
        (xy 78.725816 103.899657)
        (xy 78.743647 103.93736)
        (xy 78.757699 103.97663)
        (xy 78.767833 104.017087)
        (xy 78.773953 104.058343)
        (xy 78.776 104.1)
        (xy 78.773953 104.141657)
        (xy 78.767833 104.182913)
        (xy 78.757699 104.223371)
        (xy 78.743648 104.26264)
        (xy 78.725816 104.300343)
        (xy 78.704374 104.336117)
        (xy 78.679529 104.369616)
        (xy 78.651521 104.40052)
        (xy 78.620616 104.428529)
        (xy 78.587117 104.453374)
        (xy 78.551343 104.474816)
        (xy 78.51364 104.492648)
        (xy 78.47437 104.506699)
        (xy 78.433913 104.516833)
        (xy 78.392657 104.522953)
        (xy 78.351 104.525)
        (xy 78.309343 104.522953)
        (xy 78.268087 104.516833)
        (xy 78.22763 104.506699)
        (xy 78.18836 104.492647)
        (xy 78.150657 104.474816)
        (xy 78.114882 104.453374)
        (xy 78.081382 104.428529)
        (xy 78.05048 104.40052)
        (xy 78.022471 104.369617)
        (xy 77.997626 104.336117)
        (xy 77.976184 104.300343)
        (xy 77.958352 104.26264)
        (xy 77.944301 104.22337)
        (xy 77.934167 104.182913)
        (xy 77.928047 104.141657)
      )
    )
  )
  (zone (net 0) (net_name "") (layers "In1.Cu" "In5.Cu" "In6.Cu") (hatch edge 0.508)
    (connect_pads yes (clearance 0))
    (min_thickness 0.1) (filled_areas_thickness no)
    (keepout (tracks allowed) (vias allowed) (pads allowed) (copperpour not_allowed) (footprints allowed))
    (fill (thermal_gap 0.254) (thermal_bridge_width 0.254))
    (polygon
      (pts
        (xy 78.166648 112.39664)
        (xy 78.168695 112.354983)
        (xy 78.174815 112.313727)
        (xy 78.184949 112.27327)
        (xy 78.199 112.234001)
        (xy 78.216832 112.196297)
        (xy 78.238273 112.160523)
        (xy 78.263119 112.127022)
        (xy 78.291128 112.09612)
        (xy 78.322031 112.06811)
        (xy 78.355531 112.043266)
        (xy 78.391305 112.021824)
        (xy 78.429008 112.003992)
        (xy 78.468278 111.989941)
        (xy 78.508735 111.979807)
        (xy 78.549991 111.973687)
        (xy 78.591648 111.97164)
        (xy 78.633306 111.973687)
        (xy 78.67456 111.979807)
        (xy 78.715018 111.989941)
        (xy 78.754288 112.003991)
        (xy 78.791991 112.021825)
        (xy 78.827765 112.043266)
        (xy 78.861265 112.06811)
        (xy 78.892168 112.09612)
        (xy 78.920177 112.127023)
        (xy 78.945022 112.160523)
        (xy 78.966464 112.196298)
        (xy 78.984296 112.234)
        (xy 78.998347 112.27327)
        (xy 79.008481 112.313728)
        (xy 79.014602 112.354983)
        (xy 79.016648 112.39664)
        (xy 79.014601 112.438296)
        (xy 79.008481 112.479553)
        (xy 78.998347 112.52001)
        (xy 78.984296 112.55928)
        (xy 78.966464 112.596982)
        (xy 78.945022 112.632757)
        (xy 78.920177 112.666257)
        (xy 78.892168 112.69716)
        (xy 78.861266 112.725169)
        (xy 78.827765 112.750015)
        (xy 78.791991 112.771455)
        (xy 78.754287 112.789288)
        (xy 78.715018 112.803339)
        (xy 78.674561 112.813472)
        (xy 78.633305 112.819592)
        (xy 78.591648 112.82164)
        (xy 78.549991 112.819593)
        (xy 78.508735 112.813473)
        (xy 78.468278 112.803339)
        (xy 78.429008 112.789288)
        (xy 78.391305 112.771456)
        (xy 78.355531 112.750014)
        (xy 78.322032 112.725169)
        (xy 78.291128 112.69716)
        (xy 78.263119 112.666256)
        (xy 78.238274 112.632756)
        (xy 78.216832 112.596983)
        (xy 78.199 112.55928)
        (xy 78.184949 112.52001)
        (xy 78.174815 112.479553)
        (xy 78.168695 112.438297)
      )
    )
  )
  (zone (net 0) (net_name "") (layers "In1.Cu" "In5.Cu" "In6.Cu") (hatch edge 0.508)
    (connect_pads yes (clearance 0))
    (min_thickness 0.1) (filled_areas_thickness no)
    (keepout (tracks allowed) (vias allowed) (pads allowed) (copperpour not_allowed) (footprints allowed))
    (fill (thermal_gap 0.254) (thermal_bridge_width 0.254))
    (polygon
      (pts
        (xy 78.696648 109.59664)
        (xy 78.698695 109.554983)
        (xy 78.704815 109.513727)
        (xy 78.714949 109.47327)
        (xy 78.729 109.434001)
        (xy 78.746832 109.396297)
        (xy 78.768273 109.360523)
        (xy 78.793119 109.327022)
        (xy 78.821128 109.29612)
        (xy 78.852031 109.26811)
        (xy 78.885531 109.243266)
        (xy 78.921305 109.221824)
        (xy 78.959008 109.203992)
        (xy 78.998278 109.189941)
        (xy 79.038735 109.179807)
        (xy 79.079991 109.173687)
        (xy 79.121648 109.17164)
        (xy 79.163306 109.173687)
        (xy 79.20456 109.179807)
        (xy 79.245018 109.189941)
        (xy 79.284288 109.203991)
        (xy 79.321991 109.221825)
        (xy 79.357765 109.243266)
        (xy 79.391265 109.26811)
        (xy 79.422168 109.29612)
        (xy 79.450177 109.327023)
        (xy 79.475022 109.360523)
        (xy 79.496464 109.396298)
        (xy 79.514296 109.434)
        (xy 79.528347 109.47327)
        (xy 79.538481 109.513728)
        (xy 79.544602 109.554983)
        (xy 79.546648 109.59664)
        (xy 79.544601 109.638296)
        (xy 79.538481 109.679553)
        (xy 79.528347 109.72001)
        (xy 79.514296 109.75928)
        (xy 79.496464 109.796982)
        (xy 79.475022 109.832757)
        (xy 79.450177 109.866257)
        (xy 79.422168 109.89716)
        (xy 79.391266 109.925169)
        (xy 79.357765 109.950015)
        (xy 79.321991 109.971455)
        (xy 79.284287 109.989288)
        (xy 79.245018 110.003339)
        (xy 79.204561 110.013472)
        (xy 79.163305 110.019592)
        (xy 79.121648 110.02164)
        (xy 79.079991 110.019593)
        (xy 79.038735 110.013473)
        (xy 78.998278 110.003339)
        (xy 78.959008 109.989288)
        (xy 78.921305 109.971456)
        (xy 78.885531 109.950014)
        (xy 78.852032 109.925169)
        (xy 78.821128 109.89716)
        (xy 78.793119 109.866256)
        (xy 78.768274 109.832756)
        (xy 78.746832 109.796983)
        (xy 78.729 109.75928)
        (xy 78.714949 109.72001)
        (xy 78.704815 109.679553)
        (xy 78.698695 109.638297)
      )
    )
  )
  (zone (net 0) (net_name "") (layers "In1.Cu" "In5.Cu" "In6.Cu") (hatch edge 0.508)
    (connect_pads yes (clearance 0))
    (min_thickness 0.1) (filled_areas_thickness no)
    (keepout (tracks allowed) (vias allowed) (pads allowed) (copperpour not_allowed) (footprints allowed))
    (fill (thermal_gap 0.254) (thermal_bridge_width 0.254))
    (polygon
      (pts
        (xy 78.006648 113.79664)
        (xy 78.008695 113.754983)
        (xy 78.014815 113.713727)
        (xy 78.024949 113.67327)
        (xy 78.039 113.634001)
        (xy 78.056832 113.596297)
        (xy 78.078273 113.560523)
        (xy 78.103119 113.527022)
        (xy 78.131128 113.49612)
        (xy 78.162031 113.46811)
        (xy 78.195531 113.443266)
        (xy 78.231305 113.421824)
        (xy 78.269008 113.403992)
        (xy 78.308278 113.389941)
        (xy 78.348735 113.379807)
        (xy 78.389991 113.373687)
        (xy 78.431648 113.37164)
        (xy 78.473306 113.373687)
        (xy 78.51456 113.379807)
        (xy 78.555018 113.389941)
        (xy 78.594288 113.403991)
        (xy 78.631991 113.421825)
        (xy 78.667765 113.443266)
        (xy 78.701265 113.46811)
        (xy 78.732168 113.49612)
        (xy 78.760177 113.527023)
        (xy 78.785022 113.560523)
        (xy 78.806464 113.596298)
        (xy 78.824296 113.634)
        (xy 78.838347 113.67327)
        (xy 78.848481 113.713728)
        (xy 78.854602 113.754983)
        (xy 78.856648 113.79664)
        (xy 78.854601 113.838296)
        (xy 78.848481 113.879553)
        (xy 78.838347 113.92001)
        (xy 78.824296 113.95928)
        (xy 78.806464 113.996982)
        (xy 78.785022 114.032757)
        (xy 78.760177 114.066257)
        (xy 78.732168 114.09716)
        (xy 78.701266 114.125169)
        (xy 78.667765 114.150015)
        (xy 78.631991 114.171455)
        (xy 78.594287 114.189288)
        (xy 78.555018 114.203339)
        (xy 78.514561 114.213472)
        (xy 78.473305 114.219592)
        (xy 78.431648 114.22164)
        (xy 78.389991 114.219593)
        (xy 78.348735 114.213473)
        (xy 78.308278 114.203339)
        (xy 78.269008 114.189288)
        (xy 78.231305 114.171456)
        (xy 78.195531 114.150014)
        (xy 78.162032 114.125169)
        (xy 78.131128 114.09716)
        (xy 78.103119 114.066256)
        (xy 78.078274 114.032756)
        (xy 78.056832 113.996983)
        (xy 78.039 113.95928)
        (xy 78.024949 113.92001)
        (xy 78.014815 113.879553)
        (xy 78.008695 113.838297)
      )
    )
  )
  (zone (net 0) (net_name "") (layers "In1.Cu" "In5.Cu" "In6.Cu") (hatch edge 0.508)
    (connect_pads yes (clearance 0))
    (min_thickness 0.1) (filled_areas_thickness no)
    (keepout (tracks allowed) (vias allowed) (pads allowed) (copperpour not_allowed) (footprints allowed))
    (fill (thermal_gap 0.254) (thermal_bridge_width 0.254))
    (polygon
      (pts
        (xy 77.928 104.698)
        (xy 77.929 104.104)
        (xy 78.776 104.104)
        (xy 78.776 104.699)
      )
    )
  )
  (zone (net 0) (net_name "") (layers "In1.Cu" "In5.Cu" "In6.Cu") (hatch edge 0.508)
    (connect_pads yes (clearance 0))
    (min_thickness 0.1) (filled_areas_thickness no)
    (keepout (tracks allowed) (vias allowed) (pads allowed) (copperpour not_allowed) (footprints allowed))
    (fill (thermal_gap 0.254) (thermal_bridge_width 0.254))
    (polygon
      (pts
        (xy 78.116648 106.08664)
        (xy 78.118695 106.044983)
        (xy 78.124815 106.003727)
        (xy 78.134949 105.96327)
        (xy 78.149 105.924001)
        (xy 78.166832 105.886297)
        (xy 78.188273 105.850523)
        (xy 78.213119 105.817022)
        (xy 78.241128 105.78612)
        (xy 78.272031 105.75811)
        (xy 78.305531 105.733266)
        (xy 78.341305 105.711824)
        (xy 78.379008 105.693992)
        (xy 78.418278 105.679941)
        (xy 78.458735 105.669807)
        (xy 78.499991 105.663687)
        (xy 78.541648 105.66164)
        (xy 78.583306 105.663687)
        (xy 78.62456 105.669807)
        (xy 78.665018 105.679941)
        (xy 78.704288 105.693991)
        (xy 78.741991 105.711825)
        (xy 78.777765 105.733266)
        (xy 78.811265 105.75811)
        (xy 78.842168 105.78612)
        (xy 78.870177 105.817023)
        (xy 78.895022 105.850523)
        (xy 78.916464 105.886298)
        (xy 78.934296 105.924)
        (xy 78.948347 105.96327)
        (xy 78.958481 106.003728)
        (xy 78.964602 106.044983)
        (xy 78.966648 106.08664)
        (xy 78.964601 106.128296)
        (xy 78.958481 106.169553)
        (xy 78.948347 106.21001)
        (xy 78.934296 106.24928)
        (xy 78.916464 106.286982)
        (xy 78.895022 106.322757)
        (xy 78.870177 106.356257)
        (xy 78.842168 106.38716)
        (xy 78.811266 106.415169)
        (xy 78.777765 106.440015)
        (xy 78.741991 106.461455)
        (xy 78.704287 106.479288)
        (xy 78.665018 106.493339)
        (xy 78.624561 106.503472)
        (xy 78.583305 106.509592)
        (xy 78.541648 106.51164)
        (xy 78.499991 106.509593)
        (xy 78.458735 106.503473)
        (xy 78.418278 106.493339)
        (xy 78.379008 106.479288)
        (xy 78.341305 106.461456)
        (xy 78.305531 106.440014)
        (xy 78.272032 106.415169)
        (xy 78.241128 106.38716)
        (xy 78.213119 106.356256)
        (xy 78.188274 106.322756)
        (xy 78.166832 106.286983)
        (xy 78.149 106.24928)
        (xy 78.134949 106.21001)
        (xy 78.124815 106.169553)
        (xy 78.118695 106.128297)
      )
    )
  )
  (zone (net 0) (net_name "") (layers "In1.Cu" "In5.Cu" "In6.Cu") (hatch edge 0.508)
    (connect_pads yes (clearance 0))
    (min_thickness 0.1) (filled_areas_thickness no)
    (keepout (tracks allowed) (vias allowed) (pads allowed) (copperpour not_allowed) (footprints allowed))
    (fill (thermal_gap 0.254) (thermal_bridge_width 0.254))
    (polygon
      (pts
        (xy 78.168 112.408)
        (xy 78.169 111.814)
        (xy 79.016 111.814)
        (xy 79.016 112.409)
      )
    )
  )
  (zone (net 0) (net_name "") (layers "In1.Cu" "In5.Cu" "In6.Cu") (hatch edge 0.508)
    (connect_pads yes (clearance 0))
    (min_thickness 0.1) (filled_areas_thickness no)
    (keepout (tracks allowed) (vias allowed) (pads allowed) (copperpour not_allowed) (footprints allowed))
    (fill (thermal_gap 0.254) (thermal_bridge_width 0.254))
    (polygon
      (pts
        (xy 78.698 109.608)
        (xy 78.699 109.014)
        (xy 79.546 109.014)
        (xy 79.546 109.609)
      )
    )
  )
  (zone (net 0) (net_name "") (layers "In1.Cu" "In5.Cu" "In6.Cu") (hatch edge 0.508)
    (connect_pads yes (clearance 0))
    (min_thickness 0.1) (filled_areas_thickness no)
    (keepout (tracks allowed) (vias allowed) (pads allowed) (copperpour not_allowed) (footprints allowed))
    (fill (thermal_gap 0.254) (thermal_bridge_width 0.254))
    (polygon
      (pts
        (xy 78.118 106.098)
        (xy 78.119 105.504)
        (xy 78.966 105.504)
        (xy 78.966 106.099)
      )
    )
  )
  (zone (net 0) (net_name "") (layers "In1.Cu" "In5.Cu" "In6.Cu") (hatch edge 0.508)
    (connect_pads yes (clearance 0))
    (min_thickness 0.1) (filled_areas_thickness no)
    (keepout (tracks allowed) (vias allowed) (pads allowed) (copperpour not_allowed) (footprints allowed))
    (fill (thermal_gap 0.254) (thermal_bridge_width 0.254))
    (polygon
      (pts
        (xy 78.846648 108.16664)
        (xy 78.848695 108.124983)
        (xy 78.854815 108.083727)
        (xy 78.864949 108.04327)
        (xy 78.879 108.004001)
        (xy 78.896832 107.966297)
        (xy 78.918273 107.930523)
        (xy 78.943119 107.897022)
        (xy 78.971128 107.86612)
        (xy 79.002031 107.83811)
        (xy 79.035531 107.813266)
        (xy 79.071305 107.791824)
        (xy 79.109008 107.773992)
        (xy 79.148278 107.759941)
        (xy 79.188735 107.749807)
        (xy 79.229991 107.743687)
        (xy 79.271648 107.74164)
        (xy 79.313306 107.743687)
        (xy 79.35456 107.749807)
        (xy 79.395018 107.759941)
        (xy 79.434288 107.773991)
        (xy 79.471991 107.791825)
        (xy 79.507765 107.813266)
        (xy 79.541265 107.83811)
        (xy 79.572168 107.86612)
        (xy 79.600177 107.897023)
        (xy 79.625022 107.930523)
        (xy 79.646464 107.966298)
        (xy 79.664296 108.004)
        (xy 79.678347 108.04327)
        (xy 79.688481 108.083728)
        (xy 79.694602 108.124983)
        (xy 79.696648 108.16664)
        (xy 79.694601 108.208296)
        (xy 79.688481 108.249553)
        (xy 79.678347 108.29001)
        (xy 79.664296 108.32928)
        (xy 79.646464 108.366982)
        (xy 79.625022 108.402757)
        (xy 79.600177 108.436257)
        (xy 79.572168 108.46716)
        (xy 79.541266 108.495169)
        (xy 79.507765 108.520015)
        (xy 79.471991 108.541455)
        (xy 79.434287 108.559288)
        (xy 79.395018 108.573339)
        (xy 79.354561 108.583472)
        (xy 79.313305 108.589592)
        (xy 79.271648 108.59164)
        (xy 79.229991 108.589593)
        (xy 79.188735 108.583473)
        (xy 79.148278 108.573339)
        (xy 79.109008 108.559288)
        (xy 79.071305 108.541456)
        (xy 79.035531 108.520014)
        (xy 79.002032 108.495169)
        (xy 78.971128 108.46716)
        (xy 78.943119 108.436256)
        (xy 78.918274 108.402756)
        (xy 78.896832 108.366983)
        (xy 78.879 108.32928)
        (xy 78.864949 108.29001)
        (xy 78.854815 108.249553)
        (xy 78.848695 108.208297)
      )
    )
  )
  (zone (net 21) (net_name "PL_1V2") (layer "In2.Cu") (hatch edge 0.508)
    (connect_pads yes (clearance 0.1))
    (min_thickness 0.254) (filled_areas_thickness no)
    (fill yes (thermal_gap 0.508) (thermal_bridge_width 0.508) (smoothing fillet) (radius 0.127))
    (polygon
      (pts
        (xy 191.6 145.05)
        (xy 187.5 145.05)
        (xy 185.2 147.35)
        (xy 185.2 148.85)
        (xy 182.05 152)
        (xy 82.1 152)
        (xy 80.6 150.5)
        (xy 80.6 137.05)
        (xy 88.5 137.05)
        (xy 88.95 136.6)
        (xy 88.95 135.85)
        (xy 90 135.85)
        (xy 90 138.375)
        (xy 90.325 138.7)
        (xy 92.975 138.7)
        (xy 92.975 140.6)
        (xy 88 140.6)
        (xy 85.95 142.65)
        (xy 85.95 147.1)
        (xy 87.6 148.75)
        (xy 178.95 148.8)
        (xy 180.645913 147.095934)
        (xy 180.65 139.2)
        (xy 188.527042 139.176914)
        (xy 189.35 138.35)
        (xy 191.6 138.35)
      )
    )
  )
  (zone (net 20) (net_name "PL_3V3") (layer "In2.Cu") (hatch edge 0.508)
    (connect_pads yes (clearance 0.1))
    (min_thickness 0.254) (filled_areas_thickness no)
    (fill yes (thermal_gap 0.508) (thermal_bridge_width 0.508) (smoothing fillet) (radius 0.127))
    (polygon
      (pts
        (xy 92.35 129.75)
        (xy 88.05 129.75)
        (xy 87.55 129.25)
        (xy 87.55 127.8)
        (xy 92.35 127.8)
      )
    )
  )
  (zone (net 138) (net_name "/Debug and JTAG/USB_3V3") (layer "In2.Cu") (hatch edge 0.508)
    (connect_pads (clearance 0.127))
    (min_thickness 0.1) (filled_areas_thickness no)
    (fill yes (thermal_gap 0.254) (thermal_bridge_width 0.254) (smoothing fillet) (radius 0.127))
    (polygon
      (pts
        (xy 153.5 113.65)
        (xy 153.5 125.95)
        (xy 150.45 129)
        (xy 144.85 129.005)
        (xy 141.835 132.03)
        (xy 137.45 132.03)
        (xy 137.45 125.2)
        (xy 136.5 124.255)
        (xy 136.5 121.705)
        (xy 136.5 120.28)
        (xy 136.257383 120.03)
        (xy 136.275 112.875)
        (xy 138.325 110.825)
        (xy 140.2 110.825)
        (xy 140.975 110.05)
        (xy 146.9 110.05)
        (xy 147.5 110.655)
        (xy 147.5 112.65)
        (xy 149.7 112.65)
        (xy 149.7 110.05)
        (xy 153.5 110.05)
      )
    )
  )
  (zone (net 17) (net_name "PS_1V8") (layer "In2.Cu") (hatch edge 0.508)
    (connect_pads (clearance 0.127))
    (min_thickness 0.1) (filled_areas_thickness no)
    (fill yes (thermal_gap 0.254) (thermal_bridge_width 0.254) (smoothing fillet) (radius 0.127))
    (polygon
      (pts
        (xy 156.9 91.8)
        (xy 159.3 94.2)
        (xy 165.05 94.2)
        (xy 165.06 111.18)
        (xy 167.12 113.24)
        (xy 177.82 113.24)
        (xy 177.8 117.58)
        (xy 166.725 117.58)
        (xy 164 120.305)
        (xy 164 138.7)
        (xy 161.4 141.25)
        (xy 151.55 141.25)
        (xy 149.600005 139.30114)
        (xy 136.700564 139.349436)
        (xy 129.8 146.25)
        (xy 107.3 146.275)
        (xy 107.3 141.7)
        (xy 107.7 141.3)
        (xy 107.7 136.9375)
        (xy 109.1 135.55)
        (xy 111.55 135.55)
        (xy 114.6 138.6)
        (xy 124.3 138.6)
        (xy 125.475 137.425)
        (xy 130.1 137.425)
        (xy 135.06 132.525)
        (xy 142.285 132.525)
        (xy 145.2 129.6)
        (xy 150.8 129.6)
        (xy 155.65 124.65)
        (xy 155.7 102.35)
        (xy 155.7 99.65)
        (xy 154.3 98.25)
        (xy 154.3 92.7)
        (xy 152.85 92.7)
        (xy 151.75 93.8)
        (xy 149.075 93.8)
        (xy 143.6 88.325)
        (xy 143.6 87.5)
        (xy 142.1 87.5)
        (xy 142.1 89.7)
        (xy 147 94.7)
        (xy 147 95.5)
        (xy 145.6 96.9)
        (xy 130.2 96.9)
        (xy 127.7125 99.4)
        (xy 127.3875 99.4)
        (xy 127.194509 99.594225)
        (xy 126.2 99.6)
        (xy 120.825 104.95)
        (xy 115.3 104.95)
        (xy 115.3 96.8)
        (xy 116.3 95.8)
        (xy 119.22 95.8)
        (xy 119.5 96.08)
        (xy 120.72 96.08)
        (xy 121 95.8)
        (xy 126.1 95.8)
        (xy 134.602489 87.252476)
        (xy 138.65 87.25)
        (xy 138.65 85.5)
        (xy 145 85.5)
        (xy 145.2 85.7)
        (xy 152.1 85.7)
        (xy 153.4 84.4)
        (xy 156.9 84.4)
      )
    )
  )
  (zone (net 15) (net_name "PS_3V3") (layer "In2.Cu") (hatch edge 0.508)
    (connect_pads (clearance 0.127))
    (min_thickness 0.1) (filled_areas_thickness no)
    (fill yes (thermal_gap 0.254) (thermal_bridge_width 0.254) (smoothing fillet) (radius 0.127))
    (polygon
      (pts
        (xy 129.04 79.39)
        (xy 129.04 81.33)
        (xy 129.5 81.76)
        (xy 129.5 84.05)
        (xy 127.05 86.5)
        (xy 125 86.5)
        (xy 124.22 87.28)
        (xy 124.22 89.08)
        (xy 125.375 90.225)
        (xy 128.5 90.225)
        (xy 128.5 93.05)
        (xy 126.225 95.325)
        (xy 125.8 95.32)
        (xy 125.8 94.59)
        (xy 123.65 94.59)
        (xy 123.65 93.135)
        (xy 124.12 92.67)
        (xy 124.12 90.3075)
        (xy 123.65 89.8375)
        (xy 123.65 88.55)
        (xy 118.1 88.55)
        (xy 118.1 89.75)
        (xy 122 89.75)
        (xy 122 90.35)
        (xy 122.55 90.9)
        (xy 122.55 91.55)
        (xy 120.8 91.55)
        (xy 120.8 92.75)
        (xy 119.15 94.35)
        (xy 119.15 95.5)
        (xy 116.29217 95.5)
        (xy 115 96.8)
        (xy 115 103.9)
        (xy 115 104.95)
        (xy 97.6 104.95)
        (xy 97.6 92.8)
        (xy 96.6 91.8)
        (xy 96.6 87.9)
        (xy 95 86.3)
        (xy 94.985 76.95)
        (xy 93.185 75.15)
        (xy 93.2 69.3)
        (xy 98.3 69.3)
        (xy 98.3 86.3)
        (xy 103.1 91.1)
        (xy 113 91.1)
        (xy 115.15 88.95)
        (xy 115.195 80.645)
        (xy 115.395 80.445)
        (xy 116.055 80.445)
        (xy 116.25 80.25)
        (xy 117.75 80.25)
        (xy 119.9 78.1)
        (xy 119.9 77.4)
        (xy 120.35 77.4)
        (xy 121.6 78.65)
        (xy 128.3 78.65)
      )
    )
  )
  (zone (net 9) (net_name "/Power Supply/PoE/VDD_POE_IN") (layer "In2.Cu") (hatch edge 0.508)
    (connect_pads yes (clearance 0.254))
    (min_thickness 0.1) (filled_areas_thickness no)
    (fill yes (thermal_gap 0.254) (thermal_bridge_width 0.254) (smoothing fillet) (radius 0.127))
    (polygon
      (pts
        (xy 191.95 79.35)
        (xy 185.75 85.575)
        (xy 185.75 86.8)
        (xy 183.8 88.75)
        (xy 177.4 88.75)
        (xy 177.39 92.1)
        (xy 167.45 92.1)
        (xy 162.45 87.1)
        (xy 162.45 80.8)
        (xy 171.95 80.8)
        (xy 176.45 80.79)
        (xy 176.45 77.8)
        (xy 179.45 74.8)
        (xy 179.45 70.55)
        (xy 192 70.55)
      )
    )
  )
  (zone (net 306) (net_name "USB_5V") (layer "In2.Cu") (hatch edge 0.508)
    (priority 3)
    (connect_pads yes (clearance 0.127))
    (min_thickness 0.254) (filled_areas_thickness no)
    (fill yes (thermal_gap 0.508) (thermal_bridge_width 0.508) (smoothing fillet) (radius 0.254))
    (polygon
      (pts
        (xy 132.320532 74.220533)
        (xy 142.25 74.25)
        (xy 144.25 76.25)
        (xy 147.3 76.25)
        (xy 151.4 76.25)
        (xy 151.4 79)
        (xy 149.95 79)
        (xy 149.8 79)
        (xy 139.25 79)
        (xy 135.85 75.55)
        (xy 131.549732 75.549733)
        (xy 129.350268 73.350268)
        (xy 124.25 73.35)
        (xy 124.25 72.15)
        (xy 130.229468 72.129468)
      )
    )
  )
  (zone (net 16) (net_name "PS_2V5") (layer "In2.Cu") (hatch edge 0.508)
    (priority 1)
    (connect_pads yes (clearance 0.127))
    (min_thickness 0.254) (filled_areas_thickness no)
    (fill yes (thermal_gap 0.508) (thermal_bridge_width 0.508) (smoothing fillet) (radius 0.127))
    (polygon
      (pts
        (xy 143.2 80.8)
        (xy 147.35 80.8)
        (xy 147.35 81.7)
        (xy 146.2 82.85)
        (xy 146.2 84.2)
        (xy 151 84.2)
        (xy 151 85.4)
        (xy 145.5 85.4)
        (xy 145.3 85.2)
        (xy 138.5 85.195)
        (xy 138.5 87.15)
        (xy 135.55 87.15)
        (xy 135.55 80.79)
      )
    )
  )
  (zone (net 1) (net_name "GND") (layer "In3.Cu") (hatch edge 0.508)
    (connect_pads yes (clearance 0.131))
    (min_thickness 0.1) (filled_areas_thickness no)
    (fill yes (thermal_gap 0.254) (thermal_bridge_width 0.254) (smoothing fillet) (radius 0.127))
    (polygon
      (pts
        (xy 192 152)
        (xy 74 152)
        (xy 74 52)
        (xy 192 52)
      )
    )
  )
  (zone (net 0) (net_name "") (layers "In3.Cu" "In5.Cu" "B.Cu") (hatch edge 0.508)
    (connect_pads yes (clearance 0))
    (min_thickness 0.1) (filled_areas_thickness no)
    (keepout (tracks allowed) (vias allowed) (pads allowed) (copperpour not_allowed) (footprints allowed))
    (fill (thermal_gap 0.254) (thermal_bridge_width 0.254))
    (polygon
      (pts
        (xy 92.8465 106.475)
        (xy 93.8075 106.475)
        (xy 93.8075 107.173)
        (xy 92.8465 107.173)
      )
    )
  )
  (zone (net 0) (net_name "") (layers "In3.Cu" "In5.Cu" "B.Cu") (hatch edge 0.508)
    (connect_pads yes (clearance 0))
    (min_thickness 0.1) (filled_areas_thickness no)
    (keepout (tracks allowed) (vias allowed) (pads allowed) (copperpour not_allowed) (footprints allowed))
    (fill (thermal_gap 0.254) (thermal_bridge_width 0.254))
    (polygon
      (pts
        (xy 89.481657 133.730047)
        (xy 89.522913 133.736167)
        (xy 89.56337 133.746301)
        (xy 89.60264 133.760352)
        (xy 89.640343 133.778184)
        (xy 89.676117 133.799626)
        (xy 89.709617 133.824471)
        (xy 89.74052 133.85248)
        (xy 89.768529 133.883383)
        (xy 89.793374 133.916882)
        (xy 89.814816 133.952657)
        (xy 89.832647 133.99036)
        (xy 89.846699 134.02963)
        (xy 89.856833 134.070087)
        (xy 89.862953 134.111343)
        (xy 89.865 134.153)
        (xy 89.864803 134.157)
        (xy 89.865 134.157)
        (xy 89.865 134.726447)
        (xy 89.865648 134.73964)
        (xy 89.863601 134.781296)
        (xy 89.857481 134.822553)
        (xy 89.847347 134.86301)
        (xy 89.833296 134.90228)
        (xy 89.815464 134.939982)
        (xy 89.794022 134.975757)
        (xy 89.769177 135.009257)
        (xy 89.741168 135.04016)
        (xy 89.710266 135.068169)
        (xy 89.676765 135.093015)
        (xy 89.640991 135.114455)
        (xy 89.603287 135.132288)
        (xy 89.564018 135.146339)
        (xy 89.523561 135.156472)
        (xy 89.482305 135.162592)
        (xy 89.440648 135.16464)
        (xy 89.398991 135.162593)
        (xy 89.357735 135.156473)
        (xy 89.317278 135.146339)
        (xy 89.278008 135.132288)
        (xy 89.240305 135.114456)
        (xy 89.204531 135.093014)
        (xy 89.171032 135.068169)
        (xy 89.140128 135.04016)
        (xy 89.112119 135.009256)
        (xy 89.087274 134.975756)
        (xy 89.065832 134.939983)
        (xy 89.048 134.90228)
        (xy 89.033949 134.86301)
        (xy 89.023815 134.822553)
        (xy 89.017695 134.781297)
        (xy 89.015648 134.73964)
        (xy 89.017068 134.710747)
        (xy 89.017927 134.200587)
        (xy 89.017047 134.194657)
        (xy 89.015 134.153)
        (xy 89.017047 134.111342)
        (xy 89.023166 134.070087)
        (xy 89.033301 134.02963)
        (xy 89.047352 133.99036)
        (xy 89.065183 133.952657)
        (xy 89.086626 133.916883)
        (xy 89.111471 133.883383)
        (xy 89.13948 133.85248)
        (xy 89.170383 133.824471)
        (xy 89.203883 133.799626)
        (xy 89.239657 133.778183)
        (xy 89.27736 133.760352)
        (xy 89.31663 133.746301)
        (xy 89.357087 133.736166)
        (xy 89.398343 133.730046)
        (xy 89.44 133.728)
      )
    )
  )
  (zone (net 0) (net_name "") (layers "In3.Cu" "In5.Cu" "B.Cu") (hatch edge 0.508)
    (connect_pads yes (clearance 0))
    (min_thickness 0.1) (filled_areas_thickness no)
    (keepout (tracks allowed) (vias allowed) (pads allowed) (copperpour not_allowed) (footprints allowed))
    (fill (thermal_gap 0.254) (thermal_bridge_width 0.254))
    (polygon
      (pts
        (xy 91.218704 133.728704)
        (xy 91.25996 133.734824)
        (xy 91.300417 133.744958)
        (xy 91.339687 133.759009)
        (xy 91.37739 133.776841)
        (xy 91.413164 133.798283)
        (xy 91.446664 133.823128)
        (xy 91.477567 133.851137)
        (xy 91.505576 133.88204)
        (xy 91.530421 133.915539)
        (xy 91.551863 133.951314)
        (xy 91.569694 133.989017)
        (xy 91.583746 134.028287)
        (xy 91.59388 134.068744)
        (xy 91.6 134.11)
        (xy 91.602047 134.151657)
        (xy 91.60185 134.155657)
        (xy 91.602047 134.155657)
        (xy 91.602047 134.725104)
        (xy 91.602695 134.738297)
        (xy 91.600648 134.779953)
        (xy 91.594528 134.82121)
        (xy 91.584394 134.861667)
        (xy 91.570343 134.900937)
        (xy 91.552511 134.938639)
        (xy 91.531069 134.974414)
        (xy 91.506224 135.007914)
        (xy 91.478215 135.038817)
        (xy 91.447313 135.066826)
        (xy 91.413812 135.091672)
        (xy 91.378038 135.113112)
        (xy 91.340334 135.130945)
        (xy 91.301065 135.144996)
        (xy 91.260608 135.155129)
        (xy 91.219352 135.161249)
        (xy 91.177695 135.163297)
        (xy 91.136038 135.16125)
        (xy 91.094782 135.15513)
        (xy 91.054325 135.144996)
        (xy 91.015055 135.130945)
        (xy 90.977352 135.113113)
        (xy 90.941578 135.091671)
        (xy 90.908079 135.066826)
        (xy 90.877175 135.038817)
        (xy 90.849166 135.007913)
        (xy 90.824321 134.974413)
        (xy 90.802879 134.93864)
        (xy 90.785047 134.900937)
        (xy 90.770996 134.861667)
        (xy 90.760862 134.82121)
        (xy 90.754742 134.779954)
        (xy 90.752695 134.738297)
        (xy 90.754115 134.709404)
        (xy 90.754974 134.199244)
        (xy 90.754094 134.193314)
        (xy 90.752047 134.151657)
        (xy 90.754094 134.109999)
        (xy 90.760213 134.068744)
        (xy 90.770348 134.028287)
        (xy 90.784399 133.989017)
        (xy 90.80223 133.951314)
        (xy 90.823673 133.91554)
        (xy 90.848518 133.88204)
        (xy 90.876527 133.851137)
        (xy 90.90743 133.823128)
        (xy 90.94093 133.798283)
        (xy 90.976704 133.77684)
        (xy 91.014407 133.759009)
        (xy 91.053677 133.744958)
        (xy 91.094134 133.734823)
        (xy 91.13539 133.728703)
        (xy 91.177047 133.726657)
      )
    )
  )
  (zone (net 0) (net_name "") (layers "In3.Cu" "In5.Cu" "B.Cu") (hatch edge 0.508)
    (connect_pads yes (clearance 0))
    (min_thickness 0.1) (filled_areas_thickness no)
    (keepout (tracks allowed) (vias allowed) (pads allowed) (copperpour not_allowed) (footprints allowed))
    (fill (thermal_gap 0.254) (thermal_bridge_width 0.254))
    (polygon
      (pts
        (xy 92.017379 133.711708)
        (xy 92.058635 133.717828)
        (xy 92.099092 133.727962)
        (xy 92.138362 133.742013)
        (xy 92.176065 133.759845)
        (xy 92.211839 133.781287)
        (xy 92.245339 133.806132)
        (xy 92.276242 133.834141)
        (xy 92.304251 133.865044)
        (xy 92.329096 133.898543)
        (xy 92.350538 133.934318)
        (xy 92.368369 133.972021)
        (xy 92.382421 134.011291)
        (xy 92.392555 134.051748)
        (xy 92.398675 134.093004)
        (xy 92.400722 134.134661)
        (xy 92.400525 134.138661)
        (xy 92.400722 134.138661)
        (xy 92.400722 134.708108)
        (xy 92.40137 134.721301)
        (xy 92.399323 134.762957)
        (xy 92.393203 134.804214)
        (xy 92.383069 134.844671)
        (xy 92.369018 134.883941)
        (xy 92.351186 134.921643)
        (xy 92.329744 134.957418)
        (xy 92.304899 134.990918)
        (xy 92.27689 135.021821)
        (xy 92.245988 135.04983)
        (xy 92.212487 135.074676)
        (xy 92.176713 135.096116)
        (xy 92.139009 135.113949)
        (xy 92.09974 135.128)
        (xy 92.059283 135.138133)
        (xy 92.018027 135.144253)
        (xy 91.97637 135.146301)
        (xy 91.934713 135.144254)
        (xy 91.893457 135.138134)
        (xy 91.853 135.128)
        (xy 91.81373 135.113949)
        (xy 91.776027 135.096117)
        (xy 91.740253 135.074675)
        (xy 91.706754 135.04983)
        (xy 91.67585 135.021821)
        (xy 91.647841 134.990917)
        (xy 91.622996 134.957417)
        (xy 91.601554 134.921644)
        (xy 91.583722 134.883941)
        (xy 91.569671 134.844671)
        (xy 91.559537 134.804214)
        (xy 91.553417 134.762958)
        (xy 91.55137 134.721301)
        (xy 91.55279 134.692408)
        (xy 91.553649 134.182248)
        (xy 91.552769 134.176318)
        (xy 91.550722 134.134661)
        (xy 91.552769 134.093003)
        (xy 91.558888 134.051748)
        (xy 91.569023 134.011291)
        (xy 91.583074 133.972021)
        (xy 91.600905 133.934318)
        (xy 91.622348 133.898544)
        (xy 91.647193 133.865044)
        (xy 91.675202 133.834141)
        (xy 91.706105 133.806132)
        (xy 91.739605 133.781287)
        (xy 91.775379 133.759844)
        (xy 91.813082 133.742013)
        (xy 91.852352 133.727962)
        (xy 91.892809 133.717827)
        (xy 91.934065 133.711707)
        (xy 91.975722 133.709661)
      )
    )
  )
  (zone (net 0) (net_name "") (layers "In3.Cu" "In5.Cu" "B.Cu") (hatch edge 0.508)
    (connect_pads yes (clearance 0))
    (min_thickness 0.1) (filled_areas_thickness no)
    (keepout (tracks allowed) (vias allowed) (pads allowed) (copperpour not_allowed) (footprints allowed))
    (fill (thermal_gap 0.254) (thermal_bridge_width 0.254))
    (polygon
      (pts
        (xy 90.303 106.477)
        (xy 91.264 106.477)
        (xy 91.264 107.175)
        (xy 90.303 107.175)
      )
    )
  )
  (zone (net 0) (net_name "") (layers "In3.Cu" "In5.Cu" "B.Cu") (hatch edge 0.508)
    (connect_pads yes (clearance 0))
    (min_thickness 0.1) (filled_areas_thickness no)
    (keepout (tracks allowed) (vias allowed) (pads allowed) (copperpour not_allowed) (footprints allowed))
    (fill (thermal_gap 0.254) (thermal_bridge_width 0.254))
    (polygon
      (pts
        (xy 89.351 105.214)
        (xy 90.312 105.214)
        (xy 90.312 105.912)
        (xy 89.351 105.912)
      )
    )
  )
  (zone (net 0) (net_name "") (layers "In3.Cu" "In5.Cu" "B.Cu") (hatch edge 0.508)
    (connect_pads yes (clearance 0))
    (min_thickness 0.1) (filled_areas_thickness no)
    (keepout (tracks allowed) (vias allowed) (pads allowed) (copperpour not_allowed) (footprints allowed))
    (fill (thermal_gap 0.254) (thermal_bridge_width 0.254))
    (polygon
      (pts
        (xy 91.888 105.22)
        (xy 92.849 105.22)
        (xy 92.849 105.918)
        (xy 91.888 105.918)
      )
    )
  )
  (zone (net 0) (net_name "") (layers "In3.Cu" "In5.Cu" "B.Cu") (hatch edge 0.508)
    (connect_pads yes (clearance 0))
    (min_thickness 0.1) (filled_areas_thickness no)
    (keepout (tracks allowed) (vias allowed) (pads allowed) (copperpour not_allowed) (footprints allowed))
    (fill (thermal_gap 0.254) (thermal_bridge_width 0.254))
    (polygon
      (pts
        (xy 92.847 103.94)
        (xy 93.808 103.94)
        (xy 93.808 104.638)
        (xy 92.847 104.638)
      )
    )
  )
  (zone (net 0) (net_name "") (layers "In3.Cu" "In5.Cu" "B.Cu") (hatch edge 0.508)
    (connect_pads yes (clearance 0))
    (min_thickness 0.1) (filled_areas_thickness no)
    (keepout (tracks allowed) (vias allowed) (pads allowed) (copperpour not_allowed) (footprints allowed))
    (fill (thermal_gap 0.254) (thermal_bridge_width 0.254))
    (polygon
      (pts
        (xy 89.488704 129.908704)
        (xy 89.52996 129.914824)
        (xy 89.570417 129.924958)
        (xy 89.609687 129.939009)
        (xy 89.64739 129.956841)
        (xy 89.683164 129.978283)
        (xy 89.716664 130.003128)
        (xy 89.747567 130.031137)
        (xy 89.775576 130.06204)
        (xy 89.800421 130.095539)
        (xy 89.821863 130.131314)
        (xy 89.839694 130.169017)
        (xy 89.853746 130.208287)
        (xy 89.86388 130.248744)
        (xy 89.87 130.29)
        (xy 89.872047 130.331657)
        (xy 89.87185 130.335657)
        (xy 89.872047 130.335657)
        (xy 89.872047 130.905104)
        (xy 89.872695 130.918297)
        (xy 89.870648 130.959953)
        (xy 89.864528 131.00121)
        (xy 89.854394 131.041667)
        (xy 89.840343 131.080937)
        (xy 89.822511 131.118639)
        (xy 89.801069 131.154414)
        (xy 89.776224 131.187914)
        (xy 89.748215 131.218817)
        (xy 89.717313 131.246826)
        (xy 89.683812 131.271672)
        (xy 89.648038 131.293112)
        (xy 89.610334 131.310945)
        (xy 89.571065 131.324996)
        (xy 89.530608 131.335129)
        (xy 89.489352 131.341249)
        (xy 89.447695 131.343297)
        (xy 89.406038 131.34125)
        (xy 89.364782 131.33513)
        (xy 89.324325 131.324996)
        (xy 89.285055 131.310945)
        (xy 89.247352 131.293113)
        (xy 89.211578 131.271671)
        (xy 89.178079 131.246826)
        (xy 89.147175 131.218817)
        (xy 89.119166 131.187913)
        (xy 89.094321 131.154413)
        (xy 89.072879 131.11864)
        (xy 89.055047 131.080937)
        (xy 89.040996 131.041667)
        (xy 89.030862 131.00121)
        (xy 89.024742 130.959954)
        (xy 89.022695 130.918297)
        (xy 89.024115 130.889404)
        (xy 89.024974 130.379244)
        (xy 89.024094 130.373314)
        (xy 89.022047 130.331657)
        (xy 89.024094 130.289999)
        (xy 89.030213 130.248744)
        (xy 89.040348 130.208287)
        (xy 89.054399 130.169017)
        (xy 89.07223 130.131314)
        (xy 89.093673 130.09554)
        (xy 89.118518 130.06204)
        (xy 89.146527 130.031137)
        (xy 89.17743 130.003128)
        (xy 89.21093 129.978283)
        (xy 89.246704 129.95684)
        (xy 89.284407 129.939009)
        (xy 89.323677 129.924958)
        (xy 89.364134 129.914823)
        (xy 89.40539 129.908703)
        (xy 89.447047 129.906657)
      )
    )
  )
  (zone (net 0) (net_name "") (layers "In3.Cu" "In5.Cu" "B.Cu") (hatch edge 0.508)
    (connect_pads yes (clearance 0))
    (min_thickness 0.1) (filled_areas_thickness no)
    (keepout (tracks allowed) (vias allowed) (pads allowed) (copperpour not_allowed) (footprints allowed))
    (fill (thermal_gap 0.254) (thermal_bridge_width 0.254))
    (polygon
      (pts
        (xy 91.866 102.666)
        (xy 92.827 102.666)
        (xy 92.827 103.364)
        (xy 91.866 103.364)
      )
    )
  )
  (zone (net 0) (net_name "") (layers "In3.Cu" "In5.Cu" "B.Cu") (hatch edge 0.508)
    (connect_pads yes (clearance 0))
    (min_thickness 0.1) (filled_areas_thickness no)
    (keepout (tracks allowed) (vias allowed) (pads allowed) (copperpour not_allowed) (footprints allowed))
    (fill (thermal_gap 0.254) (thermal_bridge_width 0.254))
    (polygon
      (pts
        (xy 91.208704 129.928704)
        (xy 91.24996 129.934824)
        (xy 91.290417 129.944958)
        (xy 91.329687 129.959009)
        (xy 91.36739 129.976841)
        (xy 91.403164 129.998283)
        (xy 91.436664 130.023128)
        (xy 91.467567 130.051137)
        (xy 91.495576 130.08204)
        (xy 91.520421 130.115539)
        (xy 91.541863 130.151314)
        (xy 91.559694 130.189017)
        (xy 91.573746 130.228287)
        (xy 91.58388 130.268744)
        (xy 91.59 130.31)
        (xy 91.592047 130.351657)
        (xy 91.59185 130.355657)
        (xy 91.592047 130.355657)
        (xy 91.592047 130.925104)
        (xy 91.592695 130.938297)
        (xy 91.590648 130.979953)
        (xy 91.584528 131.02121)
        (xy 91.574394 131.061667)
        (xy 91.560343 131.100937)
        (xy 91.542511 131.138639)
        (xy 91.521069 131.174414)
        (xy 91.496224 131.207914)
        (xy 91.468215 131.238817)
        (xy 91.437313 131.266826)
        (xy 91.403812 131.291672)
        (xy 91.368038 131.313112)
        (xy 91.330334 131.330945)
        (xy 91.291065 131.344996)
        (xy 91.250608 131.355129)
        (xy 91.209352 131.361249)
        (xy 91.167695 131.363297)
        (xy 91.126038 131.36125)
        (xy 91.084782 131.35513)
        (xy 91.044325 131.344996)
        (xy 91.005055 131.330945)
        (xy 90.967352 131.313113)
        (xy 90.931578 131.291671)
        (xy 90.898079 131.266826)
        (xy 90.867175 131.238817)
        (xy 90.839166 131.207913)
        (xy 90.814321 131.174413)
        (xy 90.792879 131.13864)
        (xy 90.775047 131.100937)
        (xy 90.760996 131.061667)
        (xy 90.750862 131.02121)
        (xy 90.744742 130.979954)
        (xy 90.742695 130.938297)
        (xy 90.744115 130.909404)
        (xy 90.744974 130.399244)
        (xy 90.744094 130.393314)
        (xy 90.742047 130.351657)
        (xy 90.744094 130.309999)
        (xy 90.750213 130.268744)
        (xy 90.760348 130.228287)
        (xy 90.774399 130.189017)
        (xy 90.79223 130.151314)
        (xy 90.813673 130.11554)
        (xy 90.838518 130.08204)
        (xy 90.866527 130.051137)
        (xy 90.89743 130.023128)
        (xy 90.93093 129.998283)
        (xy 90.966704 129.97684)
        (xy 91.004407 129.959009)
        (xy 91.043677 129.944958)
        (xy 91.084134 129.934823)
        (xy 91.12539 129.928703)
        (xy 91.167047 129.926657)
      )
    )
  )
  (zone (net 0) (net_name "") (layers "In3.Cu" "In5.Cu" "B.Cu") (hatch edge 0.508)
    (connect_pads yes (clearance 0))
    (min_thickness 0.1) (filled_areas_thickness no)
    (keepout (tracks allowed) (vias allowed) (pads allowed) (copperpour not_allowed) (footprints allowed))
    (fill (thermal_gap 0.254) (thermal_bridge_width 0.254))
    (polygon
      (pts
        (xy 92.026657 135.627423)
        (xy 92.067913 135.633543)
        (xy 92.10837 135.643677)
        (xy 92.14764 135.657728)
        (xy 92.185343 135.67556)
        (xy 92.221117 135.697002)
        (xy 92.254617 135.721847)
        (xy 92.28552 135.749856)
        (xy 92.313529 135.780759)
        (xy 92.338374 135.814258)
        (xy 92.359816 135.850033)
        (xy 92.377647 135.887736)
        (xy 92.391699 135.927006)
        (xy 92.401833 135.967463)
        (xy 92.407953 136.008719)
        (xy 92.41 136.050376)
        (xy 92.409803 136.054376)
        (xy 92.41 136.054376)
        (xy 92.41 136.623823)
        (xy 92.410648 136.637016)
        (xy 92.408601 136.678672)
        (xy 92.402481 136.719929)
        (xy 92.392347 136.760386)
        (xy 92.378296 136.799656)
        (xy 92.360464 136.837358)
        (xy 92.339022 136.873133)
        (xy 92.314177 136.906633)
        (xy 92.286168 136.937536)
        (xy 92.255266 136.965545)
        (xy 92.221765 136.990391)
        (xy 92.185991 137.011831)
        (xy 92.148287 137.029664)
        (xy 92.109018 137.043715)
        (xy 92.068561 137.053848)
        (xy 92.027305 137.059968)
        (xy 91.985648 137.062016)
        (xy 91.943991 137.059969)
        (xy 91.902735 137.053849)
        (xy 91.862278 137.043715)
        (xy 91.823008 137.029664)
        (xy 91.785305 137.011832)
        (xy 91.749531 136.99039)
        (xy 91.716032 136.965545)
        (xy 91.685128 136.937536)
        (xy 91.657119 136.906632)
        (xy 91.632274 136.873132)
        (xy 91.610832 136.837359)
        (xy 91.593 136.799656)
        (xy 91.578949 136.760386)
        (xy 91.568815 136.719929)
        (xy 91.562695 136.678673)
        (xy 91.560648 136.637016)
        (xy 91.562068 136.608123)
        (xy 91.562927 136.097963)
        (xy 91.562047 136.092033)
        (xy 91.56 136.050376)
        (xy 91.562047 136.008718)
        (xy 91.568166 135.967463)
        (xy 91.578301 135.927006)
        (xy 91.592352 135.887736)
        (xy 91.610183 135.850033)
        (xy 91.631626 135.814259)
        (xy 91.656471 135.780759)
        (xy 91.68448 135.749856)
        (xy 91.715383 135.721847)
        (xy 91.748883 135.697002)
        (xy 91.784657 135.675559)
        (xy 91.82236 135.657728)
        (xy 91.86163 135.643677)
        (xy 91.902087 135.633542)
        (xy 91.943343 135.627422)
        (xy 91.985 135.625376)
      )
    )
  )
  (zone (net 0) (net_name "") (layers "In3.Cu" "In5.Cu" "B.Cu") (hatch edge 0.508)
    (connect_pads yes (clearance 0))
    (min_thickness 0.1) (filled_areas_thickness no)
    (keepout (tracks allowed) (vias allowed) (pads allowed) (copperpour not_allowed) (footprints allowed))
    (fill (thermal_gap 0.254) (thermal_bridge_width 0.254))
    (polygon
      (pts
        (xy 91.892 100.129)
        (xy 92.853 100.129)
        (xy 92.853 100.827)
        (xy 91.892 100.827)
      )
    )
  )
  (zone (net 0) (net_name "") (layers "In3.Cu" "In5.Cu" "B.Cu") (hatch edge 0.508)
    (connect_pads yes (clearance 0))
    (min_thickness 0.1) (filled_areas_thickness no)
    (keepout (tracks allowed) (vias allowed) (pads allowed) (copperpour not_allowed) (footprints allowed))
    (fill (thermal_gap 0.254) (thermal_bridge_width 0.254))
    (polygon
      (pts
        (xy 90.291 103.938)
        (xy 91.252 103.938)
        (xy 91.252 104.636)
        (xy 90.291 104.636)
      )
    )
  )
  (zone (net 0) (net_name "") (layers "In3.Cu" "In5.Cu" "B.Cu") (hatch edge 0.508)
    (connect_pads yes (clearance 0))
    (min_thickness 0.1) (filled_areas_thickness no)
    (keepout (tracks allowed) (vias allowed) (pads allowed) (copperpour not_allowed) (footprints allowed))
    (fill (thermal_gap 0.254) (thermal_bridge_width 0.254))
    (polygon
      (pts
        (xy 93.748704 133.728704)
        (xy 93.78996 133.734824)
        (xy 93.830417 133.744958)
        (xy 93.869687 133.759009)
        (xy 93.90739 133.776841)
        (xy 93.943164 133.798283)
        (xy 93.976664 133.823128)
        (xy 94.007567 133.851137)
        (xy 94.035576 133.88204)
        (xy 94.060421 133.915539)
        (xy 94.081863 133.951314)
        (xy 94.099694 133.989017)
        (xy 94.113746 134.028287)
        (xy 94.12388 134.068744)
        (xy 94.13 134.11)
        (xy 94.132047 134.151657)
        (xy 94.13185 134.155657)
        (xy 94.132047 134.155657)
        (xy 94.132047 134.725104)
        (xy 94.132695 134.738297)
        (xy 94.130648 134.779953)
        (xy 94.124528 134.82121)
        (xy 94.114394 134.861667)
        (xy 94.100343 134.900937)
        (xy 94.082511 134.938639)
        (xy 94.061069 134.974414)
        (xy 94.036224 135.007914)
        (xy 94.008215 135.038817)
        (xy 93.977313 135.066826)
        (xy 93.943812 135.091672)
        (xy 93.908038 135.113112)
        (xy 93.870334 135.130945)
        (xy 93.831065 135.144996)
        (xy 93.790608 135.155129)
        (xy 93.749352 135.161249)
        (xy 93.707695 135.163297)
        (xy 93.666038 135.16125)
        (xy 93.624782 135.15513)
        (xy 93.584325 135.144996)
        (xy 93.545055 135.130945)
        (xy 93.507352 135.113113)
        (xy 93.471578 135.091671)
        (xy 93.438079 135.066826)
        (xy 93.407175 135.038817)
        (xy 93.379166 135.007913)
        (xy 93.354321 134.974413)
        (xy 93.332879 134.93864)
        (xy 93.315047 134.900937)
        (xy 93.300996 134.861667)
        (xy 93.290862 134.82121)
        (xy 93.284742 134.779954)
        (xy 93.282695 134.738297)
        (xy 93.284115 134.709404)
        (xy 93.284974 134.199244)
        (xy 93.284094 134.193314)
        (xy 93.282047 134.151657)
        (xy 93.284094 134.109999)
        (xy 93.290213 134.068744)
        (xy 93.300348 134.028287)
        (xy 93.314399 133.989017)
        (xy 93.33223 133.951314)
        (xy 93.353673 133.91554)
        (xy 93.378518 133.88204)
        (xy 93.406527 133.851137)
        (xy 93.43743 133.823128)
        (xy 93.47093 133.798283)
        (xy 93.506704 133.77684)
        (xy 93.544407 133.759009)
        (xy 93.583677 133.744958)
        (xy 93.624134 133.734823)
        (xy 93.66539 133.728703)
        (xy 93.707047 133.726657)
      )
    )
  )
  (zone (net 0) (net_name "") (layers "In3.Cu" "In5.Cu" "B.Cu") (hatch edge 0.508)
    (connect_pads yes (clearance 0))
    (min_thickness 0.1) (filled_areas_thickness no)
    (keepout (tracks allowed) (vias allowed) (pads allowed) (copperpour not_allowed) (footprints allowed))
    (fill (thermal_gap 0.254) (thermal_bridge_width 0.254))
    (polygon
      (pts
        (xy 92.018704 131.818704)
        (xy 92.05996 131.824824)
        (xy 92.100417 131.834958)
        (xy 92.139687 131.849009)
        (xy 92.17739 131.866841)
        (xy 92.213164 131.888283)
        (xy 92.246664 131.913128)
        (xy 92.277567 131.941137)
        (xy 92.305576 131.97204)
        (xy 92.330421 132.005539)
        (xy 92.351863 132.041314)
        (xy 92.369694 132.079017)
        (xy 92.383746 132.118287)
        (xy 92.39388 132.158744)
        (xy 92.4 132.2)
        (xy 92.402047 132.241657)
        (xy 92.40185 132.245657)
        (xy 92.402047 132.245657)
        (xy 92.402047 132.815104)
        (xy 92.402695 132.828297)
        (xy 92.400648 132.869953)
        (xy 92.394528 132.91121)
        (xy 92.384394 132.951667)
        (xy 92.370343 132.990937)
        (xy 92.352511 133.028639)
        (xy 92.331069 133.064414)
        (xy 92.306224 133.097914)
        (xy 92.278215 133.128817)
        (xy 92.247313 133.156826)
        (xy 92.213812 133.181672)
        (xy 92.178038 133.203112)
        (xy 92.140334 133.220945)
        (xy 92.101065 133.234996)
        (xy 92.060608 133.245129)
        (xy 92.019352 133.251249)
        (xy 91.977695 133.253297)
        (xy 91.936038 133.25125)
        (xy 91.894782 133.24513)
        (xy 91.854325 133.234996)
        (xy 91.815055 133.220945)
        (xy 91.777352 133.203113)
        (xy 91.741578 133.181671)
        (xy 91.708079 133.156826)
        (xy 91.677175 133.128817)
        (xy 91.649166 133.097913)
        (xy 91.624321 133.064413)
        (xy 91.602879 133.02864)
        (xy 91.585047 132.990937)
        (xy 91.570996 132.951667)
        (xy 91.560862 132.91121)
        (xy 91.554742 132.869954)
        (xy 91.552695 132.828297)
        (xy 91.554115 132.799404)
        (xy 91.554974 132.289244)
        (xy 91.554094 132.283314)
        (xy 91.552047 132.241657)
        (xy 91.554094 132.199999)
        (xy 91.560213 132.158744)
        (xy 91.570348 132.118287)
        (xy 91.584399 132.079017)
        (xy 91.60223 132.041314)
        (xy 91.623673 132.00554)
        (xy 91.648518 131.97204)
        (xy 91.676527 131.941137)
        (xy 91.70743 131.913128)
        (xy 91.74093 131.888283)
        (xy 91.776704 131.86684)
        (xy 91.814407 131.849009)
        (xy 91.853677 131.834958)
        (xy 91.894134 131.824823)
        (xy 91.93539 131.818703)
        (xy 91.977047 131.816657)
      )
    )
  )
  (zone (net 0) (net_name "") (layers "In3.Cu" "In5.Cu" "B.Cu") (hatch edge 0.508)
    (connect_pads yes (clearance 0))
    (min_thickness 0.1) (filled_areas_thickness no)
    (keepout (tracks allowed) (vias allowed) (pads allowed) (copperpour not_allowed) (footprints allowed))
    (fill (thermal_gap 0.254) (thermal_bridge_width 0.254))
    (polygon
      (pts
        (xy 89.308 100.127)
        (xy 90.269 100.127)
        (xy 90.269 100.825)
        (xy 89.308 100.825)
      )
    )
  )
  (zone (net 0) (net_name "") (layers "In3.Cu" "In5.Cu" "B.Cu") (hatch edge 0.508)
    (connect_pads yes (clearance 0))
    (min_thickness 0.1) (filled_areas_thickness no)
    (keepout (tracks allowed) (vias allowed) (pads allowed) (copperpour not_allowed) (footprints allowed))
    (fill (thermal_gap 0.254) (thermal_bridge_width 0.254))
    (polygon
      (pts
        (xy 91.213657 131.827046)
        (xy 91.254913 131.833166)
        (xy 91.29537 131.8433)
        (xy 91.33464 131.857351)
        (xy 91.372343 131.875183)
        (xy 91.408117 131.896625)
        (xy 91.441617 131.92147)
        (xy 91.47252 131.949479)
        (xy 91.500529 131.980382)
        (xy 91.525374 132.013881)
        (xy 91.546816 132.049656)
        (xy 91.564647 132.087359)
        (xy 91.578699 132.126629)
        (xy 91.588833 132.167086)
        (xy 91.594953 132.208342)
        (xy 91.597 132.249999)
        (xy 91.596803 132.253999)
        (xy 91.597 132.253999)
        (xy 91.597 132.823446)
        (xy 91.597648 132.836639)
        (xy 91.595601 132.878295)
        (xy 91.589481 132.919552)
        (xy 91.579347 132.960009)
        (xy 91.565296 132.999279)
        (xy 91.547464 133.036981)
        (xy 91.526022 133.072756)
        (xy 91.501177 133.106256)
        (xy 91.473168 133.137159)
        (xy 91.442266 133.165168)
        (xy 91.408765 133.190014)
        (xy 91.372991 133.211454)
        (xy 91.335287 133.229287)
        (xy 91.296018 133.243338)
        (xy 91.255561 133.253471)
        (xy 91.214305 133.259591)
        (xy 91.172648 133.261639)
        (xy 91.130991 133.259592)
        (xy 91.089735 133.253472)
        (xy 91.049278 133.243338)
        (xy 91.010008 133.229287)
        (xy 90.972305 133.211455)
        (xy 90.936531 133.190013)
        (xy 90.903032 133.165168)
        (xy 90.872128 133.137159)
        (xy 90.844119 133.106255)
        (xy 90.819274 133.072755)
        (xy 90.797832 133.036982)
        (xy 90.78 132.999279)
        (xy 90.765949 132.960009)
        (xy 90.755815 132.919552)
        (xy 90.749695 132.878296)
        (xy 90.747648 132.836639)
        (xy 90.749068 132.807746)
        (xy 90.749927 132.297586)
        (xy 90.749047 132.291656)
        (xy 90.747 132.249999)
        (xy 90.749047 132.208341)
        (xy 90.755166 132.167086)
        (xy 90.765301 132.126629)
        (xy 90.779352 132.087359)
        (xy 90.797183 132.049656)
        (xy 90.818626 132.013882)
        (xy 90.843471 131.980382)
        (xy 90.87148 131.949479)
        (xy 90.902383 131.92147)
        (xy 90.935883 131.896625)
        (xy 90.971657 131.875182)
        (xy 91.00936 131.857351)
        (xy 91.04863 131.8433)
        (xy 91.089087 131.833165)
        (xy 91.130343 131.827045)
        (xy 91.172 131.824999)
      )
    )
  )
  (zone (net 0) (net_name "") (layers "In3.Cu" "In5.Cu" "B.Cu") (hatch edge 0.508)
    (connect_pads yes (clearance 0))
    (min_thickness 0.1) (filled_areas_thickness no)
    (keepout (tracks allowed) (vias allowed) (pads allowed) (copperpour not_allowed) (footprints allowed))
    (fill (thermal_gap 0.254) (thermal_bridge_width 0.254))
    (polygon
      (pts
        (xy 89.346 102.67)
        (xy 90.307 102.67)
        (xy 90.307 103.368)
        (xy 89.346 103.368)
      )
    )
  )
  (zone (net 0) (net_name "") (layers "In3.Cu" "In5.Cu" "B.Cu") (hatch edge 0.508)
    (connect_pads yes (clearance 0))
    (min_thickness 0.1) (filled_areas_thickness no)
    (keepout (tracks allowed) (vias allowed) (pads allowed) (copperpour not_allowed) (footprints allowed))
    (fill (thermal_gap 0.254) (thermal_bridge_width 0.254))
    (polygon
      (pts
        (xy 89.478704 131.828704)
        (xy 89.51996 131.834824)
        (xy 89.560417 131.844958)
        (xy 89.599687 131.859009)
        (xy 89.63739 131.876841)
        (xy 89.673164 131.898283)
        (xy 89.706664 131.923128)
        (xy 89.737567 131.951137)
        (xy 89.765576 131.98204)
        (xy 89.790421 132.015539)
        (xy 89.811863 132.051314)
        (xy 89.829694 132.089017)
        (xy 89.843746 132.128287)
        (xy 89.85388 132.168744)
        (xy 89.86 132.21)
        (xy 89.862047 132.251657)
        (xy 89.86185 132.255657)
        (xy 89.862047 132.255657)
        (xy 89.862047 132.825104)
        (xy 89.862695 132.838297)
        (xy 89.860648 132.879953)
        (xy 89.854528 132.92121)
        (xy 89.844394 132.961667)
        (xy 89.830343 133.000937)
        (xy 89.812511 133.038639)
        (xy 89.791069 133.074414)
        (xy 89.766224 133.107914)
        (xy 89.738215 133.138817)
        (xy 89.707313 133.166826)
        (xy 89.673812 133.191672)
        (xy 89.638038 133.213112)
        (xy 89.600334 133.230945)
        (xy 89.561065 133.244996)
        (xy 89.520608 133.255129)
        (xy 89.479352 133.261249)
        (xy 89.437695 133.263297)
        (xy 89.396038 133.26125)
        (xy 89.354782 133.25513)
        (xy 89.314325 133.244996)
        (xy 89.275055 133.230945)
        (xy 89.237352 133.213113)
        (xy 89.201578 133.191671)
        (xy 89.168079 133.166826)
        (xy 89.137175 133.138817)
        (xy 89.109166 133.107913)
        (xy 89.084321 133.074413)
        (xy 89.062879 133.03864)
        (xy 89.045047 133.000937)
        (xy 89.030996 132.961667)
        (xy 89.020862 132.92121)
        (xy 89.014742 132.879954)
        (xy 89.012695 132.838297)
        (xy 89.014115 132.809404)
        (xy 89.014974 132.299244)
        (xy 89.014094 132.293314)
        (xy 89.012047 132.251657)
        (xy 89.014094 132.209999)
        (xy 89.020213 132.168744)
        (xy 89.030348 132.128287)
        (xy 89.044399 132.089017)
        (xy 89.06223 132.051314)
        (xy 89.083673 132.01554)
        (xy 89.108518 131.98204)
        (xy 89.136527 131.951137)
        (xy 89.16743 131.923128)
        (xy 89.20093 131.898283)
        (xy 89.236704 131.87684)
        (xy 89.274407 131.859009)
        (xy 89.313677 131.844958)
        (xy 89.354134 131.834823)
        (xy 89.39539 131.828703)
        (xy 89.437047 131.826657)
      )
    )
  )
  (zone (net 14) (net_name "/Power Supply/DC/DC conventers/DC_MAIN_BUS") (layer "In4.Cu") (hatch edge 0.508)
    (priority 1)
    (connect_pads yes (clearance 0.2))
    (min_thickness 0.1) (filled_areas_thickness no)
    (fill yes (thermal_gap 0.508) (thermal_bridge_width 0.508) (smoothing fillet) (radius 0.127))
    (polygon
      (pts
        (xy 191.964024 122.888192)
        (xy 183.135 122.95)
        (xy 183.135 100)
        (xy 189.71322 93.438997)
        (xy 189.73 85.02)
        (xy 181.214024 76.488192)
        (xy 181.214024 70.318192)
        (xy 183.764024 67.768192)
        (xy 183.764024 58.688192)
        (xy 182.264024 57.188192)
        (xy 156.864024 57.188192)
        (xy 155.864024 58.188192)
        (xy 155.86 67.98)
        (xy 149.66 74.15)
        (xy 148.06 74.15)
        (xy 144.04 78.18)
        (xy 144.045 79.795)
        (xy 141.26 82.58)
        (xy 141.254581 85.188192)
        (xy 137.554581 88.889915)
        (xy 137.554581 89.74)
        (xy 134.004581 89.74)
        (xy 134.004581 82.139915)
        (xy 135.264024 80.888192)
        (xy 146.764024 69.388192)
        (xy 146.764024 52)
        (xy 155.064024 51.988192)
        (xy 192.164024 51.988192)
      )
    )
  )
  (zone (net 86) (net_name "/USB/USB3_VBUS") (layer "In4.Cu") (hatch edge 0.508)
    (connect_pads yes (clearance 0.15))
    (min_thickness 0.1) (filled_areas_thickness no)
    (fill yes (thermal_gap 0.508) (thermal_bridge_width 0.508) (smoothing fillet) (radius 0.127))
    (polygon
      (pts
        (xy 115.875 66.15)
        (xy 115.875 70.35)
        (xy 117.375 71.85)
        (xy 117.375 73.55)
        (xy 116.575 74.35)
        (xy 115.375 74.35)
        (xy 115.375 73.75)
        (xy 116.375 73.75)
        (xy 116.675 73.45)
        (xy 116.675 72.35)
        (xy 114.975 70.65)
        (xy 114.975 69.75)
        (xy 114.575 69.35)
        (xy 114.575 68.25)
        (xy 114.975 67.85)
        (xy 114.975 66.75)
        (xy 114.775 66.55)
        (xy 113.075 66.55)
        (xy 113.075 64.95)
        (xy 114.675 64.95)
      )
    )
  )
  (zone (net 64) (net_name "/USB/USB1_VBUS") (layer "In4.Cu") (hatch edge 0.508)
    (connect_pads yes (clearance 0.15))
    (min_thickness 0.1) (filled_areas_thickness no)
    (fill yes (thermal_gap 0.508) (thermal_bridge_width 0.508) (smoothing fillet) (radius 0.127))
    (polygon
      (pts
        (xy 135.275 66.15)
        (xy 135.275 70.35)
        (xy 136.775 71.85)
        (xy 136.775 73.55)
        (xy 135.975 74.35)
        (xy 134.775 74.35)
        (xy 134.775 73.75)
        (xy 135.775 73.75)
        (xy 136.075 73.45)
        (xy 136.075 72.35)
        (xy 134.375 70.65)
        (xy 134.375 69.75)
        (xy 133.975 69.35)
        (xy 133.975 68.25)
        (xy 134.375 67.85)
        (xy 134.375 66.75)
        (xy 134.175 66.55)
        (xy 132.475 66.55)
        (xy 132.475 64.95)
        (xy 134.075 64.95)
      )
    )
  )
  (zone (net 15) (net_name "PS_3V3") (layer "In4.Cu") (hatch edge 0.508)
    (connect_pads yes (clearance 0.127))
    (min_thickness 0.254) (filled_areas_thickness no)
    (fill yes (thermal_gap 0.508) (thermal_bridge_width 0.508) (smoothing fillet) (radius 0.127))
    (polygon
      (pts
        (xy 163.75 98.5)
        (xy 163.772882 135.250016)
        (xy 169.4 135.25)
        (xy 169.4 138.65)
        (xy 155.11 138.65)
        (xy 155.1 106)
        (xy 150.05 106)
        (xy 150.05 104)
        (xy 155.6 104)
        (xy 155.625 100.05)
        (xy 152.5 100.05)
        (xy 152.5 96.55)
        (xy 156.95 96.55)
        (xy 159.6 93.9)
        (xy 163.75 93.9)
      )
    )
  )
  (zone (net 8) (net_name "SOM_5V0") (layer "In4.Cu") (hatch edge 0.508)
    (priority 1)
    (connect_pads yes (clearance 0.127))
    (min_thickness 0.1) (filled_areas_thickness no)
    (fill yes (thermal_gap 0.254) (thermal_bridge_width 0.254) (smoothing fillet) (radius 0.127))
    (polygon
      (pts
        (xy 126.240557 96.751723)
        (xy 126.240557 100.351723)
        (xy 120.490557 106.101723)
        (xy 113.590557 106.101723)
        (xy 113.590557 98.101723)
        (xy 116.4 95.305)
        (xy 118.904722 95.306639)
        (xy 119.545279 95.953362)
        (xy 120.590557 95.951723)
        (xy 121.25 95.305)
        (xy 124.8 95.305)
      )
    )
  )
  (zone (net 17) (net_name "PS_1V8") (layer "In4.Cu") (hatch edge 0.508)
    (connect_pads yes (clearance 0.127))
    (min_thickness 0.1) (filled_areas_thickness no)
    (fill yes (thermal_gap 0.254) (thermal_bridge_width 0.254) (smoothing fillet) (radius 0.127))
    (polygon
      (pts
        (xy 145.4 128.95)
        (xy 140.6 133.75)
        (xy 140.6 135.25)
        (xy 138.65 137.2)
        (xy 132.3 137.2)
        (xy 132.3 135.6)
        (xy 135.475 135.6)
        (xy 136.75 134.325)
        (xy 136.75 125.9)
        (xy 138.1 124.35)
        (xy 138.1 118.675)
        (xy 141.7 118.675)
        (xy 141.7 121)
        (xy 145.4 124.7)
      )
    )
  )
  (zone (net 15) (net_name "PS_3V3") (layer "In4.Cu") (hatch edge 0.508)
    (connect_pads (clearance 0.127))
    (min_thickness 0.1) (filled_areas_thickness no)
    (fill yes (thermal_gap 0.254) (thermal_bridge_width 0.254) (smoothing fillet) (radius 0.127))
    (polygon
      (pts
        (xy 126.9 146.45)
        (xy 106.9 146.45)
        (xy 99.6 139.15)
        (xy 99.6 133.1)
        (xy 100.6 132.1)
        (xy 106.7 132.1)
        (xy 106.7 136.15)
        (xy 104.75 136.15)
        (xy 103.9 137)
        (xy 103.9 138.15)
        (xy 104.3 138.15)
        (xy 104.425 138.15)
        (xy 105.8125 136.75)
        (xy 113.9 136.75)
        (xy 114.3 137.15)
        (xy 126.9 137.15)
      )
    )
  )
  (zone (net 1) (net_name "GND") (layer "In4.Cu") (hatch edge 0.508)
    (connect_pads yes (clearance 0.5))
    (min_thickness 0.254) (filled_areas_thickness no)
    (fill yes (thermal_gap 0.508) (thermal_bridge_width 0.508) (smoothing fillet) (radius 0.127))
    (polygon
      (pts
        (xy 145.035 68.45)
        (xy 143.885 69.6)
        (xy 136.185 69.6)
        (xy 136.185 63.925)
        (xy 85.71 63.925)
        (xy 83.11 66.525)
        (xy 83.11 84.575)
        (xy 82.035 85.65)
        (xy 74.035 85.65)
        (xy 74.035 52.1125)
        (xy 145.035 51.95)
      )
    )
  )
  (zone (net 0) (net_name "") (layers "In4.Cu" "In6.Cu") (hatch edge 0.508)
    (connect_pads yes (clearance 0))
    (min_thickness 0.1) (filled_areas_thickness no)
    (keepout (tracks allowed) (vias allowed) (pads allowed) (copperpour not_allowed) (footprints allowed))
    (fill (thermal_gap 0.508) (thermal_bridge_width 0.508))
    (polygon
      (pts
        (xy 192.17 74.39)
        (xy 187.8 74.38)
        (xy 187.8 70.16)
        (xy 192.17 70.17)
      )
    )
  )
  (zone (net 1) (net_name "GND") (layer "In5.Cu") (hatch edge 0.508)
    (connect_pads yes (clearance 0.131))
    (min_thickness 0.1) (filled_areas_thickness no)
    (fill yes (thermal_gap 0.254) (thermal_bridge_width 0.254) (smoothing fillet) (radius 0.127))
    (polygon
      (pts
        (xy 192 152)
        (xy 74 152)
        (xy 74 52)
        (xy 192 52)
      )
    )
  )
  (zone (net 1) (net_name "GND") (layer "In6.Cu") (hatch edge 0.508)
    (priority 8)
    (connect_pads yes (clearance 0.1))
    (min_thickness 0.1) (filled_areas_thickness no)
    (fill yes (thermal_gap 0.508) (thermal_bridge_width 0.508) (smoothing fillet) (radius 0.2))
    (polygon
      (pts
        (xy 154.3 70.725)
        (xy 154.3 75.975)
        (xy 151.75 78.525)
        (xy 142.1 78.5)
        (xy 145.725 74.85)
        (xy 145.725 69.325)
        (xy 146.175 69.325)
        (xy 146.625 69.775)
        (xy 150.85 69.775)
        (xy 153.05 67.575)
        (xy 154.47 66.155)
        (xy 155.94 67.64)
        (xy 155.95 69.075)
      )
    )
  )
  (zone (net 1) (net_name "GND") (layer "In6.Cu") (hatch edge 0.508)
    (connect_pads yes (clearance 0.5))
    (min_thickness 0.254) (filled_areas_thickness no)
    (fill yes (thermal_gap 0.508) (thermal_bridge_width 0.508) (smoothing fillet) (radius 0.127))
    (polygon
      (pts
        (xy 145.016186 61.05)
        (xy 144.21 61.85)
        (xy 142.01 61.85)
        (xy 139.31 64.55)
        (xy 139.31 69.575)
        (xy 136.166186 69.575)
        (xy 136.166186 63.9)
        (xy 85.691186 63.9)
        (xy 82.01 67.6)
        (xy 82.01 68.85)
        (xy 80.86 70)
        (xy 80.86 74.05)
        (xy 82.023597 75.199981)
        (xy 82.035 83.775)
        (xy 80.16 85.65)
        (xy 74.016186 85.625)
        (xy 74.016186 52.0875)
        (xy 145.016186 51.925)
      )
    )
  )
  (zone (net 1) (net_name "GND") (layer "In6.Cu") (hatch edge 0.508)
    (connect_pads yes (clearance 0.131))
    (min_thickness 0.1) (filled_areas_thickness no)
    (fill yes (thermal_gap 0.254) (thermal_bridge_width 0.254) (smoothing fillet) (radius 0.127))
    (polygon
      (pts
        (xy 111.3 66.550341)
        (xy 115.125 66.550341)
        (xy 115.125 70.79)
        (xy 116.671929 72.312475)
        (xy 116.67 76.19)
        (xy 116.27 76.6)
        (xy 112.625 76.6)
        (xy 112.625 77.0125)
        (xy 112.625 77.425)
        (xy 112.625 77.9)
        (xy 112.425 77.9)
        (xy 112.425031 77.422536)
        (xy 112.1222 77.418803)
        (xy 111.526199 77.418804)
        (xy 109.825 77.425)
        (xy 109.825 78.225)
        (xy 108.24 78.225)
        (xy 107.596393 77.579986)
        (xy 107.60625 75.175)
        (xy 107.375 74.95)
        (xy 107.375 73.750341)
        (xy 105.7 72.075341)
        (xy 105.675 72.075341)
        (xy 105.675 66.550341)
        (xy 109.125 66.550341)
      )
    )
  )
  (zone (net 0) (net_name "") (layer "In6.Cu") (hatch edge 0.508)
    (connect_pads (clearance 0))
    (min_thickness 0.1) (filled_areas_thickness no)
    (keepout (tracks allowed) (vias allowed) (pads allowed) (copperpour not_allowed) (footprints allowed))
    (fill (thermal_gap 0.254) (thermal_bridge_width 0.254))
    (polygon
      (pts
        (xy 112.025 76.025)
        (xy 110.275 76.025)
        (xy 110.275 74.275)
        (xy 112.025 74.275)
      )
    )
  )
  (zone (net 0) (net_name "") (layer "In6.Cu") (hatch edge 0.508)
    (connect_pads yes (clearance 0))
    (min_thickness 0.1) (filled_areas_thickness no)
    (keepout (tracks not_allowed) (vias not_allowed) (pads allowed) (copperpour not_allowed) (footprints allowed))
    (fill (thermal_gap 0.254) (thermal_bridge_width 0.254))
    (polygon
      (pts
        (xy 111.525 74.025)
        (xy 109.275 74.025)
        (xy 109.275 72.575)
        (xy 111.525 72.575)
      )
    )
  )
  (zone (net 20) (net_name "PL_3V3") (layer "In6.Cu") (hatch edge 0.508)
    (connect_pads yes (clearance 0.127))
    (min_thickness 0.254) (filled_areas_thickness no)
    (fill yes (thermal_gap 0.508) (thermal_bridge_width 0.508) (smoothing fillet) (radius 0.127))
    (polygon
      (pts
        (xy 86.55 146.6)
        (xy 88.75 148.8)
        (xy 94.4 148.8)
        (xy 95.15 148.05)
        (xy 95.15 146.45)
        (xy 97.05 144.55)
        (xy 98.15 144.55)
        (xy 102.35 148.75)
        (xy 163.45 148.8)
        (xy 163.45 142.1)
        (xy 169.8 142.05)
        (xy 169.8 143)
        (xy 166.9 143)
        (xy 166.9 148.8)
        (xy 178.975 148.8)
        (xy 180.2 147.6)
        (xy 180.2 137.1125)
        (xy 184 137.1)
        (xy 184 150.5)
        (xy 182.6 151.9)
        (xy 82.15 151.9)
        (xy 80.65 150.4)
        (xy 80.65 137.1)
        (xy 86.55 137.1)
      )
    )
  )
  (zone (net 8) (net_name "SOM_5V0") (layer "In6.Cu") (hatch edge 0.508)
    (connect_pads yes (clearance 0.127))
    (min_thickness 0.254) (filled_areas_thickness no)
    (fill yes (thermal_gap 0.508) (thermal_bridge_width 0.508) (smoothing fillet) (radius 0.127))
    (polygon
      (pts
        (xy 165.05 119.75)
        (xy 167.8 122.5)
        (xy 167.8 129.4)
        (xy 167.3 129.9)
        (xy 167.3 130.9)
        (xy 165.1 130.9)
        (xy 161.7 130.9)
        (xy 160.7 129.9)
        (xy 156.3 129.9)
        (xy 155.6 129.2)
        (xy 155.6 104)
        (xy 152.15 104)
        (xy 150.05 101.9)
        (xy 150.05 100.45)
        (xy 155.05 100.45)
        (xy 155.05 98.5)
        (xy 159.35 94.2)
        (xy 165.05 94.2)
      )
    )
  )
  (zone (net 132) (net_name "/Debug and JTAG/USB_1V2") (layer "In6.Cu") (hatch edge 0.508)
    (priority 1)
    (connect_pads yes (clearance 0.127))
    (min_thickness 0.1) (filled_areas_thickness no)
    (fill yes (thermal_gap 0.254) (thermal_bridge_width 0.254) (smoothing fillet) (radius 0.127))
    (polygon
      (pts
        (xy 153 116.1)
        (xy 153 121.2)
        (xy 151.1 123.1)
        (xy 144.5 123.1)
        (xy 143.3 121.9)
        (xy 143.3 116)
        (xy 145.8 113.5)
        (xy 150.4 113.5)
      )
    )
  )
  (zone (net 15) (net_name "PS_3V3") (layer "In6.Cu") (hatch edge 0.508)
    (connect_pads (clearance 0.127))
    (min_thickness 0.1) (filled_areas_thickness no)
    (fill yes (thermal_gap 0.254) (thermal_bridge_width 0.254) (smoothing fillet) (radius 0.127))
    (polygon
      (pts
        (xy 120.45 123.9)
        (xy 119.75 124.6)
        (xy 116.2 124.6)
        (xy 115.75 124.15)
        (xy 108.95 124.15)
        (xy 106.7 121.9)
        (xy 106.7 117.35)
        (xy 120.45 117.35)
      )
    )
  )
  (zone (net 17) (net_name "PS_1V8") (layer "In6.Cu") (hatch edge 0.508)
    (connect_pads (clearance 0.127))
    (min_thickness 0.1) (filled_areas_thickness no)
    (fill yes (thermal_gap 0.254) (thermal_bridge_width 0.254) (smoothing fillet) (radius 0.127))
    (polygon
      (pts
        (xy 120.575 96.425)
        (xy 121.625 96.425)
        (xy 122.5 97.3)
        (xy 126.78 97.3)
        (xy 128.11 95.975)
        (xy 129.135 95.975)
        (xy 129.135 97.325)
        (xy 129.135 99.2)
        (xy 127.195 99.205)
        (xy 126.645 98.655)
        (xy 124.725 98.65)
        (xy 124.175 99.2)
        (xy 123.725 99.2)
        (xy 123.275 98.75)
        (xy 122.65 98.75)
        (xy 122 99.4)
        (xy 122 101.49)
        (xy 120.83 101.49)
        (xy 120.73 101.59)
        (xy 120.35 101.59)
        (xy 120.35 97.8)
        (xy 119.52 96.97)
        (xy 117.33 96.97)
        (xy 117.05 96.69)
        (xy 116.41 96.69)
        (xy 115.8 97.3)
        (xy 113.95 97.3)
        (xy 111.05 94.4)
        (xy 99.1 94.4)
        (xy 97.6 92.8)
        (xy 96.6 91.8)
        (xy 96.6 88.5)
        (xy 95 86.9)
        (xy 95 85.9)
        (xy 98.3 85.9)
        (xy 98.3 86.3)
        (xy 103.1 91.1)
        (xy 109.6 91.1)
        (xy 114 95.55)
        (xy 119.15 95.55)
        (xy 119.65 96.05)
        (xy 120.2 96.05)
      )
    )
  )
  (zone (net 18) (net_name "PS_1V2") (layer "In6.Cu") (hatch edge 0.508)
    (priority 2)
    (connect_pads (clearance 0.1))
    (min_thickness 0.1) (filled_areas_thickness no)
    (fill yes (thermal_gap 0.254) (thermal_bridge_width 0.254) (smoothing fillet) (radius 0.127))
    (polygon
      (pts
        (xy 131 78.25)
        (xy 132.02 79.26)
        (xy 131 80.28)
        (xy 131 82)
        (xy 131 88.35)
        (xy 131.5 88.85)
        (xy 131.5 90.9)
        (xy 131.075 91.325)
        (xy 131.075 94.825)
        (xy 131.5 95.25)
        (xy 131.5 97.17)
        (xy 131.32 97.35)
        (xy 130.05 97.35)
        (xy 130.05 95.1)
        (xy 126.7 91.7)
        (xy 117.65 91.725)
        (xy 117.65 90.55)
        (xy 119.95 90.55)
        (xy 120.9 89.6)
        (xy 120.9 87.15)
        (xy 115.75 87.15)
        (xy 115.75 83.7)
        (xy 114.7 82.65)
        (xy 114.7 78.25)
        (xy 129.84 78.25)
      )
    )
  )
  (zone (net 19) (net_name "PS_1V0") (layer "In6.Cu") (hatch edge 0.508)
    (connect_pads yes (clearance 0.1))
    (min_thickness 0.254) (filled_areas_thickness no)
    (fill yes (thermal_gap 0.508) (thermal_bridge_width 0.508) (smoothing fillet) (radius 0.127))
    (polygon
      (pts
        (xy 144.9 90.5)
        (xy 144.9 85.8)
        (xy 146.3 84.4)
        (xy 152.6 84.4)
        (xy 153.3 85.1)
        (xy 153.3 92.3)
        (xy 151.9 93.7)
        (xy 146 93.7)
        (xy 143.2 96.5)
        (xy 138.55 96.5)
        (xy 137.75 97.3)
        (xy 134.6 97.3)
        (xy 134.6 94.3)
        (xy 136.9 94.3)
        (xy 136.9 91.7)
        (xy 143.7 91.7)
      )
    )
  )
  (zone (net 14) (net_name "/Power Supply/DC/DC conventers/DC_MAIN_BUS") (layer "In6.Cu") (hatch edge 0.508)
    (priority 1)
    (connect_pads yes (clearance 0.2))
    (min_thickness 0.1) (filled_areas_thickness no)
    (fill yes (thermal_gap 0.508) (thermal_bridge_width 0.508) (smoothing fillet) (radius 0.127))
    (polygon
      (pts
        (xy 192 122.9)
        (xy 183.185 122.9)
        (xy 183.16 100.025)
        (xy 189.749196 93.450805)
        (xy 189.73 84.9)
        (xy 181.25 76.5)
        (xy 181.25 70.33)
        (xy 183.8 67.78)
        (xy 183.8 58.7)
        (xy 182.3 57.2)
        (xy 156.9 57.2)
        (xy 155.9 58.2)
        (xy 155.9 64.4)
        (xy 150.75 69.55)
        (xy 146.725 69.55)
        (xy 146.35 69.175)
        (xy 145.6 69.175)
        (xy 145.6 74.7)
        (xy 141.3 79)
        (xy 141.290557 85.2)
        (xy 137.590557 88.901723)
        (xy 137.590557 90.251723)
        (xy 135.2 90.25)
        (xy 135.205625 81.994375)
        (xy 143.974375 73.225625)
        (xy 143.98125 65.71875)
        (xy 144.875 64.825014)
        (xy 146.834459 64.824986)
        (xy 146.825 61.765625)
        (xy 148.299823 60.284375)
        (xy 148.300177 57.925)
        (xy 146.856907 56.475)
        (xy 146.86 52.025)
        (xy 155.1 52)
        (xy 192.2 52)
      )
    )
  )
  (zone (net 1) (net_name "GND") (layer "In6.Cu") (hatch edge 0.508)
    (connect_pads yes (clearance 0.131))
    (min_thickness 0.1) (filled_areas_thickness no)
    (fill yes (thermal_gap 0.254) (thermal_bridge_width 0.254) (smoothing fillet) (radius 0.127))
    (polygon
      (pts
        (xy 130.7 66.500341)
        (xy 134.525 66.500341)
        (xy 134.525 70.46)
        (xy 136.45 72.37)
        (xy 136.45 75.89)
        (xy 133.88 78.46)
        (xy 132.85 78.46)
        (xy 132.16 79.15)
        (xy 131.030043 78.021197)
        (xy 126.775 78.0375)
        (xy 126.775 77.8)
        (xy 127.775 76.8)
        (xy 127.775 75.125)
        (xy 127.28 74.63233)
        (xy 127.28 74.207671)
        (xy 125.1 72.025341)
        (xy 125.075 72.025341)
        (xy 125.075 66.500341)
        (xy 128.525 66.500341)
      )
    )
  )
  (zone (net 1) (net_name "GND") (layer "In6.Cu") (hatch edge 0.508)
    (connect_pads (clearance 0.131))
    (min_thickness 0.254) (filled_areas_thickness no)
    (fill yes (thermal_gap 0.508) (thermal_bridge_width 0.508) (smoothing fillet) (radius 0.2))
    (polygon
      (pts
        (xy 137.51 125.995)
        (xy 130.4 125.995)
        (xy 130.4 119.475)
        (xy 131.375 119.475)
        (xy 132.525 118.325)
        (xy 133.37 118.33)
        (xy 133.376646 116.969536)
        (xy 137.51 116.995)
      )
    )
  )
  (zone (net 0) (net_name "") (layer "In6.Cu") (hatch edge 0.508)
    (connect_pads (clearance 0))
    (min_thickness 0.254) (filled_areas_thickness no)
    (keepout (tracks allowed) (vias allowed) (pads allowed) (copperpour not_allowed) (footprints allowed))
    (fill (thermal_gap 0.508) (thermal_bridge_width 0.508))
    (polygon
      (pts
        (xy 92.825 77.6)
        (xy 91.725 77.6)
        (xy 91.725 76.1)
        (xy 92.825 76.1)
      )
    )
  )
  (zone (net 0) (net_name "") (layer "In6.Cu") (hatch edge 0.508)
    (connect_pads (clearance 0))
    (min_thickness 0.1) (filled_areas_thickness no)
    (keepout (tracks allowed) (vias allowed) (pads allowed) (copperpour not_allowed) (footprints allowed))
    (fill (thermal_gap 0.254) (thermal_bridge_width 0.254))
    (polygon
      (pts
        (xy 131.375 75.975)
        (xy 129.625 75.975)
        (xy 129.625 74.225)
        (xy 131.375 74.225)
      )
    )
  )
  (zone (net 0) (net_name "") (layer "In6.Cu") (hatch edge 0.508)
    (connect_pads yes (clearance 0))
    (min_thickness 0.1) (filled_areas_thickness no)
    (keepout (tracks not_allowed) (vias not_allowed) (pads allowed) (copperpour not_allowed) (footprints allowed))
    (fill (thermal_gap 0.254) (thermal_bridge_width 0.254))
    (polygon
      (pts
        (xy 130.875 73.975)
        (xy 128.625 73.975)
        (xy 128.625 72.525)
        (xy 130.875 72.525)
      )
    )
  )
  (zone (net 1) (net_name "GND") (layer "In6.Cu") (hatch edge 0.508)
    (connect_pads (clearance 0.131))
    (min_thickness 0.254) (filled_areas_thickness no)
    (fill yes (thermal_gap 0.508) (thermal_bridge_width 0.508) (smoothing fillet) (radius 0.2))
    (polygon
      (pts
        (xy 94.16 81.29)
        (xy 91.46 83.99)
        (xy 90.17 83.99)
        (xy 90.175 74.775)
        (xy 94.15 74.775)
      )
    )
  )
  (zone (net 1) (net_name "GND") (layer "In6.Cu") (hatch edge 0.508)
    (priority 9)
    (connect_pads yes (clearance 0.131))
    (min_thickness 0.2) (filled_areas_thickness no)
    (fill yes (thermal_gap 0.254) (thermal_bridge_width 0.254) (smoothing fillet) (radius 0.127))
    (polygon
      (pts
        (xy 83.4 114.3)
        (xy 80.45 114.3)
        (xy 80.45 113.55)
        (xy 79.77 112.87)
        (xy 78.92 112.87)
        (xy 78.92 107.1)
        (xy 77.31 107.1)
        (xy 77.31 102.1)
        (xy 77.72 101.69)
        (xy 77.72 98.6)
        (xy 83.4 98.6)
      )
    )
  )
  (zone (net 0) (net_name "") (layer "In6.Cu") (hatch edge 0.508)
    (connect_pads (clearance 0))
    (min_thickness 0.254) (filled_areas_thickness no)
    (keepout (tracks allowed) (vias allowed) (pads allowed) (copperpour not_allowed) (footprints allowed))
    (fill (thermal_gap 0.508) (thermal_bridge_width 0.508))
    (polygon
      (pts
        (xy 128.07 83.96)
        (xy 128.07 86.02)
        (xy 129.58 87.54)
        (xy 131.19 87.54)
        (xy 131.2 89)
        (xy 128.49 89)
        (xy 126.44 86.97)
        (xy 126.45 84.7)
        (xy 126.45 83.35)
        (xy 127.45 83.35)
      )
    )
  )
  (zone (net 0) (net_name "") (layer "In6.Cu") (hatch edge 0.508)
    (connect_pads (clearance 0))
    (min_thickness 0.254) (filled_areas_thickness no)
    (keepout (tracks allowed) (vias allowed) (pads allowed) (copperpour not_allowed) (footprints allowed))
    (fill (thermal_gap 0.508) (thermal_bridge_width 0.508))
    (polygon
      (pts
        (xy 135.01 123.315)
        (xy 133.435 123.315)
        (xy 133.435 121.715)
        (xy 135.01 121.715)
      )
    )
  )
  (zone (net 365) (net_name "/Power Supply/DC/DC conventers/SW_USB_5V") (layer "B.Cu") (hatch edge 0.508)
    (priority 8)
    (connect_pads yes (clearance 0.1))
    (min_thickness 0.1) (filled_areas_thickness no)
    (fill yes (thermal_gap 0.508) (thermal_bridge_width 0.508) (smoothing fillet) (radius 0.2))
    (polygon
      (pts
        (xy 153.725 73.9)
        (xy 149.775 73.9)
        (xy 149.625 73.75)
        (xy 148.025 73.75)
        (xy 148.025 73.3)
        (xy 149.625 73.3)
        (xy 149.825 73.1)
        (xy 149.825 72.2)
        (xy 150.715 72.2)
        (xy 150.715 71.04)
        (xy 151.525 71.04)
        (xy 151.525 72.2)
        (xy 153.725 72.2)
      )
    )
  )
  (zone (net 252) (net_name "Net-(U47-BOOT)") (layer "B.Cu") (hatch edge 0.508)
    (priority 8)
    (connect_pads yes (clearance 0.1))
    (min_thickness 0.1) (filled_areas_thickness no)
    (fill yes (thermal_gap 0.508) (thermal_bridge_width 0.508) (smoothing fillet) (radius 0.2))
    (polygon
      (pts
        (xy 150.525 72.1)
        (xy 149.725 72.1)
        (xy 149.725 73)
        (xy 149.525 73.2)
        (xy 148.525 73.2)
        (xy 148.525 72.2)
        (xy 149.025 72.2)
        (xy 149.025 71.03)
        (xy 150.525 71.03)
      )
    )
  )
  (zone (net 14) (net_name "/Power Supply/DC/DC conventers/DC_MAIN_BUS") (layer "B.Cu") (hatch edge 0.508)
    (priority 8)
    (connect_pads yes (clearance 0.1))
    (min_thickness 0.1) (filled_areas_thickness no)
    (fill yes (thermal_gap 0.508) (thermal_bridge_width 0.508) (smoothing fillet) (radius 0.2))
    (polygon
      (pts
        (xy 150.625 69.4)
        (xy 148.425 71.6)
        (xy 148.425 73.2)
        (xy 147.725 73.2)
        (xy 147.725 72.2)
        (xy 147.325 71.8)
        (xy 147.325 67.9)
        (xy 150.625 67.9)
      )
    )
  )
  (zone (net 772) (net_name "/Power Supply/DC/DC conventers/USB_5V_OUT") (layer "B.Cu") (hatch edge 0.508)
    (priority 8)
    (connect_pads yes (clearance 0.1))
    (min_thickness 0.1) (filled_areas_thickness no)
    (fill yes (thermal_gap 0.508) (thermal_bridge_width 0.508) (smoothing fillet) (radius 0.2))
    (polygon
      (pts
        (xy 153.725 76.5)
        (xy 153.425 76.8)
        (xy 150.88 76.8)
        (xy 150.88 78.35)
        (xy 150.86 78.5)
        (xy 150.86 79.48)
        (xy 150.26 79.48)
        (xy 150.26 78.8)
        (xy 149.45 77.85)
        (xy 148.75 77.85)
        (xy 148.75 75.6)
        (xy 149.45 74.9)
        (xy 153.725 74.9)
      )
    )
  )
  (zone (net 254) (net_name "Net-(U47-FB)") (layer "B.Cu") (hatch edge 0.508)
    (priority 8)
    (connect_pads yes (clearance 0.1))
    (min_thickness 0.1) (filled_areas_thickness no)
    (fill yes (thermal_gap 0.508) (thermal_bridge_width 0.508) (smoothing fillet) (radius 0.2))
    (polygon
      (pts
        (xy 147.725 75.2)
        (xy 147.4 75.2)
        (xy 147.025 75.575)
        (xy 147.025 75.9)
        (xy 144.125 75.9)
        (xy 144.125 75.1)
        (xy 147.025 75.1)
        (xy 147.325 74.8)
        (xy 147.325 74)
        (xy 147.725 74)
      )
    )
  )
  (zone (net 248) (net_name "Net-(U47-PVCC)") (layer "B.Cu") (hatch edge 0.508)
    (priority 8)
    (connect_pads yes (clearance 0.1))
    (min_thickness 0.1) (filled_areas_thickness no)
    (fill yes (thermal_gap 0.508) (thermal_bridge_width 0.508) (smoothing fillet) (radius 0.2))
    (polygon
      (pts
        (xy 146.8875 73.2)
        (xy 147.6 73.2)
        (xy 147.6 73.475)
        (xy 144.825 73.475)
        (xy 144.825 72.325)
        (xy 145.975 72.325)
      )
    )
  )
  (zone (net 250) (net_name "Net-(U47-SS)") (layer "B.Cu") (hatch edge 0.508)
    (priority 8)
    (connect_pads yes (clearance 0.1))
    (min_thickness 0.1) (filled_areas_thickness no)
    (fill yes (thermal_gap 0.508) (thermal_bridge_width 0.508) (smoothing fillet) (radius 0.2))
    (polygon
      (pts
        (xy 146.8875 73.85)
        (xy 147.6 73.85)
        (xy 147.6 73.62)
        (xy 144.825 73.62)
        (xy 144.825 74.725)
        (xy 146.025 74.725)
      )
    )
  )
  (zone (net 0) (net_name "") (layer "B.Cu") (hatch edge 0.508)
    (connect_pads yes (clearance 0))
    (min_thickness 0.2) (filled_areas_thickness no)
    (keepout (tracks allowed) (vias allowed) (pads allowed) (copperpour not_allowed) (footprints allowed))
    (fill (thermal_gap 0.254) (thermal_bridge_width 0.254))
    (polygon
      (pts
        (xy 128.485 70.2)
        (xy 129.715 71.43)
        (xy 130.635 70.51)
        (xy 130.635 66.55)
        (xy 134.485 66.55)
        (xy 134.48 70.4)
        (xy 136.44 72.36)
        (xy 136.45 75.9)
        (xy 135.805 76.54)
        (xy 134.175 76.54)
        (xy 133.34 77.38)
        (xy 129.22 77.38)
        (xy 128.98 77.62)
        (xy 127.77 77.62)
        (xy 127.77 76.81)
        (xy 127.77 75.14)
        (xy 127.77 73.55)
        (xy 127.06 72.84)
        (xy 126.43 72.84)
        (xy 125.015 71.425)
        (xy 125.015 66.55)
        (xy 128.485 66.55)
      )
    )
  )
  (zone (net 306) (net_name "USB_5V") (layer "B.Cu") (hatch edge 0.508)
    (priority 1)
    (connect_pads yes (clearance 0.254))
    (min_thickness 0.254) (filled_areas_thickness no)
    (fill yes (thermal_gap 0.508) (thermal_bridge_width 0.508) (smoothing fillet) (radius 0.127))
    (polygon
      (pts
        (xy 103.45 86.3)
        (xy 103.45 87.85)
        (xy 101.1 87.85)
        (xy 101.1 85.95)
        (xy 103.1 85.95)
      )
    )
  )
  (zone (net 1) (net_name "GND") (layer "B.Cu") (hatch edge 0.508)
    (connect_pads yes (clearance 0.254))
    (min_thickness 0.254) (filled_areas_thickness no)
    (fill yes (thermal_gap 0.508) (thermal_bridge_width 0.508) (smoothing fillet) (radius 0.127))
    (polygon
      (pts
        (xy 133.9015 94.302)
        (xy 135.5165 94.3)
        (xy 135.515 92.698)
        (xy 136.4 92.7)
        (xy 136.4 91.75)
        (xy 134.85 91.75)
        (xy 134.85 90.8)
        (xy 133.9 90.799999)
      )
    )
  )
  (zone (net 9) (net_name "/Power Supply/PoE/VDD_POE_IN") (layer "B.Cu") (hatch edge 0.508)
    (connect_pads yes (clearance 0.254))
    (min_thickness 0.1) (filled_areas_thickness no)
    (fill yes (thermal_gap 0.254) (thermal_bridge_width 0.254) (smoothing fillet) (radius 0.5))
    (polygon
      (pts
        (xy 185.575 86.75)
        (xy 183.675 88.65)
        (xy 176.875 88.65)
        (xy 176.8625 95.95)
        (xy 167.68 95.97)
        (xy 167.685 92.05)
        (xy 162.575 86.95)
        (xy 162.575 84.275)
        (xy 185.575 84.3)
      )
    )
  )
  (zone (net 11) (net_name "GNDD") (layer "B.Cu") (hatch edge 0.508)
    (connect_pads yes (clearance 0.254))
    (min_thickness 0.1) (filled_areas_thickness no)
    (fill yes (thermal_gap 0.254) (thermal_bridge_width 0.254) (smoothing fillet) (radius 0.5))
    (polygon
      (pts
        (xy 188.26 83.475)
        (xy 187.275 84.45)
        (xy 187.275 84.75)
        (xy 187.275 89.15)
        (xy 186.075 89.15)
        (xy 186.075 92.075)
        (xy 186.08 95.95)
        (xy 177.675001 95.945275)
        (xy 177.675 89.25)
        (xy 183.875 89.25)
        (xy 186.05 87.075)
        (xy 186.05 82.9)
        (xy 184.975 81.85)
        (xy 162.475 81.85)
        (xy 162.475 79.05)
        (xy 163.875 77.65)
        (xy 188.26 77.65)
      )
    )
  )
  (zone (net 14) (net_name "/Power Supply/DC/DC conventers/DC_MAIN_BUS") (layer "B.Cu") (hatch edge 0.508)
    (priority 2)
    (connect_pads yes (clearance 0.254))
    (min_thickness 0.254) (filled_areas_thickness no)
    (fill yes (thermal_gap 0.508) (thermal_bridge_width 0.508) (smoothing fillet) (radius 0.127))
    (polygon
      (pts
        (xy 190.275 68.15)
        (xy 187.475 68.15)
        (xy 186.575 67.25)
        (xy 186.575 62.65)
        (xy 190.275 62.65)
      )
    )
  )
  (zone (net 22) (net_name "/Power Supply/DC Input/DC_IN") (layer "B.Cu") (hatch edge 0.508)
    (priority 1)
    (connect_pads yes (clearance 0.254))
    (min_thickness 0.254) (filled_areas_thickness no)
    (fill yes (thermal_gap 0.508) (thermal_bridge_width 0.508) (smoothing fillet) (radius 0.127))
    (polygon
      (pts
        (xy 184.575 67.25)
        (xy 177.275 67.25)
        (xy 177.275 65.05)
        (xy 179.575 62.75)
        (xy 184.575 62.75)
      )
    )
  )
  (zone (net 16) (net_name "PS_2V5") (layer "B.Cu") (hatch edge 0.508)
    (priority 1)
    (connect_pads yes (clearance 0.1))
    (min_thickness 0.2) (filled_areas_thickness no)
    (fill yes (thermal_gap 0.508) (thermal_bridge_width 0.508) (smoothing fillet) (radius 0.127))
    (polygon
      (pts
        (xy 147.275 82.075)
        (xy 144.35 82.075)
        (xy 144.35 80.625)
        (xy 147.275 80.625)
      )
    )
  )
  (zone (net 64) (net_name "/USB/USB1_VBUS") (layer "B.Cu") (hatch edge 0.508)
    (priority 1)
    (connect_pads yes (clearance 0.2))
    (min_thickness 0.1) (filled_areas_thickness no)
    (fill yes (thermal_gap 0.508) (thermal_bridge_width 0.508) (smoothing fillet) (radius 0.127))
    (polygon
      (pts
        (xy 134.1 66.4)
        (xy 132.8 66.4)
        (xy 131 64.6)
        (xy 131 63.85)
        (xy 134.1 63.85)
      )
    )
  )
  (zone (net 86) (net_name "/USB/USB3_VBUS") (layer "B.Cu") (hatch edge 0.508)
    (priority 1)
    (connect_pads yes (clearance 0.2))
    (min_thickness 0.1) (filled_areas_thickness no)
    (fill yes (thermal_gap 0.508) (thermal_bridge_width 0.508) (smoothing fillet) (radius 0.127))
    (polygon
      (pts
        (xy 114.7 66.38)
        (xy 113.4 66.38)
        (xy 111.6 64.59)
        (xy 111.6 63.9)
        (xy 114.7 63.9)
      )
    )
  )
  (zone (net 1) (net_name "GND") (layer "B.Cu") (hatch edge 0.508)
    (priority 4)
    (connect_pads yes (clearance 0.2))
    (min_thickness 0.1) (filled_areas_thickness no)
    (fill yes (thermal_gap 0.508) (thermal_bridge_width 0.508) (smoothing fillet) (radius 0.127))
    (polygon
      (pts
        (xy 139.35 67.95)
        (xy 137.85 67.95)
        (xy 137.85 65.15)
        (xy 139.35 65.15)
      )
    )
  )
  (zone (net 1) (net_name "GND") (layer "B.Cu") (hatch edge 0.508)
    (priority 4)
    (connect_pads yes (clearance 0.3))
    (min_thickness 0.1) (filled_areas_thickness no)
    (fill yes (thermal_gap 0.508) (thermal_bridge_width 0.508) (smoothing fillet) (radius 0.127))
    (polygon
      (pts
        (xy 119.9 68.05)
        (xy 118.4 68.05)
        (xy 118.4 65.25)
        (xy 119.9 65.25)
      )
    )
  )
  (zone (net 85) (net_name "/USB/USB2_VBUS") (layer "B.Cu") (hatch edge 0.508)
    (priority 3)
    (connect_pads yes (clearance 0.2))
    (min_thickness 0.1) (filled_areas_thickness no)
    (fill yes (thermal_gap 0.508) (thermal_bridge_width 0.508) (smoothing fillet) (radius 0.127))
    (polygon
      (pts
        (xy 137.65 68)
        (xy 136.1 68)
        (xy 134.4 69.7)
        (xy 133.2 69.7)
        (xy 132.7 69.2)
        (xy 132.7 68.7)
        (xy 133.3 68.1)
        (xy 134.7 68.1)
        (xy 134.7 65.2)
        (xy 137.65 65.2)
      )
    )
  )
  (zone (net 87) (net_name "/USB/USB4_VBUS") (layer "B.Cu") (hatch edge 0.508)
    (priority 2)
    (connect_pads yes (clearance 0.2))
    (min_thickness 0.1) (filled_areas_thickness no)
    (fill yes (thermal_gap 0.508) (thermal_bridge_width 0.508) (smoothing fillet) (radius 0.127))
    (polygon
      (pts
        (xy 118.2 68.1)
        (xy 116.9 68.1)
        (xy 115.2 69.8)
        (xy 114 69.8)
        (xy 113.5 69.3)
        (xy 113.5 68.8)
        (xy 114.1 68.2)
        (xy 115.5 68.2)
        (xy 115.5 65.2)
        (xy 118.2 65.2)
      )
    )
  )
  (zone (net 318) (net_name "SH_DOWN") (layer "B.Cu") (hatch edge 0.508)
    (priority 1)
    (connect_pads yes (clearance 0.6))
    (min_thickness 0.5) (filled_areas_thickness no)
    (fill yes (thermal_gap 0.508) (thermal_bridge_width 0.508) (smoothing fillet) (radius 0.127))
    (polygon
      (pts
        (xy 150.5 152)
        (xy 139.4 152)
        (xy 139.4 143.7)
        (xy 140.7 143.7)
        (xy 140.7 146.2)
        (xy 148 146.2)
        (xy 148 143.7)
        (xy 150.5 143.7)
      )
    )
  )
  (zone (net 319) (net_name "SH_UP") (layer "B.Cu") (hatch edge 0.508)
    (priority 1)
    (connect_pads yes (clearance 0.6))
    (min_thickness 0.5) (filled_areas_thickness no)
    (fill yes (thermal_gap 0.508) (thermal_bridge_width 0.508) (smoothing fillet) (radius 0.127))
    (polygon
      (pts
        (xy 173.3 52)
        (xy 173.3 67.2)
        (xy 170.7 67.2)
        (xy 170.7 61.1)
        (xy 157.3 61.1)
        (xy 157.25 67.1)
        (xy 154.95 67.1)
        (xy 155 62.4)
        (xy 152.5 59.9)
        (xy 150.3 59.9)
        (xy 150.3 57.1)
        (xy 149.8 56.6)
        (xy 143.7 56.6)
        (xy 143.1 57.2)
        (xy 143.1 59.7)
        (xy 139.3 63.5)
        (xy 139.3 70.8)
        (xy 137.8 70.8)
        (xy 135 70.8)
        (xy 135 61.775)
        (xy 124.6 61.775)
        (xy 124.6 70.95)
        (xy 115.5 70.96)
        (xy 115.5 61.8)
        (xy 105.5 61.8)
        (xy 105.5 70.9)
        (xy 98.7 70.9)
        (xy 98.7 66.4)
        (xy 96 63.7)
        (xy 84.8 63.7)
        (xy 83.5 65)
        (xy 80.9 65)
        (xy 80.9 52.1)
        (xy 105.5 52.1)
      )
    )
  )
  (zone (net 15) (net_name "PS_3V3") (layer "B.Cu") (hatch edge 0.508)
    (priority 1)
    (connect_pads yes (clearance 0.1))
    (min_thickness 0.254) (filled_areas_thickness no)
    (fill yes (thermal_gap 0.508) (thermal_bridge_width 0.508) (smoothing fillet) (radius 0.127))
    (polygon
      (pts
        (xy 127.1 144.7)
        (xy 127.1 145.5)
        (xy 125 145.5)
        (xy 124.2 144.7)
        (xy 124.2 144)
        (xy 126.4 144)
      )
    )
  )
  (zone (net 8) (net_name "SOM_5V0") (layer "B.Cu") (hatch edge 0.508)
    (priority 1)
    (connect_pads yes (clearance 0.127))
    (min_thickness 0.1) (filled_areas_thickness no)
    (fill yes (thermal_gap 0.254) (thermal_bridge_width 0.254) (smoothing fillet) (radius 0.127))
    (polygon
      (pts
        (xy 95.5 97.65)
        (xy 95.5 99.5)
        (xy 93.34 99.5)
        (xy 92.29 98.455)
        (xy 92.29 95.485)
        (xy 93.57 94.2)
        (xy 96.2 94.2)
        (xy 96.2 97.65)
      )
    )
  )
  (zone (net 323) (net_name "Net-(U53-BST)") (layer "B.Cu") (hatch edge 0.508)
    (priority 4)
    (connect_pads yes (clearance 0.254))
    (min_thickness 0.254) (filled_areas_thickness no)
    (fill yes (thermal_gap 0.508) (thermal_bridge_width 0.508) (smoothing fillet) (radius 0.127))
    (polygon
      (pts
        (xy 137.6 92.7)
        (xy 137.85 92.95)
        (xy 137.85 93.55)
        (xy 139.000001 93.55)
        (xy 139 91.8)
        (xy 137.6 91.8)
      )
    )
  )
  (zone (net 256) (net_name "/Power Supply/DC/DC conventers/SW_PS_1V0") (layer "B.Cu") (hatch edge 0.508)
    (priority 3)
    (connect_pads yes (clearance 0.254))
    (min_thickness 0.254) (filled_areas_thickness no)
    (fill yes (thermal_gap 0.508) (thermal_bridge_width 0.508) (smoothing fillet) (radius 0.127))
    (polygon
      (pts
        (xy 138.77325 94.652)
        (xy 138.77 93.637)
        (xy 137.848794 93.634021)
        (xy 137.85 92.95)
        (xy 137.6 92.7)
        (xy 137.6 90.85)
        (xy 137.3 90.85)
        (xy 135 90.85)
        (xy 135 91.7)
        (xy 136.5 91.7)
        (xy 136.502 92.76)
        (xy 135.589 92.754)
        (xy 135.583001 94.65075)
      )
    )
  )
  (zone (net 14) (net_name "/Power Supply/DC/DC conventers/DC_MAIN_BUS") (layer "B.Cu") (hatch edge 0.508)
    (priority 1)
    (connect_pads yes (clearance 0.254))
    (min_thickness 0.254) (filled_areas_thickness no)
    (fill yes (thermal_gap 0.508) (thermal_bridge_width 0.508) (smoothing fillet) (radius 0.127))
    (polygon
      (pts
        (xy 133.9 90.7)
        (xy 137.6 90.7)
        (xy 137.6 88.95)
        (xy 133.9 88.95)
      )
    )
  )
  (zone (net 258) (net_name "Net-(U50-BST)") (layer "B.Cu") (hatch edge 0.508)
    (priority 4)
    (connect_pads yes (clearance 0.254))
    (min_thickness 0.254) (filled_areas_thickness no)
    (fill yes (thermal_gap 0.508) (thermal_bridge_width 0.508) (smoothing fillet) (radius 0.127))
    (polygon
      (pts
        (xy 141.1 82.4)
        (xy 141.35 82.65)
        (xy 141.35 83.45)
        (xy 142.5 83.45)
        (xy 142.5 81.5)
        (xy 141.1 81.5)
      )
    )
  )
  (zone (net 692) (net_name "Net-(U53-FB)") (layer "B.Cu") (hatch edge 0.508)
    (priority 2)
    (connect_pads yes (clearance 0.254))
    (min_thickness 0.254) (filled_areas_thickness no)
    (fill yes (thermal_gap 0.508) (thermal_bridge_width 0.508) (smoothing fillet) (radius 0.127))
    (polygon
      (pts
        (xy 140.049998 88.9)
        (xy 139.3 88.9)
        (xy 139.1 89.099999)
        (xy 139.100001 89.650001)
        (xy 138.950001 89.800001)
        (xy 137.649999 89.799999)
        (xy 137.65 90.65)
        (xy 137.8 90.8)
        (xy 140.049999 90.799999)
      )
    )
  )
  (zone (net 14) (net_name "/Power Supply/DC/DC conventers/DC_MAIN_BUS") (layer "B.Cu") (hatch edge 0.508)
    (priority 1)
    (connect_pads yes (clearance 0.254))
    (min_thickness 0.254) (filled_areas_thickness no)
    (fill yes (thermal_gap 0.508) (thermal_bridge_width 0.508) (smoothing fillet) (radius 0.127))
    (polygon
      (pts
        (xy 137.4 80.4)
        (xy 141.1 80.4)
        (xy 141.1 78.649999)
        (xy 138.5 78.649999)
        (xy 137.41 79.75)
      )
    )
  )
  (zone (net 766) (net_name "/Power Supply/DC/DC conventers/PS_2V5_OUT") (layer "B.Cu") (hatch edge 0.508)
    (priority 5)
    (connect_pads yes (clearance 0.254))
    (min_thickness 0.254) (filled_areas_thickness no)
    (fill yes (thermal_gap 0.508) (thermal_bridge_width 0.508) (smoothing fillet) (radius 0.127))
    (polygon
      (pts
        (xy 135.1788 86)
        (xy 135.95 86)
        (xy 135.95 85.2)
        (xy 136.3 84.85)
        (xy 137.4 84.85)
        (xy 137.7 85.15)
        (xy 141.35 85.15)
        (xy 141.35 83.83)
        (xy 140.369998 83.82927)
        (xy 140.370027 84.59341)
        (xy 138.27 84.6)
        (xy 138.27 83.07)
        (xy 136.5428 83.07)
        (xy 136.55 83.69)
        (xy 135.1788 83.69)
      )
    )
  )
  (zone (net 310) (net_name "/Power Supply/DC/DC conventers/SW_PS_2V5") (layer "B.Cu") (hatch edge 0.508)
    (priority 3)
    (connect_pads yes (clearance 0.254))
    (min_thickness 0.254) (filled_areas_thickness no)
    (fill yes (thermal_gap 0.508) (thermal_bridge_width 0.508) (smoothing fillet) (radius 0.127))
    (polygon
      (pts
        (xy 140.35 84.52)
        (xy 140.35 83.66)
        (xy 141.35 83.66)
        (xy 141.35 82.65)
        (xy 141.1 82.4)
        (xy 141.1 80.55)
        (xy 140.8 80.55)
        (xy 138.5 80.55)
        (xy 138.5 81.47)
        (xy 139.91 81.47)
        (xy 139.91 82.48)
        (xy 138.5 82.48)
        (xy 138.5 84.52)
      )
    )
  )
  (zone (net 689) (net_name "Net-(U50-FB)") (layer "B.Cu") (hatch edge 0.508)
    (priority 2)
    (connect_pads yes (clearance 0.254))
    (min_thickness 0.254) (filled_areas_thickness no)
    (fill yes (thermal_gap 0.508) (thermal_bridge_width 0.508) (smoothing fillet) (radius 0.127))
    (polygon
      (pts
        (xy 143.5 78.6)
        (xy 142.750001 78.6)
        (xy 142.550001 78.799999)
        (xy 142.55 79.35)
        (xy 142.4 79.5)
        (xy 141.1 79.499998)
        (xy 141.1 80.35)
        (xy 141.25 80.5)
        (xy 143.499999 80.499999)
      )
    )
  )
  (zone (net 1) (net_name "GND") (layer "B.Cu") (hatch edge 0.508)
    (connect_pads yes (clearance 0.254))
    (min_thickness 0.2) (filled_areas_thickness no)
    (fill yes (thermal_gap 0.254) (thermal_bridge_width 0.254) (smoothing fillet) (radius 0.127))
    (polygon
      (pts
        (xy 192 69.693291)
        (xy 184.575 69.668291)
        (xy 184.575 67.168291)
        (xy 173.3 67.193291)
        (xy 173.3 64.593291)
        (xy 155 64.593291)
        (xy 155 68.293291)
        (xy 168.8 68.293291)
        (xy 170.5 69.993291)
        (xy 170.5 76.493291)
        (xy 163.7 76.493291)
        (xy 161.6 78.593291)
        (xy 161.61 86.993291)
        (xy 163.91 89.293291)
        (xy 163.9 109.493291)
        (xy 192 109.493291)
        (xy 192 151.993291)
        (xy 74 151.993291)
        (xy 74 51.993291)
        (xy 106.08 51.993291)
        (xy 108.24 51.993291)
        (xy 114.51 51.993291)
        (xy 115.54 51.993291)
        (xy 192 51.993291)
      )
    )
  )
  (zone (net 0) (net_name "") (layer "B.Cu") (hatch edge 0.508)
    (connect_pads yes (clearance 0))
    (min_thickness 0.2) (filled_areas_thickness no)
    (keepout (tracks allowed) (vias allowed) (pads allowed) (copperpour not_allowed) (footprints allowed))
    (fill (thermal_gap 0.254) (thermal_bridge_width 0.254))
    (polygon
      (pts
        (xy 148.4 57.725)
        (xy 148.4 59.025)
        (xy 147.925 59.5)
        (xy 145.325 59.5)
        (xy 144.775 58.95)
        (xy 144.775 57.85)
        (xy 145.3 57.325)
        (xy 148 57.325)
      )
    )
  )
  (zone (net 9) (net_name "/Power Supply/PoE/VDD_POE_IN") (layer "B.Cu") (hatch edge 0.508)
    (connect_pads yes (clearance 0.2))
    (min_thickness 0.254) (filled_areas_thickness no)
    (fill yes (thermal_gap 0.508) (thermal_bridge_width 0.508) (smoothing fillet) (radius 0.127))
    (polygon
      (pts
        (xy 191.9 75.6)
        (xy 184.2 75.6)
        (xy 182.5 77.3)
        (xy 178.2 77.3)
        (xy 178.2 76.05)
        (xy 184.09 70.2)
        (xy 191.9 70.2)
      )
    )
  )
  (zone (net 0) (net_name "") (layer "B.Cu") (hatch edge 0.508)
    (connect_pads yes (clearance 0))
    (min_thickness 0.2) (filled_areas_thickness no)
    (keepout (tracks allowed) (vias allowed) (pads allowed) (copperpour not_allowed) (footprints allowed))
    (fill (thermal_gap 0.254) (thermal_bridge_width 0.254))
    (polygon
      (pts
        (xy 82.84 114.49)
        (xy 80.21 114.49)
        (xy 79.72 114)
        (xy 78.121788 114.000007)
        (xy 78.13 111.75)
        (xy 78.94 110.94)
        (xy 78.95 107.145)
        (xy 78.12 106.32)
        (xy 78.12 99.33)
        (xy 82.84 99.33)
      )
    )
  )
  (zone (net 306) (net_name "USB_5V") (layer "B.Cu") (hatch edge 0.508)
    (priority 1)
    (connect_pads yes (clearance 0.254))
    (min_thickness 0.254) (filled_areas_thickness no)
    (fill yes (thermal_gap 0.508) (thermal_bridge_width 0.508) (smoothing fillet) (radius 0.127))
    (polygon
      (pts
        (xy 149.4 78.5)
        (xy 149.53 78.5)
        (xy 149.53 79.4)
        (xy 146.25 79.4)
        (xy 145.95 79)
        (xy 145.95 78.2)
        (xy 146.1 78.05)
        (xy 148.95 78.05)
      )
    )
  )
  (zone (net 769) (net_name "/Power Supply/DC/DC conventers/PS_1V0_OUT") (layer "B.Cu") (hatch edge 0.508)
    (priority 1)
    (connect_pads yes (clearance 0.131))
    (min_thickness 0.254) (filled_areas_thickness no)
    (fill yes (thermal_gap 0.508) (thermal_bridge_width 0.508) (smoothing fillet) (radius 0.2))
    (polygon
      (pts
        (xy 137.368 96.541)
        (xy 134.432 96.541)
        (xy 134.432 94.781)
        (xy 137.368 94.781)
      )
    )
  )
  (zone (net 0) (net_name "") (layer "B.Cu") (hatch edge 0.508)
    (connect_pads yes (clearance 0))
    (min_thickness 0.2) (filled_areas_thickness no)
    (keepout (tracks allowed) (vias allowed) (pads allowed) (copperpour not_allowed) (footprints allowed))
    (fill (thermal_gap 0.254) (thermal_bridge_width 0.254))
    (polygon
      (pts
        (xy 109.21 70.22)
        (xy 110.44 71.45)
        (xy 111.36 70.53)
        (xy 111.36 66.57)
        (xy 115.21 66.57)
        (xy 115.215 71.105)
        (xy 116.69 72.59)
        (xy 116.69 75.93)
        (xy 116.33 76.29)
        (xy 112.51 76.29)
        (xy 112.51 77.44)
        (xy 109.9 77.44)
        (xy 109.69 77.65)
        (xy 108.33 77.65)
        (xy 108.33 73.28)
        (xy 107.92 72.87)
        (xy 106.51 72.87)
        (xy 105.74 72.1)
        (xy 105.74 66.57)
        (xy 109.21 66.57)
      )
    )
  )
  (zone (net 243) (net_name "Net-(Q6-D)") (layer "B.Cu") (hatch edge 0.508)
    (priority 1)
    (connect_pads yes (clearance 0.2))
    (min_thickness 0.254) (filled_areas_thickness no)
    (fill yes (thermal_gap 0.508) (thermal_bridge_width 0.508))
    (polygon
      (pts
        (xy 108.9 88.9)
        (xy 107.15 88.9)
        (xy 107.15 86.15)
        (xy 108.9 86.15)
      )
    )
  )
  (zone (net 19) (net_name "PS_1V0") (layer "B.Cu") (hatch edge 0.508)
    (priority 1)
    (connect_pads yes (clearance 0.131))
    (min_thickness 0.254) (filled_areas_thickness no)
    (fill yes (thermal_gap 0.508) (thermal_bridge_width 0.508) (smoothing fillet) (radius 0.2))
    (polygon
      (pts
        (xy 137.95 96.9)
        (xy 137.95 97.35)
        (xy 137.8 97.5)
        (xy 136.05 97.5)
        (xy 135.7 97.85)
        (xy 135.5 97.85)
        (xy 135.35 98)
        (xy 134.45 98)
        (xy 134.45 97.3)
        (xy 135.05 97.3)
        (xy 135.65 96.7)
        (xy 137.75 96.7)
      )
    )
  )
  (zone (net 7) (net_name "Net-(D11-Pad1)") (layer "B.Cu") (hatch edge 0.508)
    (priority 1)
    (connect_pads yes (clearance 0.254))
    (min_thickness 0.254) (filled_areas_thickness no)
    (fill yes (thermal_gap 0.508) (thermal_bridge_width 0.508) (smoothing fillet) (radius 0.2))
    (polygon
      (pts
        (xy 188.25 77.3)
        (xy 182.75 77.3)
        (xy 184.3 75.75)
        (xy 188.25 75.75)
      )
    )
  )
  (zone (net 16) (net_name "PS_2V5") (layer "B.Cu") (hatch edge 0.508)
    (priority 1)
    (connect_pads yes (clearance 0.131))
    (min_thickness 0.254) (filled_areas_thickness no)
    (fill yes (thermal_gap 0.508) (thermal_bridge_width 0.508) (smoothing fillet) (radius 0.2))
    (polygon
      (pts
        (xy 137.7 85.6)
        (xy 138.1 85.6)
        (xy 138.3 85.8)
        (xy 138.3 86.8)
        (xy 138.1 87)
        (xy 136.3 87)
        (xy 136.15 86.85)
        (xy 136.15 86.45)
        (xy 136.7 85.9)
        (xy 136.7 85.15)
        (xy 137.25 85.15)
      )
    )
  )
)
